G04 ================== begin FILE IDENTIFICATION RECORD ==================*
G04 Layout Name:  9127_F0T_Expander_BD_F_v02_0110_1240.brd*
G04 Film Name:    in2*
G04 File Format:  Gerber RS274X*
G04 File Origin:  Cadence Allegro 17.2-S081*
G04 Origin Date:  Wed Jan 11 16:06:20 2023*
G04 *
G04 Layer:  VIA CLASS/IN2*
G04 Layer:  PIN/IN2*
G04 Layer:  ETCH/IN2*
G04 Layer:  PIN/SPECIAL_DRILL*
G04 Layer:  DRAWING FORMAT/TITLE_BLOCK_A*
G04 Layer:  MANUFACTURING/PHOTOPLOT_OUTLINE*
G04 Layer:  DRAWING FORMAT/TITLE_BLOCK*
G04 Layer:  DRAWING FORMAT/TITLE_DATA_IN2*
G04 *
G04 Offset:    (0.00 0.00)*
G04 Mirror:    No*
G04 Mode:      Positive*
G04 Rotation:  0*
G04 FullContactRelief:  No*
G04 UndefLineWidth:     6.00*
G04 ================== end FILE IDENTIFICATION RECORD ====================*
%FSLAX25Y25*MOIN*%
%IR0*IPPOS*OFA0.00000B0.00000*MIA0B0*SFA1.00000B1.00000*%
%ADD19O,.137X.062*%
%ADD10C,.02*%
%ADD22C,.03*%
%ADD13O,.137X.064*%
%ADD25C,.061*%
%ADD17C,.016*%
%ADD20C,.0315*%
%ADD14C,.018*%
%ADD18C,.064*%
%ADD24C,.048*%
%ADD15C,.0282*%
%ADD26C,.085*%
%ADD23C,.07051*%
%ADD21C,.0193*%
%ADD16C,.03568*%
%ADD27O,.044X.071*%
%ADD28O,.044X.087*%
%ADD11C,.256*%
%ADD12C,.394*%
%ADD29C,.01*%
%ADD30C,.015*%
%ADD31C,.006*%
%ADD32C,.0061*%
%ADD33C,.0035*%
%ADD34C,.0045*%
%ADD35C,.0055*%
%ADD36C,.0065*%
%ADD37C,.03004*%
%ADD38C,.03006*%
%ADD47C,.02404*%
%ADD60C,.07005*%
%ADD55C,.07104*%
%ADD57C,.02804*%
%ADD62C,.02806*%
%ADD51C,.08404*%
%ADD39C,.03824*%
%ADD56C,.02934*%
%ADD53C,.09208*%
%ADD50C,.08408*%
%ADD45C,.02576*%
%ADD52C,.07608*%
%ADD49C,.08409*%
%ADD48O,.1621X.2251*%
%ADD43O,.03604X.07004*%
%ADD61C,.32504*%
%ADD44O,.03006X.06406*%
%ADD41C,.16206*%
%ADD42O,.03606X.07006*%
%ADD46C,.17406*%
%ADD40C,.16506*%
%ADD54C,.16804*%
%ADD59C,.37406*%
%ADD58C,.21786*%
G75*
%LPD*%
G75*
G36*
G01X1081725Y1645992D02*
X1833071D01*
G02X1838945Y1640118I0J-5874D01*
G01Y970426D01*
G02X1837225Y966273I-5874J0D01*
G01X1826876Y955925D01*
G03X1823984Y948944I6982J-6982D01*
G01Y344836D01*
G03X1826876Y337855I9873J0D01*
G01X1837225Y327506D01*
G02X1838945Y323354I-4153J-4153D01*
G01Y7874D01*
G02X1833071Y2000I-5874J0D01*
G01X1756949D01*
G02X1751075Y7874I0J5874D01*
G01Y46654D01*
G03X1749600Y50571I-5938J0D01*
G01Y50666D01*
X1749606Y50672D01*
X1751979D01*
G02X1753072Y46654I-6841J-4019D01*
G01Y7874D01*
G03X1756947Y3998I3876J0D01*
G01X1833071D01*
G03X1836948Y7874I0J3877D01*
G01Y323354D01*
G03X1835813Y326094I-3876J0D01*
G01X1825464Y336443D01*
G02X1821987Y344836I8393J8394D01*
G01X1821986D01*
Y948944D01*
X1821987D01*
G02X1825464Y957337I11871J-1D01*
G01X1835813Y967685D01*
G03X1836948Y970426I-2742J2741D01*
G01Y1195778D01*
X1833800Y1198926D01*
X1768750D01*
G02X1768608Y1198985I0J200D01*
G01X1767355Y1200237D01*
G03X1767213Y1200296I-142J-141D01*
G01X1751687D01*
G02X1751545Y1200355I0J200D01*
G01X1747459Y1204441D01*
X1747430Y1204469D01*
X1747400Y1204543D01*
Y1220817D01*
G02X1747457Y1220957I200J0D01*
G01X1763207Y1236707D01*
G03X1763266Y1236849I-141J142D01*
G01Y1249606D01*
G02X1763268Y1249634I200J0D01*
G01X1764820Y1260563D01*
G02X1764877Y1260677I198J-28D01*
G01X1770243Y1266043D01*
G03X1770302Y1266185I-141J142D01*
G01Y1320032D01*
G03X1770243Y1320174I-200J0D01*
G01X1750964Y1339453D01*
G02X1750905Y1339595I141J142D01*
G01Y1426872D01*
G03X1750846Y1427014I-200J0D01*
G01X1725439Y1452421D01*
G02X1725380Y1452563I141J142D01*
G01Y1465353D01*
G03X1725321Y1465495I-200J0D01*
G01X1723001Y1467815D01*
G02X1722956Y1467884I141J141D01*
G01Y1468028D01*
X1722969Y1468062D01*
G03X1723112Y1468857I-2143J796D01*
G01Y1468859D01*
G03X1720826Y1471145I-2286J0D01*
G03X1720544Y1471127I4J-2286D01*
G01X1720497Y1471121D01*
X1720409Y1471152D01*
X1720154Y1471414D01*
G02X1720098Y1471579I143J140D01*
G01X1720099Y1471584D01*
Y1471586D01*
G03X1720112Y1471711I-1486J218D01*
G01X1720114Y1471753D01*
X1720152Y1471827D01*
X1720184Y1471853D01*
X1720185Y1471854D01*
X1720411Y1472039D01*
G02X1720562Y1472083I127J-154D01*
G01X1720566D01*
G03X1720826Y1472065I262J1894D01*
G03X1718914Y1473977I0J1912D01*
G01Y1473974D01*
G03X1718927Y1473753I1912J2D01*
G01X1718932Y1473711D01*
X1718908Y1473632D01*
X1718693Y1473378D01*
G02X1718630Y1473328I-153J129D01*
G01X1718591Y1473309D01*
X1718548Y1473307D01*
G03X1717894Y1473125I65J-1501D01*
G01X1717835Y1473093D01*
X1717704Y1473112D01*
X1713837Y1476980D01*
G02X1713778Y1477122I141J142D01*
G01Y1477252D01*
X1713792Y1477304D01*
X1713806Y1477328D01*
G03X1714077Y1478308I-1640J981D01*
G01Y1478373D01*
G03X1713806Y1479291I-1912J-65D01*
G02X1713778Y1479394I172J102D01*
G01Y1482330D01*
G02X1713788Y1482392I200J0D01*
G01X1713806Y1482445D01*
X1713816Y1482462D01*
G03Y1484390I-1650J964D01*
G01X1713806Y1484407D01*
X1713788Y1484460D01*
G02X1713778Y1484522I190J62D01*
G01Y1485635D01*
G03X1713575Y1485838I-203J0D01*
G01X1710755D01*
G03X1710552Y1485635I0J-203D01*
G01Y1484522D01*
G02X1710542Y1484460I-200J0D01*
G01X1710524Y1484407D01*
X1710514Y1484390D01*
G03Y1482462I1650J-964D01*
G01X1710524Y1482445D01*
X1710542Y1482392D01*
G02X1710552Y1482330I-190J-62D01*
G01Y1479404D01*
G02X1710542Y1479342I-200J0D01*
G01X1710524Y1479289D01*
X1710514Y1479272D01*
G03X1710267Y1478538I1651J-964D01*
G01X1710258Y1478462D01*
X1710145Y1478362D01*
X1705790D01*
G02X1705638Y1478432I0J200D01*
G01X1705502Y1478591D01*
X1705444Y1478658D01*
G02X1705395Y1478789I151J131D01*
G01Y1478820D01*
X1705397Y1478834D01*
G03X1705412Y1478982I-1893J267D01*
G01X1705416Y1479047D01*
Y1479096D01*
G03X1705144Y1480078I-1913J-1D01*
G02X1705116Y1480181I172J102D01*
G01Y1481305D01*
G03X1704913Y1481508I-203J0D01*
G01X1702093D01*
G03X1701890Y1481305I0J-203D01*
G01Y1480191D01*
G02X1701880Y1480129I-200J0D01*
G01X1701862Y1480076D01*
X1701852Y1480059D01*
G03X1701591Y1479095I1652J-965D01*
G03X1701611Y1478820I1912J1D01*
G01X1701617Y1478776D01*
X1701593Y1478694D01*
X1701367Y1478431D01*
G02X1701216Y1478362I-151J131D01*
G01X1696862D01*
X1696749Y1478462D01*
X1696740Y1478538D01*
G03X1696482Y1479290I-1898J-231D01*
G02X1696454Y1479393I172J102D01*
G01Y1482341D01*
G02X1696482Y1482444I200J1D01*
G03X1696754Y1483426I-1640J983D01*
G03X1696483Y1484407I-1911J0D01*
G01Y1484408D01*
G02X1696454Y1484511I171J104D01*
G01Y1485071D01*
X1696455Y1485635D01*
G03X1696253Y1485838I-203J0D01*
G01X1693432D01*
G03X1693230Y1485636I0J-202D01*
G01Y1484511D01*
G02X1693202Y1484408I-200J-1D01*
G03X1692930Y1483426I1640J-983D01*
G03X1693202Y1482444I1912J1D01*
G02X1693230Y1482341I-172J-102D01*
G01Y1479393D01*
G02X1693202Y1479290I-200J-1D01*
G03X1692944Y1478538I1640J-983D01*
G01X1692935Y1478462D01*
X1692822Y1478362D01*
X1688468D01*
G02X1688316Y1478432I0J200D01*
G01X1688180Y1478591D01*
X1688122Y1478658D01*
G02X1688073Y1478789I151J131D01*
G01Y1478820D01*
X1688075Y1478834D01*
G03X1688090Y1478982I-1893J267D01*
G01X1688094Y1479047D01*
Y1479096D01*
G03X1687822Y1480078I-1913J-1D01*
G02X1687794Y1480181I172J102D01*
G01Y1481305D01*
G03X1687591Y1481508I-203J0D01*
G01X1684771D01*
G03X1684568Y1481305I0J-203D01*
G01Y1480191D01*
G02X1684558Y1480129I-200J0D01*
G01X1684540Y1480076D01*
X1684530Y1480059D01*
G03X1684269Y1479095I1652J-965D01*
G03X1684289Y1478820I1912J1D01*
G01X1684295Y1478776D01*
X1684271Y1478694D01*
X1684045Y1478431D01*
G02X1683894Y1478362I-151J131D01*
G01X1679539D01*
X1679426Y1478462D01*
X1679417Y1478538D01*
G03X1679160Y1479288I-1898J-231D01*
G02X1679132Y1479391I172J102D01*
G01Y1482330D01*
G02X1679142Y1482392I200J0D01*
G01X1679160Y1482445D01*
X1679170Y1482462D01*
G03Y1484390I-1650J964D01*
G01X1679160Y1484407D01*
X1679142Y1484460D01*
G02X1679132Y1484522I190J62D01*
G01Y1485635D01*
G03X1678929Y1485838I-203J0D01*
G01X1676109D01*
G03X1675906Y1485635I0J-203D01*
G01Y1484522D01*
G02X1675896Y1484460I-200J0D01*
G01X1675878Y1484407D01*
X1675868Y1484390D01*
G03Y1482462I1650J-964D01*
G01X1675878Y1482445D01*
X1675896Y1482392D01*
G02X1675906Y1482330I-190J-62D01*
G01Y1479404D01*
G02X1675896Y1479342I-200J0D01*
G01X1675878Y1479289D01*
X1675868Y1479272D01*
G03X1675621Y1478538I1651J-964D01*
G01X1675612Y1478462D01*
X1675499Y1478362D01*
X1671145D01*
G02X1670993Y1478432I0J200D01*
G01X1670857Y1478591D01*
X1670799Y1478658D01*
G02X1670750Y1478789I151J131D01*
G01Y1478820D01*
X1670752Y1478833D01*
G03X1670770Y1479094I-1894J262D01*
G01Y1479095D01*
G03X1670499Y1480076I-1911J0D01*
G01Y1480077D01*
G02X1670470Y1480180I171J104D01*
G01Y1480741D01*
X1670471Y1481305D01*
G03X1670269Y1481508I-203J0D01*
G01X1667448D01*
G03X1667246Y1481306I0J-202D01*
G01Y1480180D01*
G02X1667218Y1480077I-200J-1D01*
G03X1666946Y1479095I1640J-983D01*
G03X1666966Y1478820I1912J1D01*
G01X1666972Y1478776D01*
X1666948Y1478694D01*
X1666722Y1478431D01*
G02X1666571Y1478362I-151J131D01*
G01X1662216D01*
X1662103Y1478462D01*
X1662094Y1478538D01*
G03X1661836Y1479290I-1898J-231D01*
G02X1661808Y1479393I172J102D01*
G01Y1482341D01*
G02X1661836Y1482444I200J1D01*
G03X1662108Y1483426I-1640J983D01*
G03X1661837Y1484407I-1911J0D01*
G01Y1484408D01*
G02X1661808Y1484511I171J104D01*
G01Y1485071D01*
X1661809Y1485635D01*
G03X1661607Y1485838I-203J0D01*
G01X1658786D01*
G03X1658584Y1485636I0J-202D01*
G01Y1484511D01*
G02X1658556Y1484408I-200J-1D01*
G03X1658284Y1483426I1640J-983D01*
G03X1658556Y1482444I1912J1D01*
G02X1658584Y1482341I-172J-102D01*
G01Y1479393D01*
G02X1658556Y1479290I-200J-1D01*
G03X1658298Y1478538I1640J-983D01*
G01X1658289Y1478462D01*
X1658176Y1478362D01*
X1653822D01*
G02X1653670Y1478432I0J200D01*
G01X1653534Y1478591D01*
X1653476Y1478658D01*
G02X1653427Y1478789I151J131D01*
G01Y1478820D01*
X1653429Y1478834D01*
G03X1653444Y1478982I-1893J267D01*
G01X1653448Y1479047D01*
Y1479096D01*
G03X1653176Y1480078I-1913J-1D01*
G02X1653148Y1480181I172J102D01*
G01Y1481305D01*
G03X1652945Y1481508I-203J0D01*
G01X1650985D01*
G02X1650785Y1481704I0J200D01*
G01X1650777Y1482160D01*
X1650775Y1482259D01*
X1650695Y1486486D01*
G02X1650699Y1486529I200J3D01*
G01X1650710Y1486583D01*
X1650717Y1486601D01*
Y1486602D01*
G03X1650774Y1486770I-1392J566D01*
G01X1650791Y1486836D01*
X1650898Y1486918D01*
X1652945D01*
G03X1653148Y1487121I0J203D01*
G01Y1488235D01*
G02X1653158Y1488297I200J0D01*
G01X1653176Y1488350D01*
X1653186Y1488367D01*
G03Y1490295I-1650J964D01*
G01X1653176Y1490312D01*
X1653158Y1490365D01*
G02X1653148Y1490427I190J62D01*
G01Y1493353D01*
G02X1653158Y1493415I200J0D01*
G01X1653176Y1493468D01*
X1653186Y1493485D01*
G03Y1495413I-1650J964D01*
G01X1653176Y1495430D01*
X1653158Y1495483D01*
G02X1653148Y1495545I190J62D01*
G01Y1496659D01*
G03X1652945Y1496862I-203J0D01*
G01X1650898D01*
X1650791Y1496944D01*
X1650773Y1497010D01*
G03X1650540Y1497499I-1450J-391D01*
G01Y1497500D01*
X1650523Y1497524D01*
X1650493Y1497608D01*
G02X1650485Y1497639I189J65D01*
G02X1650482Y1497671I197J35D01*
G01X1650413Y1501366D01*
G02X1650425Y1501439I200J5D01*
G01X1650460Y1501533D01*
X1650481Y1501559D01*
G03X1650717Y1501957I-1158J956D01*
G03X1650773Y1502125I-1394J558D01*
G01Y1502127D01*
G02X1650966Y1502274I193J-53D01*
G01X1652959D01*
G03X1653148Y1502475I-14J202D01*
G01Y1503589D01*
G02X1653158Y1503651I200J0D01*
G01X1653176Y1503704D01*
X1653186Y1503721D01*
G03Y1505649I-1650J964D01*
G01X1653176Y1505666D01*
X1653158Y1505719D01*
G02X1653148Y1505781I190J62D01*
G01Y1508708D01*
G02X1653158Y1508770I200J0D01*
G01X1653176Y1508823D01*
X1653186Y1508840D01*
G03Y1510768I-1650J964D01*
G01X1653176Y1510785D01*
X1653158Y1510838D01*
G02X1653148Y1510900I190J62D01*
G01Y1512014D01*
G03X1652946Y1512216I-202J0D01*
G01X1651451D01*
G02X1651275Y1512322I0J200D01*
G01X1651249Y1512371D01*
X1651254Y1512481D01*
X1651293Y1512539D01*
G02X1651303Y1512552I163J-115D01*
G01X1651326Y1512581D01*
X1651342Y1512594D01*
G02X1651472Y1512637I124J-157D01*
G03X1651535Y1512636I68J2285D01*
G03X1653796Y1514581I0J2287D01*
G01X1653803Y1514629D01*
X1653857Y1514705D01*
X1655321Y1515488D01*
X1658761Y1517324D01*
G02X1658910Y1517340I94J-177D01*
G01X1658969Y1517323D01*
X1658993Y1517308D01*
G03X1660196Y1516966I1203J1945D01*
G03X1662481Y1519196I0J2286D01*
G01X1662483Y1519251D01*
X1662539Y1519342D01*
X1712579Y1546064D01*
G03X1713506Y1546752I-1851J3463D01*
G01X1719375Y1552622D01*
G03X1720524Y1555397I-2777J2775D01*
G01Y1558674D01*
G02X1720579Y1558812I200J0D01*
G01X1720681Y1558919D01*
X1720799Y1559042D01*
X1720869Y1559073D01*
X1720908Y1559075D01*
G03X1720895Y1562896I-82J1910D01*
G01X1720781Y1562948D01*
G02X1720773Y1562956I137J145D01*
G01X1720710Y1563022D01*
X1720580Y1563157D01*
G02X1720524Y1563296I144J139D01*
G01Y1563792D01*
G02X1720579Y1563930I200J0D01*
G01X1720681Y1564037D01*
X1720799Y1564160D01*
X1720869Y1564191D01*
X1720908Y1564193D01*
G03X1722738Y1566103I-82J1910D01*
G03X1720827Y1568015I-1912J0D01*
G01X1720826D01*
G03X1720486Y1567984I3J-1912D01*
G01X1720469Y1567981D01*
X1720468D01*
G02X1720241Y1568117I-36J197D01*
G01X1720235Y1568132D01*
G03X1720182Y1568256I-3637J-1481D01*
G03X1720133Y1568361I-3582J-1608D01*
G01X1720123Y1568380D01*
X1720110Y1568428D01*
X1720106Y1568443D01*
X1720104Y1568458D01*
G03X1719163Y1569673I-1491J-183D01*
G01X1719145Y1569680D01*
X1719081Y1569721D01*
X1719065Y1569737D01*
X1717595Y1571206D01*
G03X1715761Y1572242I-2777J-2775D01*
G02X1715696Y1572271I48J194D01*
G02X1715688Y1572277I116J163D01*
G01X1715595Y1572348D01*
X1715574Y1572383D01*
X1715573Y1572385D01*
G03X1712165Y1574361I-3408J-1951D01*
G01X1712164D01*
X1712110Y1574360D01*
G03X1711003Y1574185I53J-3926D01*
G03X1710607Y1574039I1159J-3753D01*
G01X1710570Y1574027D01*
X1710547Y1574022D01*
G02X1710472Y1574020I-43J195D01*
G01X1710449Y1574024D01*
X1710433Y1574029D01*
G03X1710079Y1574103I-482J-1423D01*
G03X1709963Y1574108I-123J-1497D01*
G01X1709944D01*
G03X1708450Y1572606I8J-1502D01*
G01Y1572605D01*
G03X1708536Y1572105I1502J1D01*
G01X1708547Y1572073D01*
Y1571981D01*
X1708539Y1571943D01*
X1708532Y1571925D01*
X1708531Y1571923D01*
G03X1708238Y1570435I3634J-1488D01*
G01Y1568930D01*
G03X1708366Y1567937I3927J1D01*
G01X1708369Y1567926D01*
X1708376Y1567875D01*
X1708371Y1567840D01*
G03X1708346Y1567739I3800J-994D01*
G01X1708332Y1567701D01*
X1708294Y1567667D01*
G02X1708240Y1567632I-134J148D01*
G01X1708147Y1567591D01*
X1708145D01*
X1708139Y1567588D01*
G02X1708012Y1567576I-81J183D01*
G01X1707961Y1567588D01*
X1707940Y1567599D01*
G03X1707062Y1567920I-1778J-3502D01*
G01X1707028Y1567944D01*
X1706964Y1567993D01*
X1706931Y1568018D01*
X1706911Y1568053D01*
G03X1703503Y1570030I-3408J-1949D01*
G03X1701949Y1569709I1J-3927D01*
G01X1701948D01*
G02X1701728Y1569751I-79J184D01*
G01X1701621Y1569858D01*
X1700272Y1571206D01*
G03X1698438Y1572242I-2777J-2775D01*
G02X1698373Y1572271I48J194D01*
G02X1698365Y1572277I116J163D01*
G01X1698272Y1572348D01*
X1698251Y1572383D01*
X1698250Y1572385D01*
G03X1694878Y1574361I-3408J-1951D01*
G01X1694802Y1574360D01*
G03X1694527Y1574347I48J-3926D01*
G03X1693382Y1574079I312J-3914D01*
G03X1693285Y1574039I1448J-3649D01*
G01X1693267Y1574031D01*
X1693224Y1574022D01*
G02X1693149Y1574020I-43J195D01*
G01X1693126Y1574024D01*
X1693110Y1574029D01*
G03X1692756Y1574103I-482J-1423D01*
G03X1692640Y1574108I-123J-1497D01*
G01X1692621D01*
G03X1691127Y1572606I8J-1502D01*
G01Y1572605D01*
G03X1691213Y1572103I1502J-1D01*
G01X1691218Y1572089D01*
X1691232Y1572020D01*
X1691224Y1571982D01*
X1691216Y1571941D01*
X1691209Y1571923D01*
G03X1690916Y1570436I3633J-1488D01*
G01Y1568927D01*
G03X1691043Y1567937I3926J1D01*
G01X1691046Y1567926D01*
X1691053Y1567875D01*
X1691046Y1567824D01*
X1691042Y1567810D01*
G03X1691037Y1567791I3795J-1009D01*
G01X1691032Y1567769D01*
X1691031Y1567767D01*
X1691020Y1567723D01*
X1690960Y1567653D01*
X1690814Y1567588D01*
G02X1690686Y1567577I-80J183D01*
G01X1690631Y1567590D01*
X1690610Y1567601D01*
G03X1690472Y1567668I-1784J-3498D01*
G03X1690469Y1567669I-65J-189D01*
G03X1690438Y1567683I-1631J-3571D01*
G03X1690436Y1567685I-133J-131D01*
G03X1689741Y1567920I-1600J-3586D01*
G01X1689706Y1567944D01*
X1689642Y1567993D01*
X1689609Y1568018D01*
X1689589Y1568053D01*
G03X1686181Y1570030I-3408J-1949D01*
G03X1684663Y1569724I2J-3927D01*
G01X1684568Y1569684D01*
X1684449Y1569707D01*
X1684297Y1569859D01*
X1682949Y1571206D01*
G03X1681115Y1572242I-2777J-2775D01*
G02X1681050Y1572271I48J194D01*
G02X1681042Y1572277I116J163D01*
G01X1680949Y1572348D01*
X1680928Y1572383D01*
X1680927Y1572385D01*
G03X1677519Y1574361I-3408J-1951D01*
G01X1677518D01*
X1677464Y1574360D01*
G03X1676357Y1574185I53J-3926D01*
G03X1675961Y1574039I1159J-3753D01*
G01X1675924Y1574027D01*
X1675901Y1574022D01*
G02X1675826Y1574020I-43J195D01*
G01X1675803Y1574024D01*
X1675787Y1574029D01*
G03X1675433Y1574103I-482J-1423D01*
G03X1675317Y1574108I-123J-1497D01*
G01X1675298D01*
G03X1673804Y1572606I8J-1502D01*
G01Y1572605D01*
G03X1673890Y1572105I1502J1D01*
G01X1673901Y1572073D01*
Y1571981D01*
X1673893Y1571943D01*
X1673886Y1571925D01*
X1673885Y1571923D01*
G03X1673592Y1570435I3634J-1488D01*
G01Y1568930D01*
G03X1673720Y1567937I3927J1D01*
G01X1673723Y1567926D01*
X1673730Y1567875D01*
X1673723Y1567824D01*
X1673719Y1567810D01*
G03X1673714Y1567791I3795J-1009D01*
G01X1673709Y1567769D01*
X1673708Y1567767D01*
X1673697Y1567723D01*
X1673637Y1567653D01*
X1673491Y1567588D01*
G02X1673363Y1567577I-80J183D01*
G01X1673308Y1567590D01*
X1673287Y1567601D01*
G03X1673149Y1567668I-1784J-3498D01*
G03X1673146Y1567669I-65J-189D01*
G03X1673115Y1567683I-1631J-3571D01*
G03X1673113Y1567685I-133J-131D01*
G03X1672418Y1567920I-1600J-3586D01*
G01X1672383Y1567944D01*
X1672319Y1567993D01*
X1672286Y1568018D01*
X1672266Y1568053D01*
G03X1668858Y1570030I-3408J-1949D01*
G03X1667340Y1569724I2J-3927D01*
G01X1667245Y1569684D01*
X1667126Y1569707D01*
X1666974Y1569859D01*
X1665626Y1571206D01*
G03X1663792Y1572242I-2777J-2775D01*
G02X1663727Y1572271I48J194D01*
G02X1663719Y1572277I116J163D01*
G01X1663626Y1572348D01*
X1663605Y1572383D01*
X1663604Y1572385D01*
G03X1660232Y1574361I-3408J-1951D01*
G01X1660156Y1574360D01*
G03X1659881Y1574347I48J-3926D01*
G03X1658736Y1574079I312J-3914D01*
G03X1658639Y1574039I1448J-3649D01*
G01X1658621Y1574031D01*
X1658578Y1574022D01*
G02X1658503Y1574020I-43J195D01*
G01X1658480Y1574024D01*
X1658464Y1574029D01*
G03X1658110Y1574103I-482J-1423D01*
G03X1657994Y1574108I-123J-1497D01*
G01X1657975D01*
G03X1656481Y1572606I8J-1502D01*
G01Y1572605D01*
G03X1656567Y1572103I1502J-1D01*
G01X1656572Y1572089D01*
X1656586Y1572020D01*
X1656578Y1571982D01*
X1656570Y1571941D01*
X1656563Y1571923D01*
G03X1656270Y1570436I3633J-1488D01*
G01Y1568927D01*
G03X1656397Y1567937I3926J1D01*
G01X1656400Y1567926D01*
X1656407Y1567875D01*
X1656400Y1567824D01*
X1656396Y1567810D01*
G03X1656391Y1567791I3795J-1009D01*
G01X1656386Y1567769D01*
X1656385Y1567767D01*
X1656374Y1567723D01*
X1656314Y1567653D01*
X1656168Y1567588D01*
G02X1656040Y1567577I-80J183D01*
G01X1655985Y1567590D01*
X1655964Y1567601D01*
G03X1655826Y1567668I-1784J-3498D01*
G03X1655823Y1567669I-65J-189D01*
G03X1655792Y1567683I-1631J-3571D01*
G03X1655790Y1567685I-133J-131D01*
G03X1655095Y1567920I-1600J-3586D01*
G01X1655060Y1567944D01*
X1654996Y1567993D01*
X1654963Y1568018D01*
X1654943Y1568053D01*
G03X1651535Y1570030I-3408J-1949D01*
G01X1651534D01*
G03X1649976Y1569708I0J-3929D01*
G01X1649939Y1569696D01*
X1649917Y1569691D01*
G02X1649841Y1569690I-41J196D01*
G01X1649815Y1569694D01*
X1649800Y1569699D01*
G03X1649323Y1569777I-478J-1424D01*
G01X1649322D01*
G03X1647820Y1568275I0J-1502D01*
G01Y1568273D01*
G03X1647906Y1567773I1502J1D01*
G01X1647912Y1567757D01*
X1647924Y1567689D01*
X1647917Y1567652D01*
X1647909Y1567611D01*
X1647902Y1567593D01*
G03X1647608Y1566103I3633J-1491D01*
G01Y1564599D01*
G03X1647736Y1563606I3927J1D01*
G01X1647739Y1563595D01*
X1647746Y1563544D01*
X1647739Y1563493D01*
X1647736Y1563482D01*
G03X1647608Y1562489I3799J-994D01*
G01Y1560984D01*
G03X1647908Y1559479I3926J0D01*
G01X1647912Y1559460D01*
X1647916Y1559440D01*
G02X1647918Y1559360I-195J-45D01*
G01X1647912Y1559331D01*
X1647906Y1559315D01*
G03X1647820Y1558815I1416J-501D01*
G01Y1558813D01*
G03X1649317Y1557311I1502J0D01*
G01X1649324D01*
G03X1649370Y1557312I-10J1502D01*
G01X1649399Y1557313D01*
X1649428Y1557305D01*
G02X1649570Y1557061I-52J-193D01*
G01X1649557Y1557015D01*
X1649545Y1556993D01*
G03X1649249Y1555869I1990J-1125D01*
G01Y1555867D01*
G03X1649255Y1555703I2286J2D01*
G01X1649258Y1555649D01*
X1649211Y1555553D01*
X1648179Y1554866D01*
X1648138Y1554859D01*
G03X1646636Y1554260I672J-3869D01*
G01X1645012Y1553179D01*
G03X1644079Y1552308I2177J-3268D01*
G02X1643972Y1552237I-158J122D01*
G03X1642806Y1551711I1010J-3794D01*
G01X1642704Y1551643D01*
G02X1642667Y1551624I-109J167D01*
G02X1642502Y1551631I-75J185D01*
G01X1642142Y1551816D01*
X1642084Y1551907D01*
X1642082Y1551962D01*
G03X1640581Y1553409I-1501J-55D01*
G03X1639079Y1551907I0J-1502D01*
G03X1640286Y1550434I1502J0D01*
G01X1640316Y1550428D01*
X1640367Y1550401D01*
X1640389Y1550379D01*
G02X1640444Y1550276I-141J-142D01*
G01X1640470Y1550142D01*
G02X1640474Y1550104I-196J-40D01*
G01X1640423Y1549971D01*
G03X1640049Y1549476I2936J-2607D01*
G01X1640026Y1549440D01*
X1628839Y1541996D01*
G03X1628048Y1541300I2175J-3269D01*
G01X1618756Y1530588D01*
G03X1618360Y1530044I2965J-2574D01*
G01X1618261Y1529961D01*
G03X1618062Y1529866I546J-1400D01*
G03X1617297Y1528558I736J-1308D01*
G01Y1528542D01*
X1617299Y1528509D01*
Y1528506D01*
G03X1617503Y1527801I1501J52D01*
G01X1617524Y1527764D01*
X1617534Y1527684D01*
X1613056Y1512370D01*
G03X1612901Y1511406I3769J-1101D01*
G01X1611014Y1457602D01*
G02X1610956Y1457468I-200J7D01*
G01X1602504Y1449016D01*
G02X1602297Y1448968I-142J141D01*
G01X1602100Y1449036D01*
X1601959Y1449084D01*
G02X1601872Y1449143I65J189D01*
G01X1601871Y1449145D01*
G02X1601824Y1449247I151J131D01*
G01Y1449251D01*
G03X1600333Y1450570I-1491J-183D01*
G03X1598831Y1449068I0J-1502D01*
G03X1600151Y1447577I1502J0D01*
G01X1600208Y1447570D01*
X1600297Y1447499D01*
X1600365Y1447301D01*
X1600433Y1447104D01*
G02X1600385Y1446897I-189J-65D01*
G01X1597506Y1444018D01*
G03X1596790Y1444184I-716J-1461D01*
G03X1595309Y1443231I0J-1627D01*
G02X1595275Y1443228I-35J197D01*
G01X1587553D01*
G02X1587400Y1443300I1J200D01*
G02X1587355Y1443451I154J128D01*
G01X1588399Y1452646D01*
G03X1588424Y1453088I-3901J442D01*
G01Y1453108D01*
X1588071Y1526694D01*
G03X1587540Y1528648I-3926J-18D01*
G01X1586086Y1531151D01*
X1583423Y1535734D01*
X1579305Y1542820D01*
G03X1577451Y1544459I-3395J-1973D01*
G01X1549953Y1556191D01*
G02X1549836Y1556332I79J184D01*
G01Y1556335D01*
G03X1547598Y1558153I-2238J-469D01*
G01X1547585D01*
G02X1547444Y1558209I-2J200D01*
G01X1547358Y1558292D01*
G02X1547296Y1558436I138J145D01*
G01Y1558674D01*
G02X1547351Y1558812I200J0D01*
G01X1547453Y1558919D01*
X1547571Y1559042D01*
X1547641Y1559073D01*
X1547680Y1559075D01*
G03X1547667Y1562896I-82J1910D01*
G01X1547553Y1562948D01*
G02X1547545Y1562956I137J145D01*
G01X1547482Y1563022D01*
X1547352Y1563157D01*
G02X1547296Y1563296I144J139D01*
G01Y1563792D01*
G02X1547351Y1563930I200J0D01*
G01X1547453Y1564037D01*
X1547571Y1564160D01*
X1547641Y1564191D01*
X1547680Y1564193D01*
G03X1547667Y1568014I-82J1910D01*
G01X1547553Y1568066D01*
G02X1547545Y1568074I137J145D01*
G01X1547482Y1568140D01*
X1547352Y1568275D01*
G02X1547296Y1568414I144J139D01*
G01Y1574028D01*
G02X1547351Y1574166I200J0D01*
G01X1547453Y1574273D01*
X1547571Y1574396D01*
X1547641Y1574427D01*
X1547680Y1574429D01*
G03X1547667Y1578250I-82J1910D01*
G01X1547553Y1578302D01*
G02X1547545Y1578310I137J145D01*
G01X1547482Y1578376D01*
X1547352Y1578511D01*
G02X1547296Y1578650I144J139D01*
G01Y1579146D01*
G02X1547351Y1579284I200J0D01*
G01X1547453Y1579391D01*
X1547571Y1579514D01*
X1547641Y1579545D01*
X1547680Y1579547D01*
G03X1547667Y1583368I-82J1910D01*
G01X1547553Y1583420D01*
G02X1547545Y1583428I137J145D01*
G01X1547482Y1583494D01*
X1547352Y1583629D01*
G02X1547296Y1583768I144J139D01*
G01Y1589382D01*
G02X1547351Y1589520I200J0D01*
G01X1547453Y1589627D01*
X1547571Y1589750D01*
X1547641Y1589781D01*
X1547680Y1589783D01*
G03X1547667Y1593604I-82J1910D01*
G01X1547553Y1593656D01*
G02X1547545Y1593664I137J145D01*
G01X1547482Y1593730D01*
X1547352Y1593865D01*
G02X1547296Y1594004I144J139D01*
G01Y1594500D01*
G02X1547351Y1594638I200J0D01*
G01X1547453Y1594745D01*
X1547571Y1594868D01*
X1547641Y1594899D01*
X1547680Y1594901D01*
G03X1549510Y1596811I-82J1910D01*
G03X1547598Y1598723I-1912J0D01*
G03X1547241Y1598689I2J-1912D01*
G02X1547018Y1598811I-37J197D01*
G03X1546914Y1599048I-3645J-1458D01*
G01X1546912Y1599051D01*
X1546897Y1599086D01*
X1546878Y1599150D01*
X1546876Y1599167D01*
G03X1545934Y1600383I-1491J-182D01*
G01X1545915Y1600390D01*
X1545851Y1600431D01*
X1545835Y1600447D01*
X1544367Y1601914D01*
G03X1542533Y1602950I-2777J-2775D01*
G02X1542468Y1602979I48J194D01*
G02X1542460Y1602985I116J163D01*
G01X1542367Y1603056D01*
X1542346Y1603091D01*
X1542345Y1603093D01*
G03X1538937Y1605069I-3408J-1951D01*
G01X1538907D01*
X1538832Y1605067D01*
G03X1537678Y1604861I105J-3925D01*
G03X1537363Y1604739I1260J-3720D01*
G02X1537217Y1604733I-81J183D01*
G03X1536724Y1604817I-495J-1418D01*
G03X1535222Y1603315I0J-1502D01*
G01Y1603314D01*
G03X1535308Y1602812I1502J-1D01*
G01X1535313Y1602798D01*
X1535327Y1602729D01*
X1535319Y1602691D01*
X1535311Y1602650D01*
X1535304Y1602632D01*
G03X1535010Y1601142I3633J-1491D01*
G01Y1599638D01*
G03X1535138Y1598645I3927J1D01*
G01X1535141Y1598634D01*
X1535148Y1598583D01*
X1535143Y1598548D01*
G03X1535118Y1598447I3800J-994D01*
G01X1535104Y1598409D01*
X1535066Y1598375D01*
G02X1535012Y1598340I-134J148D01*
G01X1534919Y1598299D01*
X1534917D01*
X1534911Y1598296D01*
G02X1534784Y1598284I-81J183D01*
G01X1534733Y1598296D01*
X1534712Y1598307D01*
G03X1533834Y1598628I-1778J-3502D01*
G01X1533800Y1598652D01*
X1533736Y1598701D01*
X1533703Y1598726D01*
X1533683Y1598761D01*
G03X1530275Y1600738I-3408J-1949D01*
G03X1528721Y1600417I1J-3927D01*
G02X1528500Y1600459I-80J183D01*
G01X1528392Y1600567D01*
X1527044Y1601914D01*
G03X1525210Y1602950I-2777J-2775D01*
G02X1525145Y1602979I48J194D01*
G02X1525137Y1602985I116J163D01*
G01X1525044Y1603056D01*
X1525023Y1603091D01*
X1525022Y1603093D01*
G03X1521614Y1605069I-3408J-1951D01*
G01Y1605068D01*
G03X1520041Y1604739I0J-3926D01*
G02X1519895Y1604733I-81J183D01*
G03X1519404Y1604817I-495J-1418D01*
G01X1519401D01*
G03X1517899Y1603315I0J-1502D01*
G01Y1603312D01*
G03X1517985Y1602811I1502J0D01*
G01X1517990Y1602797D01*
X1518004Y1602728D01*
X1517996Y1602690D01*
X1517988Y1602649D01*
X1517981Y1602631D01*
G03X1517688Y1601144I3633J-1488D01*
G01Y1599635D01*
G03X1517815Y1598645I3926J1D01*
G01X1517818Y1598634D01*
X1517825Y1598583D01*
X1517818Y1598532D01*
X1517814Y1598518D01*
G03X1517809Y1598499I3795J-1009D01*
G01X1517804Y1598477D01*
X1517803Y1598475D01*
X1517792Y1598431D01*
X1517732Y1598361D01*
X1517586Y1598296D01*
G02X1517458Y1598285I-80J183D01*
G01X1517403Y1598298D01*
X1517382Y1598309D01*
G03X1517244Y1598376I-1784J-3498D01*
G03X1517241Y1598377I-65J-189D01*
G03X1517210Y1598391I-1631J-3571D01*
G03X1517208Y1598393I-133J-131D01*
G03X1516513Y1598628I-1600J-3586D01*
G01X1516478Y1598652D01*
X1516414Y1598701D01*
X1516381Y1598726D01*
X1516361Y1598761D01*
G03X1512953Y1600738I-3408J-1949D01*
G03X1511400Y1600417I2J-3927D01*
G01X1511398Y1600416D01*
X1511393Y1600414D01*
G02X1511178Y1600458I-74J186D01*
G01X1511096Y1600540D01*
X1509721Y1601914D01*
G03X1507887Y1602950I-2777J-2775D01*
G02X1507822Y1602979I48J194D01*
G02X1507814Y1602985I116J163D01*
G01X1507721Y1603056D01*
X1507700Y1603091D01*
X1507699Y1603093D01*
G03X1504291Y1605069I-3408J-1951D01*
G01X1504261D01*
X1504186Y1605067D01*
G03X1503032Y1604861I105J-3925D01*
G03X1502717Y1604739I1260J-3720D01*
G02X1502571Y1604733I-81J183D01*
G03X1502078Y1604817I-495J-1418D01*
G03X1500576Y1603315I0J-1502D01*
G01Y1603314D01*
G03X1500662Y1602812I1502J-1D01*
G01X1500667Y1602798D01*
X1500681Y1602729D01*
X1500673Y1602691D01*
X1500665Y1602650D01*
X1500658Y1602632D01*
G03X1500364Y1601142I3633J-1491D01*
G01Y1599638D01*
G03X1500492Y1598645I3927J1D01*
G01X1500495Y1598634D01*
X1500502Y1598583D01*
X1500495Y1598532D01*
X1500491Y1598518D01*
G03X1500486Y1598499I3795J-1009D01*
G01X1500481Y1598477D01*
X1500480Y1598475D01*
X1500469Y1598431D01*
X1500409Y1598361D01*
X1500263Y1598296D01*
G02X1500135Y1598285I-80J183D01*
G01X1500080Y1598298D01*
X1500059Y1598309D01*
G03X1499921Y1598376I-1784J-3498D01*
G03X1499918Y1598377I-65J-189D01*
G03X1499887Y1598391I-1631J-3571D01*
G03X1499885Y1598393I-133J-131D01*
G03X1499190Y1598628I-1600J-3586D01*
G01X1499155Y1598652D01*
X1499091Y1598701D01*
X1499058Y1598726D01*
X1499038Y1598761D01*
G03X1495630Y1600738I-3408J-1949D01*
G03X1494077Y1600417I2J-3927D01*
G01X1494075Y1600416D01*
X1494070Y1600414D01*
G02X1493855Y1600458I-74J186D01*
G01X1493773Y1600540D01*
X1492398Y1601914D01*
G03X1490564Y1602950I-2777J-2775D01*
G02X1490499Y1602979I48J194D01*
G02X1490491Y1602985I116J163D01*
G01X1490398Y1603056D01*
X1490377Y1603091D01*
X1490376Y1603093D01*
G03X1486968Y1605069I-3408J-1951D01*
G01Y1605068D01*
G03X1485395Y1604739I0J-3926D01*
G02X1485249Y1604733I-81J183D01*
G03X1484758Y1604817I-495J-1418D01*
G01X1484755D01*
G03X1483253Y1603315I0J-1502D01*
G01Y1603312D01*
G03X1483339Y1602811I1502J0D01*
G01X1483344Y1602797D01*
X1483358Y1602728D01*
X1483350Y1602690D01*
X1483342Y1602649D01*
X1483335Y1602631D01*
G03X1483042Y1601144I3633J-1488D01*
G01Y1599635D01*
G03X1483169Y1598645I3926J1D01*
G01X1483172Y1598634D01*
X1483179Y1598583D01*
X1483172Y1598532D01*
X1483168Y1598518D01*
G03X1483163Y1598499I3795J-1009D01*
G01X1483158Y1598477D01*
X1483157Y1598475D01*
X1483146Y1598431D01*
X1483086Y1598361D01*
X1482940Y1598296D01*
G02X1482812Y1598285I-80J183D01*
G01X1482757Y1598298D01*
X1482736Y1598309D01*
G03X1482598Y1598376I-1784J-3498D01*
G03X1482595Y1598377I-65J-189D01*
G03X1482564Y1598391I-1631J-3571D01*
G03X1482562Y1598393I-133J-131D01*
G03X1481867Y1598628I-1600J-3586D01*
G01X1481832Y1598652D01*
X1481768Y1598701D01*
X1481735Y1598726D01*
X1481715Y1598761D01*
G03X1478307Y1600738I-3408J-1949D01*
G01X1478305D01*
G03X1476749Y1600417I-1J-3927D01*
G01X1476712Y1600405D01*
X1476689Y1600400D01*
G02X1476614Y1600398I-43J195D01*
G01X1476591Y1600402D01*
X1476575Y1600407D01*
G03X1476221Y1600481I-482J-1423D01*
G03X1476105Y1600486I-123J-1497D01*
G01X1476086D01*
G03X1474592Y1598984I8J-1502D01*
G01Y1598983D01*
G03X1474678Y1598481I1502J-1D01*
G01X1474683Y1598467D01*
X1474697Y1598398D01*
X1474689Y1598360D01*
X1474681Y1598319D01*
X1474674Y1598301D01*
G03X1474380Y1596811I3633J-1491D01*
G01Y1595307D01*
G03X1474508Y1594314I3927J1D01*
G01X1474511Y1594303D01*
X1474518Y1594252D01*
X1474511Y1594201D01*
X1474508Y1594190D01*
G03X1474380Y1593197I3799J-994D01*
G01Y1591693D01*
G03X1474675Y1590200I3926J0D01*
G01X1474683Y1590182D01*
X1474689Y1590147D01*
G02X1474690Y1590074I-196J-39D01*
G01X1474684Y1590040D01*
X1474678Y1590024D01*
G03X1474592Y1589524I1416J-501D01*
G01Y1589522D01*
G03X1475893Y1588033I1503J0D01*
G01X1475940Y1588027D01*
X1476019Y1587974D01*
X1476220Y1587614D01*
X1476225Y1587521D01*
X1476207Y1587478D01*
G03X1476021Y1586576I2100J-903D01*
G01Y1586526D01*
X1476022Y1586502D01*
Y1586501D01*
G03X1477569Y1584412I2285J75D01*
G01X1477630Y1584391D01*
X1477704Y1584288D01*
Y1584070D01*
G02X1477504Y1583870I-200J0D01*
G01X1476897D01*
G03X1476694Y1583667I0J-203D01*
G01Y1582553D01*
G02X1476684Y1582491I-200J0D01*
G01X1476666Y1582438D01*
X1476656Y1582421D01*
G03Y1580493I1650J-964D01*
G01X1476666Y1580476D01*
X1476684Y1580423D01*
G02X1476694Y1580361I-190J-62D01*
G01Y1577435D01*
G02X1476684Y1577373I-200J0D01*
G01X1476666Y1577320D01*
X1476656Y1577303D01*
G03Y1575375I1650J-964D01*
G01X1476666Y1575358D01*
X1476684Y1575305D01*
G02X1476694Y1575243I-190J-62D01*
G01Y1574129D01*
G03X1476897Y1573926I203J0D01*
G01X1477504D01*
G02X1477704Y1573726I0J-200D01*
G01Y1573508D01*
X1477630Y1573405D01*
X1477569Y1573384D01*
G03Y1569058I738J-2163D01*
G01X1477630Y1569037D01*
X1477704Y1568934D01*
Y1568716D01*
G02X1477504Y1568516I-200J0D01*
G01X1476897D01*
G03X1476694Y1568313I0J-203D01*
G01Y1567199D01*
G02X1476684Y1567137I-200J0D01*
G01X1476666Y1567084D01*
X1476656Y1567067D01*
G03Y1565139I1650J-964D01*
G01X1476666Y1565122D01*
X1476684Y1565069D01*
G02X1476694Y1565007I-190J-62D01*
G01Y1562081D01*
G02X1476684Y1562019I-200J0D01*
G01X1476666Y1561966D01*
X1476656Y1561949D01*
G03Y1560021I1650J-964D01*
G01X1476666Y1560004D01*
X1476684Y1559951D01*
G02X1476694Y1559889I-190J-62D01*
G01Y1558775D01*
G03X1476897Y1558572I203J0D01*
G01X1477549D01*
G02X1477679Y1558524I0J-200D01*
G01X1477707Y1558500D01*
X1477742Y1558438D01*
X1477747Y1558401D01*
G03X1477923Y1557692I3882J587D01*
G01X1479748Y1552463D01*
X1480173Y1551246D01*
G03X1481758Y1549236I3707J1294D01*
G01X1506438Y1533386D01*
G03X1506982Y1533095I2118J3306D01*
G01X1536616Y1520085D01*
G02X1536734Y1519875I-81J-183D01*
G01X1536730Y1519848D01*
X1536727Y1519836D01*
G03X1536651Y1519252I2212J-585D01*
G01Y1519251D01*
G03X1536945Y1518130I2285J0D01*
G01X1536946Y1518129D01*
X1536958Y1518107D01*
X1536971Y1518061D01*
G02X1536830Y1517815I-193J-53D01*
G01X1536801Y1517807D01*
X1536771Y1517808D01*
G03X1536724Y1517809I-55J-1501D01*
G03X1535222Y1516307I0J-1502D01*
G01Y1516306D01*
G03X1535308Y1515804I1502J-1D01*
G01X1535313Y1515790D01*
X1535327Y1515721D01*
X1535319Y1515683D01*
X1535311Y1515642D01*
X1535304Y1515624D01*
G03X1535010Y1514134I3633J-1491D01*
G01Y1512630D01*
G03X1535138Y1511637I3927J1D01*
G01X1535141Y1511626D01*
X1535148Y1511575D01*
X1535142Y1511532D01*
X1535140Y1511523D01*
G03X1535137Y1511514I3713J-1243D01*
G01X1535126Y1511469D01*
X1535045Y1511372D01*
G03X1535043Y1511370I140J-142D01*
G01X1535029Y1511353D01*
X1534994Y1511326D01*
X1534913Y1511289D01*
G02X1534785Y1511277I-82J183D01*
G01X1534734Y1511288D01*
X1534712Y1511300D01*
G03X1533871Y1511612I-1777J-3502D01*
G02X1533857Y1511616I48J194D01*
G02X1533806Y1511641I62J190D01*
G02X1533798Y1511647I116J163D01*
G01X1533705Y1511718D01*
X1533684Y1511753D01*
X1533683Y1511755D01*
G03X1530275Y1513731I-3408J-1951D01*
G03X1528720Y1513410I0J-3927D01*
G01X1528719D01*
G02X1528499Y1513452I-79J184D01*
G01X1528391Y1513560D01*
X1527044Y1514906D01*
G03X1525210Y1515942I-2777J-2775D01*
G02X1525145Y1515971I48J194D01*
G02X1525137Y1515977I116J163D01*
G01X1525044Y1516048D01*
X1525023Y1516083D01*
X1525022Y1516085D01*
G03X1521614Y1518061I-3408J-1951D01*
G01Y1518060D01*
G03X1520041Y1517731I0J-3926D01*
G02X1519895Y1517725I-81J183D01*
G03X1519404Y1517809I-495J-1418D01*
G01X1519401D01*
G03X1517899Y1516307I0J-1502D01*
G01Y1516304D01*
G03X1517985Y1515803I1502J0D01*
G01X1517990Y1515789D01*
X1518004Y1515720D01*
X1517996Y1515682D01*
X1517988Y1515641D01*
X1517981Y1515623D01*
G03X1517688Y1514136I3633J-1488D01*
G01Y1512627D01*
G03X1517815Y1511637I3926J1D01*
G01X1517818Y1511626D01*
X1517825Y1511575D01*
X1517819Y1511532D01*
X1517817Y1511523D01*
G03X1517814Y1511514I3713J-1243D01*
G01X1517803Y1511469D01*
X1517722Y1511373D01*
Y1511371D01*
X1517707Y1511354D01*
X1517672Y1511327D01*
X1517589Y1511290D01*
G02X1517460Y1511277I-83J182D01*
G01X1517403Y1511291D01*
X1517382Y1511302D01*
G03X1517244Y1511369I-1784J-3498D01*
G03X1517241Y1511370I-65J-189D01*
G03X1517210Y1511384I-1631J-3571D01*
G03X1517208Y1511386I-133J-131D01*
G03X1516549Y1511612I-1598J-3587D01*
G02X1516541Y1511614I45J195D01*
G02X1516484Y1511641I56J192D01*
G02X1516476Y1511647I116J163D01*
G01X1516383Y1511718D01*
X1516362Y1511753D01*
X1516361Y1511755D01*
G03X1512973Y1513731I-3408J-1951D01*
G01X1512898Y1513730D01*
G03X1511397Y1513409I55J-3926D01*
G01X1511341Y1513385D01*
X1511220Y1513408D01*
X1511068Y1513560D01*
X1509721Y1514906D01*
G03X1507887Y1515942I-2777J-2775D01*
G02X1507822Y1515971I48J194D01*
G02X1507814Y1515977I116J163D01*
G01X1507721Y1516048D01*
X1507700Y1516083D01*
X1507699Y1516085D01*
G03X1504291Y1518061I-3408J-1951D01*
G01X1504261D01*
X1504186Y1518059D01*
G03X1503032Y1517853I105J-3925D01*
G03X1502717Y1517731I1260J-3720D01*
G02X1502571Y1517725I-81J183D01*
G03X1502078Y1517809I-495J-1418D01*
G03X1500576Y1516307I0J-1502D01*
G01Y1516306D01*
G03X1500662Y1515804I1502J-1D01*
G01X1500667Y1515790D01*
X1500681Y1515721D01*
X1500673Y1515683D01*
X1500665Y1515642D01*
X1500658Y1515624D01*
G03X1500364Y1514134I3633J-1491D01*
G01Y1512630D01*
G03X1500492Y1511637I3927J1D01*
G01X1500495Y1511626D01*
X1500502Y1511575D01*
X1500496Y1511532D01*
X1500494Y1511523D01*
G03X1500491Y1511514I3713J-1243D01*
G01X1500480Y1511469D01*
X1500399Y1511373D01*
Y1511371D01*
X1500384Y1511354D01*
X1500349Y1511327D01*
X1500266Y1511290D01*
G02X1500137Y1511277I-83J182D01*
G01X1500080Y1511291D01*
X1500059Y1511302D01*
G03X1499921Y1511369I-1784J-3498D01*
G03X1499918Y1511370I-65J-189D01*
G03X1499887Y1511384I-1631J-3571D01*
G03X1499885Y1511386I-133J-131D01*
G03X1499226Y1511612I-1598J-3587D01*
G02X1499218Y1511614I45J195D01*
G02X1499161Y1511641I56J192D01*
G02X1499153Y1511647I116J163D01*
G01X1499060Y1511718D01*
X1499039Y1511753D01*
X1499038Y1511755D01*
G03X1495650Y1513731I-3408J-1951D01*
G01X1495575Y1513730D01*
G03X1494074Y1513409I55J-3926D01*
G01X1494018Y1513385D01*
X1493897Y1513408D01*
X1493745Y1513560D01*
X1492398Y1514906D01*
G03X1490564Y1515942I-2777J-2775D01*
G02X1490499Y1515971I48J194D01*
G02X1490491Y1515977I116J163D01*
G01X1490398Y1516048D01*
X1490377Y1516083D01*
X1490376Y1516085D01*
G03X1486968Y1518061I-3408J-1951D01*
G01Y1518060D01*
G03X1485395Y1517731I0J-3926D01*
G02X1485249Y1517725I-81J183D01*
G03X1484758Y1517809I-495J-1418D01*
G01X1484755D01*
G03X1483253Y1516307I0J-1502D01*
G01Y1516304D01*
G03X1483339Y1515803I1502J0D01*
G01X1483344Y1515789D01*
X1483358Y1515720D01*
X1483350Y1515682D01*
X1483342Y1515641D01*
X1483335Y1515623D01*
G03X1483042Y1514136I3633J-1488D01*
G01Y1512627D01*
G03X1483169Y1511637I3926J1D01*
G01X1483172Y1511626D01*
X1483179Y1511575D01*
X1483173Y1511532D01*
X1483171Y1511523D01*
G03X1483168Y1511514I3713J-1243D01*
G01X1483157Y1511469D01*
X1483076Y1511373D01*
Y1511371D01*
X1483061Y1511354D01*
X1483026Y1511327D01*
X1482943Y1511290D01*
G02X1482814Y1511277I-83J182D01*
G01X1482757Y1511291D01*
X1482736Y1511302D01*
G03X1482598Y1511369I-1784J-3498D01*
G03X1482595Y1511370I-65J-189D01*
G03X1482564Y1511384I-1631J-3571D01*
G03X1482562Y1511386I-133J-131D01*
G03X1481903Y1511612I-1598J-3587D01*
G02X1481895Y1511614I45J195D01*
G02X1481838Y1511641I56J192D01*
G02X1481830Y1511647I116J163D01*
G01X1481737Y1511718D01*
X1481716Y1511753D01*
X1481715Y1511755D01*
G03X1478307Y1513731I-3408J-1951D01*
G01X1478306D01*
X1478252Y1513730D01*
G03X1477145Y1513555I53J-3926D01*
G03X1476749Y1513409I1159J-3753D01*
G01X1476712Y1513397D01*
X1476689Y1513392D01*
G02X1476614Y1513390I-43J195D01*
G01X1476591Y1513394D01*
X1476575Y1513399D01*
G03X1476221Y1513473I-482J-1423D01*
G03X1476105Y1513478I-123J-1497D01*
G01X1476086D01*
G03X1474592Y1511976I8J-1502D01*
G01Y1511975D01*
G03X1474678Y1511475I1502J1D01*
G01X1474689Y1511443D01*
Y1511351D01*
X1474681Y1511313D01*
X1474674Y1511295D01*
X1474673Y1511293D01*
G03X1474380Y1509805I3634J-1488D01*
G01Y1508300D01*
G03X1474508Y1507307I3927J1D01*
G01X1474511Y1507296D01*
X1474518Y1507245D01*
X1474511Y1507194D01*
X1474508Y1507183D01*
G03X1474380Y1506190I3799J-994D01*
G01Y1504685D01*
G03X1474675Y1503192I3926J0D01*
G01X1474683Y1503174D01*
X1474689Y1503139D01*
G02X1474690Y1503066I-196J-39D01*
G01X1474684Y1503032D01*
X1474678Y1503016D01*
G03X1474592Y1502516I1416J-501D01*
G01Y1502514D01*
G03X1475893Y1501025I1503J0D01*
G01X1475940Y1501019D01*
X1476019Y1500966D01*
X1476220Y1500606D01*
X1476225Y1500513D01*
X1476207Y1500470D01*
G03X1476021Y1499568I2100J-903D01*
G01Y1499518D01*
X1476022Y1499494D01*
Y1499493D01*
G03X1477569Y1497404I2285J75D01*
G01X1477630Y1497383D01*
X1477704Y1497280D01*
Y1497062D01*
G02X1477504Y1496862I-200J0D01*
G01X1476897D01*
G03X1476694Y1496659I0J-203D01*
G01Y1495545D01*
G02X1476684Y1495483I-200J0D01*
G01X1476666Y1495430D01*
X1476656Y1495413D01*
G03Y1493485I1650J-964D01*
G01X1476666Y1493468D01*
X1476684Y1493415D01*
G02X1476694Y1493353I-190J-62D01*
G01Y1490427D01*
G02X1476684Y1490365I-200J0D01*
G01X1476666Y1490312D01*
X1476656Y1490295D01*
G03Y1488367I1650J-964D01*
G01X1476666Y1488350D01*
X1476684Y1488297D01*
G02X1476694Y1488235I-190J-62D01*
G01Y1487121D01*
G03X1476897Y1486918I203J0D01*
G01X1477504D01*
G02X1477704Y1486718I0J-200D01*
G01Y1486500D01*
X1477630Y1486397D01*
X1477569Y1486376D01*
G03Y1482050I738J-2163D01*
G01X1477630Y1482029D01*
X1477704Y1481926D01*
Y1481708D01*
G02X1477504Y1481508I-200J0D01*
G01X1476897D01*
G03X1476694Y1481305I0J-203D01*
G01Y1480191D01*
G02X1476684Y1480129I-200J0D01*
G01X1476666Y1480076D01*
X1476656Y1480059D01*
G03Y1478131I1650J-964D01*
G01X1476666Y1478114D01*
X1476684Y1478061D01*
G02X1476694Y1477999I-190J-62D01*
G01Y1475073D01*
G02X1476684Y1475011I-200J0D01*
G01X1476666Y1474958D01*
X1476656Y1474941D01*
G03Y1473013I1650J-964D01*
G01X1476666Y1472996D01*
X1476684Y1472943D01*
G02X1476694Y1472881I-190J-62D01*
G01Y1471767D01*
G03X1476897Y1471564I203J0D01*
G01X1477504D01*
G02X1477704Y1471364I0J-200D01*
G01Y1471146D01*
X1477630Y1471043D01*
X1477569Y1471022D01*
G03Y1466696I738J-2163D01*
G01X1477630Y1466675D01*
X1477704Y1466572D01*
Y1466354D01*
G02X1477504Y1466154I-200J0D01*
G01X1476897D01*
G03X1476694Y1465951I0J-203D01*
G01Y1464837D01*
G02X1476684Y1464775I-200J0D01*
G01X1476666Y1464722D01*
X1476656Y1464705D01*
G03Y1462777I1650J-964D01*
G01X1476666Y1462760D01*
X1476684Y1462707D01*
G02X1476694Y1462645I-190J-62D01*
G01Y1459718D01*
G02X1476684Y1459656I-200J0D01*
G01X1476666Y1459603D01*
X1476656Y1459586D01*
G03Y1457658I1650J-964D01*
G01X1476666Y1457641D01*
X1476684Y1457588D01*
G02X1476694Y1457526I-190J-62D01*
G01Y1456413D01*
G03X1476897Y1456210I203J0D01*
G01X1477504D01*
G02X1477704Y1456010I0J-200D01*
G01Y1455791D01*
X1477630Y1455688D01*
X1477569Y1455667D01*
G03X1476021Y1453504I737J-2163D01*
G03X1476731Y1451848I2286J0D01*
G01X1476760Y1451820D01*
X1476797Y1451736D01*
G02X1476796Y1451571I-183J-81D01*
G01X1473399Y1444273D01*
X1472966Y1443344D01*
G02X1472785Y1443228I-182J84D01*
G01X1400083D01*
G02X1399941Y1443287I0J200D01*
G01X1393659Y1449569D01*
G02X1393600Y1449711I141J142D01*
G01Y1580317D01*
G03X1393541Y1580459I-200J0D01*
G01X1384758Y1589242D01*
X1384750Y1589396D01*
X1384799Y1589456D01*
G03X1385318Y1590906I-1766J1450D01*
G03X1383032Y1593192I-2286J0D01*
G03X1381582Y1592673I0J-2285D01*
G01X1381522Y1592624D01*
X1381368Y1592632D01*
X1371659Y1602341D01*
G03X1371517Y1602400I-142J-141D01*
G01X1370609D01*
G02X1370501Y1602432I0J200D01*
G01X1370500D01*
G03X1369305Y1602950I-2138J-3294D01*
G01X1369298Y1602952D01*
G02X1369240Y1602979I54J193D01*
G02X1369232Y1602985I116J163D01*
G01X1369139Y1603056D01*
X1369118Y1603091D01*
X1369117Y1603093D01*
G03X1365709Y1605069I-3408J-1951D01*
G01X1365679D01*
X1365604Y1605067D01*
G03X1364450Y1604861I105J-3925D01*
G03X1364135Y1604739I1260J-3720D01*
G02X1363989Y1604733I-81J183D01*
G03X1363496Y1604817I-495J-1418D01*
G03X1361994Y1603315I0J-1502D01*
G01Y1603314D01*
G03X1362080Y1602812I1502J-1D01*
G01X1362085Y1602798D01*
X1362099Y1602729D01*
X1362091Y1602691D01*
X1362083Y1602650D01*
X1362075Y1602632D01*
G03X1362057Y1602586I3649J-1454D01*
G01X1362046Y1602558D01*
X1362009Y1602512D01*
X1361898Y1602435D01*
G02X1361785Y1602400I-113J165D01*
G01X1359373D01*
X1359266Y1602481D01*
X1359248Y1602546D01*
G03X1354846I-2201J-615D01*
G02X1354654Y1602400I-193J54D01*
G01X1353286D01*
G02X1353178Y1602432I0J200D01*
G01X1353177D01*
G03X1351982Y1602950I-2138J-3294D01*
G01X1351975Y1602952D01*
G02X1351917Y1602979I54J193D01*
G02X1351909Y1602985I116J163D01*
G01X1351816Y1603056D01*
X1351795Y1603091D01*
X1351794Y1603093D01*
G03X1348386Y1605069I-3408J-1951D01*
G01X1348356D01*
X1348281Y1605067D01*
G03X1347127Y1604861I105J-3925D01*
G03X1346812Y1604739I1260J-3720D01*
G02X1346666Y1604733I-81J183D01*
G03X1346173Y1604817I-495J-1418D01*
G03X1344671Y1603315I0J-1502D01*
G01Y1603314D01*
G03X1344757Y1602812I1502J-1D01*
G01X1344762Y1602798D01*
X1344776Y1602729D01*
X1344768Y1602691D01*
X1344760Y1602650D01*
X1344752Y1602632D01*
G03X1344734Y1602586I3649J-1454D01*
G01X1344723Y1602558D01*
X1344686Y1602512D01*
X1344575Y1602435D01*
G02X1344462Y1602400I-113J165D01*
G01X1342051D01*
X1341944Y1602481D01*
X1341926Y1602546D01*
G03X1337524I-2201J-615D01*
G02X1337332Y1602400I-193J54D01*
G01X1335963D01*
G02X1335855Y1602432I0J200D01*
G01X1335854D01*
G03X1334659Y1602950I-2138J-3294D01*
G01X1334652Y1602952D01*
G02X1334594Y1602979I54J193D01*
G02X1334586Y1602985I116J163D01*
G01X1334493Y1603056D01*
X1334472Y1603091D01*
X1334471Y1603093D01*
G03X1331063Y1605069I-3408J-1951D01*
G01X1331033D01*
X1330958Y1605067D01*
G03X1329804Y1604861I105J-3925D01*
G03X1329489Y1604739I1260J-3720D01*
G02X1329343Y1604733I-81J183D01*
G03X1328850Y1604817I-495J-1418D01*
G03X1327348Y1603315I0J-1502D01*
G01Y1603314D01*
G03X1327434Y1602812I1502J-1D01*
G01X1327439Y1602798D01*
X1327453Y1602729D01*
X1327445Y1602691D01*
X1327437Y1602650D01*
X1327429Y1602632D01*
G03X1327411Y1602586I3649J-1454D01*
G01X1327400Y1602558D01*
X1327363Y1602512D01*
X1327252Y1602435D01*
G02X1327139Y1602400I-113J165D01*
G01X1324728D01*
X1324621Y1602481D01*
X1324603Y1602546D01*
G03X1320201I-2201J-615D01*
G02X1320009Y1602400I-193J54D01*
G01X1318640D01*
G02X1318532Y1602432I0J200D01*
G01X1318531D01*
G03X1317336Y1602950I-2138J-3294D01*
G01X1317329Y1602952D01*
G02X1317271Y1602979I54J193D01*
G02X1317263Y1602985I116J163D01*
G01X1317170Y1603056D01*
X1317149Y1603091D01*
X1317148Y1603093D01*
G03X1313740Y1605069I-3408J-1951D01*
G01X1313710D01*
X1313635Y1605067D01*
G03X1312481Y1604861I105J-3925D01*
G03X1312166Y1604739I1260J-3720D01*
G02X1312020Y1604733I-81J183D01*
G03X1311527Y1604817I-495J-1418D01*
G03X1310025Y1603315I0J-1502D01*
G01Y1603314D01*
G03X1310111Y1602812I1502J-1D01*
G01X1310116Y1602798D01*
X1310130Y1602729D01*
X1310122Y1602691D01*
X1310114Y1602650D01*
X1310106Y1602632D01*
G03X1310088Y1602586I3649J-1454D01*
G01X1310077Y1602558D01*
X1310040Y1602512D01*
X1309929Y1602435D01*
G02X1309816Y1602400I-113J165D01*
G01X1307405D01*
X1307298Y1602481D01*
X1307280Y1602546D01*
G03X1302878I-2201J-615D01*
G02X1302686Y1602400I-193J54D01*
G01X1286117D01*
G02X1285975Y1602459I0J200D01*
G01X1285593Y1602841D01*
X1285564Y1602869D01*
X1285534Y1602943D01*
Y1642231D01*
G02X1285734Y1642431I200J0D01*
G01X1577660D01*
G02X1577860Y1642231I0J-200D01*
G01Y1550771D01*
G03X1577919Y1550629I200J0D01*
G01X1579595Y1548953D01*
G03X1579737Y1548894I142J141D01*
G01X1630582D01*
G03X1630724Y1548953I0J200D01*
G01X1633467Y1551696D01*
G03X1633526Y1551838I-141J142D01*
G01Y1643911D01*
G02X1633544Y1643994I200J0D01*
G01X1633526D01*
Y1644873D01*
X1578560D01*
Y1643994D01*
X1285912D01*
Y1644677D01*
X1232543D01*
Y1643994D01*
X1081724D01*
G03X1078854Y1642722I1J-3877D01*
G02X1070058Y1638822I-8797J7971D01*
G01X800966D01*
G02X792169Y1642722I0J11872D01*
G03X789299Y1643994I-2871J-2603D01*
G01X608951D01*
Y1644464D01*
X555228D01*
Y1643994D01*
X262776D01*
Y1644377D01*
X208818D01*
Y1643994D01*
X7874D01*
G03X3998Y1640118I0J-3876D01*
G01Y970425D01*
G03X5133Y967685I3877J1D01*
G01X15480Y957338D01*
G02X18958Y948943I-8394J-8396D01*
G01Y344836D01*
G02X15480Y336442I-11871J1D01*
G01X5132Y326094D01*
G03X3998Y323355I2742J-2739D01*
G01Y7874D01*
G03X7874Y3998I3876J0D01*
G01X23484D01*
G03X27360Y7874I0J3876D01*
G01Y46654D01*
G02X35295Y54588I7935J-1D01*
G01X64100D01*
X64454Y54234D01*
Y52945D01*
X64100Y52591D01*
X35295D01*
G03X29358Y46654I0J-5937D01*
G01Y7874D01*
G02X23484Y2000I-5874J0D01*
G01X7874D01*
G02X2000Y7874I0J5874D01*
G01Y323354D01*
G02X3720Y327506I5873J-1D01*
G01X14068Y337855D01*
G03X16961Y344836I-6980J6983D01*
G01Y948943D01*
G03X14068Y955925I-9875J-1D01*
G01X3720Y966273D01*
G02X2000Y970426I4154J4153D01*
G01Y1640118D01*
G02X7874Y1645992I5874J0D01*
G01X789298D01*
G02X793649Y1644063I-1J-5873D01*
G03X800966Y1640819I7317J6631D01*
G01X1070058D01*
G03X1077374Y1644063I-1J9873D01*
G02X1081725Y1645992I4352J-3945D01*
G37*
G36*
G01X608767Y1638670D02*
X791437D01*
G02X791470Y1638667I-2J-200D01*
G02X791577Y1638613I-32J-197D01*
G01X792926Y1637264D01*
G03X793068Y1637205I142J141D01*
G01X1074512D01*
G02X1074654Y1637146I0J-200D01*
G01X1076856Y1634944D01*
G02X1076915Y1634802I-141J-142D01*
G01Y1589833D01*
G03X1076974Y1589691I200J0D01*
G01X1081656Y1585009D01*
G02X1081715Y1584867I-141J-142D01*
G01Y1572493D01*
G02X1081656Y1572351I-200J0D01*
G01X1078933Y1569628D01*
G02X1078791Y1569569I-142J141D01*
G01X1049200D01*
G03X1049058Y1569510I0J-200D01*
G01X1044389Y1564841D01*
X1044373Y1564830D01*
G03X1038712Y1559169I11532J-17193D01*
G01X1038701Y1559153D01*
X1024376Y1544828D01*
G02X1024234Y1544769I-142J141D01*
G01X1003880D01*
G02X1003738Y1544828I0J200D01*
G01X1002426Y1546140D01*
G02X1002367Y1546282I141J142D01*
G01Y1568972D01*
G03X1002308Y1569114I-200J0D01*
G01X998760Y1572662D01*
G03X998618Y1572721I-142J-141D01*
G01X967381D01*
G02X967239Y1572780I0J200D01*
G01X964317Y1575702D01*
G02X964258Y1575844I141J142D01*
G01Y1579631D01*
G03X964199Y1579773I-200J0D01*
G01X960541Y1583431D01*
G03X960399Y1583490I-142J-141D01*
G01X942870D01*
G02X942728Y1583549I0J200D01*
G01X938157Y1588120D01*
G02X938098Y1588262I141J142D01*
G01Y1625289D01*
G03X938039Y1625431I-200J0D01*
G01X931910Y1631560D01*
G03X931768Y1631619I-142J-141D01*
G01X817580D01*
G03X817438Y1631560I0J-200D01*
G01X811459Y1625581D01*
G03X811400Y1625439I141J-142D01*
G01Y1536809D01*
G02X811341Y1536667I-200J0D01*
G01X802433Y1527759D01*
G03X802374Y1527617I141J-142D01*
G01Y1488575D01*
G02X802360Y1488500I-200J-1D01*
G01X802345Y1488464D01*
X798000Y1484120D01*
G03X797630Y1483227I897J-895D01*
G01Y1482756D01*
G02X797571Y1482614I-200J0D01*
G01X771088Y1456131D01*
G02X771060Y1456129I-28J198D01*
G01X745714D01*
G02X745614Y1456156I0J200D01*
G01X745593Y1456168D01*
X745579Y1456174D01*
G03X745506Y1456188I-74J-186D01*
G01X705918D01*
G02X705843Y1456202I-1J200D01*
G01X705807Y1456217D01*
X703495Y1458529D01*
G02X703459Y1458579I142J140D01*
G02X703437Y1458670I178J91D01*
G01Y1566554D01*
G03X703378Y1566696I-200J0D01*
G01X699695Y1570379D01*
G03X699553Y1570438I-142J-141D01*
G01X695698D01*
G02X695556Y1570496I-1J200D01*
G01X694847Y1571205D01*
G03X694318Y1571649I-2779J-2774D01*
G01X694304Y1571659D01*
X694146Y1571817D01*
G02X694088Y1571958I142J141D01*
G01Y1571963D01*
G03X694029Y1572104I-200J-1D01*
G01X693323Y1572810D01*
X693315Y1572820D01*
G03X692586Y1573550I-3119J-2385D01*
G01X692576Y1573558D01*
X691867Y1574266D01*
G03X691726Y1574325I-142J-141D01*
G01X690724D01*
X690711Y1574327D01*
G03X690197Y1574360I-508J-3893D01*
G03X689683Y1574327I-6J-3926D01*
G01X689670Y1574325D01*
X688668D01*
G03X688527Y1574266I1J-200D01*
G01X688405Y1574144D01*
G02X688323Y1574094I-142J141D01*
G01X688278Y1574080D01*
X688230Y1574088D01*
G03X688166Y1574097I-241J-1483D01*
G03X688047Y1574107I-185J-1491D01*
G01X688035D01*
G03X688022Y1574108I-122J-1496D01*
G01X687976D01*
G03X686482Y1572606I8J-1502D01*
G01Y1572600D01*
G03X686502Y1572360I1501J4D01*
G01X686510Y1572312D01*
X686496Y1572267D01*
G02X686446Y1572185I-191J60D01*
G01X686365Y1572104D01*
G03X686306Y1571963I141J-142D01*
G01Y1570961D01*
X686304Y1570948D01*
G03X686275Y1570628I3893J-514D01*
G01X686271Y1570542D01*
G02X686120Y1570440I-175J96D01*
G02X686096Y1570438I-29J198D01*
G01X678375D01*
G02X678233Y1570496I-1J200D01*
G01X677524Y1571205D01*
G03X676996Y1571648I-2778J-2775D01*
G01X676982Y1571658D01*
X676823Y1571817D01*
G02X676765Y1571958I142J141D01*
G01Y1571963D01*
G03X676706Y1572104I-200J-1D01*
G01X676000Y1572810D01*
X675992Y1572820D01*
G03X675263Y1573550I-3119J-2385D01*
G01X675253Y1573558D01*
X674544Y1574266D01*
G03X674403Y1574325I-142J-141D01*
G01X673401D01*
X673388Y1574327D01*
G03X672874Y1574360I-508J-3893D01*
G03X672360Y1574327I-6J-3926D01*
G01X672347Y1574325D01*
X671345D01*
G03X671204Y1574266I1J-200D01*
G01X671082Y1574144D01*
G02X671000Y1574094I-142J141D01*
G01X670955Y1574080D01*
X670907Y1574088D01*
G03X670843Y1574097I-241J-1483D01*
G03X670724Y1574107I-185J-1491D01*
G01X670712D01*
G03X670699Y1574108I-122J-1496D01*
G01X670653D01*
G03X669159Y1572606I8J-1502D01*
G01Y1572600D01*
G03X669179Y1572360I1501J4D01*
G01X669187Y1572312D01*
X669173Y1572267D01*
G02X669123Y1572185I-191J60D01*
G01X669042Y1572104D01*
G03X668983Y1571963I141J-142D01*
G01Y1570961D01*
X668981Y1570948D01*
G03X668952Y1570628I3893J-514D01*
G01X668948Y1570542D01*
G02X668797Y1570440I-175J96D01*
G02X668773Y1570438I-29J198D01*
G01X661052D01*
G02X660910Y1570496I-1J200D01*
G01X660201Y1571205D01*
G03X659673Y1571648I-2778J-2775D01*
G01X659659Y1571658D01*
X659500Y1571817D01*
G02X659442Y1571958I142J141D01*
G01Y1571963D01*
G03X659383Y1572104I-200J-1D01*
G01X658677Y1572810D01*
X658669Y1572820D01*
G03X657940Y1573550I-3119J-2385D01*
G01X657930Y1573558D01*
X657221Y1574266D01*
G03X657080Y1574325I-142J-141D01*
G01X656078D01*
X656065Y1574327D01*
G03X655551Y1574360I-508J-3893D01*
G03X655037Y1574327I-6J-3926D01*
G01X655024Y1574325D01*
X654022D01*
G03X653881Y1574266I1J-200D01*
G01X653759Y1574144D01*
G02X653677Y1574094I-142J141D01*
G01X653632Y1574080D01*
X653584Y1574088D01*
G03X653520Y1574097I-241J-1483D01*
G03X653401Y1574107I-185J-1491D01*
G01X653389D01*
G03X653376Y1574108I-122J-1496D01*
G01X653330D01*
G03X651836Y1572606I8J-1502D01*
G01Y1572600D01*
G03X651856Y1572360I1501J4D01*
G01X651864Y1572312D01*
X651850Y1572267D01*
G02X651800Y1572185I-191J60D01*
G01X651719Y1572104D01*
G03X651660Y1571963I141J-142D01*
G01Y1570961D01*
X651658Y1570948D01*
G03X651629Y1570628I3893J-514D01*
G01X651625Y1570542D01*
G02X651474Y1570440I-175J96D01*
G02X651450Y1570438I-29J198D01*
G01X643729D01*
G02X643587Y1570496I-1J200D01*
G01X642878Y1571205D01*
G03X642350Y1571648I-2778J-2775D01*
G01X642336Y1571658D01*
X642177Y1571817D01*
G02X642119Y1571958I142J141D01*
G01Y1571963D01*
G03X642060Y1572104I-200J-1D01*
G01X641354Y1572810D01*
X641346Y1572820D01*
G03X640617Y1573550I-3119J-2385D01*
G01X640607Y1573558D01*
X639898Y1574266D01*
G03X639757Y1574325I-142J-141D01*
G01X638755D01*
X638742Y1574327D01*
G03X638228Y1574360I-508J-3893D01*
G03X637714Y1574327I-6J-3926D01*
G01X637701Y1574325D01*
X636699D01*
G03X636558Y1574266I1J-200D01*
G01X636436Y1574144D01*
G02X636354Y1574094I-142J141D01*
G01X636309Y1574080D01*
X636261Y1574088D01*
G03X636197Y1574097I-241J-1483D01*
G03X636078Y1574107I-185J-1491D01*
G01X636066D01*
G03X636053Y1574108I-122J-1496D01*
G01X636007D01*
G03X634513Y1572606I8J-1502D01*
G01Y1572600D01*
G03X634533Y1572360I1501J4D01*
G01X634541Y1572312D01*
X634527Y1572267D01*
G02X634477Y1572185I-191J60D01*
G01X634396Y1572104D01*
G03X634337Y1571963I141J-142D01*
G01Y1570961D01*
X634335Y1570948D01*
G03X634306Y1570628I3893J-514D01*
G01X634302Y1570542D01*
G02X634151Y1570440I-175J96D01*
G02X634127Y1570438I-29J198D01*
G01X629886D01*
G03X629744Y1570379I0J-200D01*
G01X629417Y1570052D01*
G02X629384Y1570026I-140J143D01*
G01X629317Y1570021D01*
X629315D01*
G03X629053Y1569996I242J-3919D01*
G01X629040Y1569994D01*
X628038D01*
G03X627897Y1569935I1J-200D01*
G01X627774Y1569813D01*
G02X627695Y1569764I-142J141D01*
G01X627648Y1569749D01*
X627600Y1569757D01*
G03X627354Y1569778I-250J-1482D01*
G03X626343Y1569387I0J-1503D01*
G01X626341Y1569384D01*
X626330Y1569374D01*
G03X626326Y1569370I1060J-1064D01*
G01X626307Y1569352D01*
X626263Y1569328D01*
X626227Y1569319D01*
X626110Y1569286D01*
X626072Y1569290D01*
G03X625852Y1569091I-20J-199D01*
G01Y1568272D01*
G03X625872Y1568029I1502J1D01*
G01X625880Y1567981D01*
X625865Y1567934D01*
G02X625817Y1567855I-191J62D01*
G01X625735Y1567773D01*
G03X625676Y1567632I141J-142D01*
G01Y1566630D01*
X625674Y1566617D01*
G03X625649Y1566355I3894J-504D01*
G01Y1566353D01*
X625644Y1566286D01*
G02X625618Y1566253I-169J107D01*
G01X625004Y1565639D01*
G03X624945Y1565497I141J-142D01*
G01Y1555372D01*
G02X624931Y1555297I-200J-1D01*
G01X624916Y1555261D01*
X622733Y1553078D01*
G02X622701Y1553052I-141J141D01*
G01X622672Y1553033D01*
X622657Y1553025D01*
X622653Y1553023D01*
G03X622175Y1552749I1692J-3505D01*
G01X620727Y1551781D01*
G03X619894Y1551031I2160J-3237D01*
G02X619795Y1550966I-154J127D01*
G03X618693Y1550455I1081J-3775D01*
G01X617070Y1549370D01*
G03X616139Y1548499I2181J-3265D01*
G02X616032Y1548428I-158J122D01*
G03X614866Y1547899I1018J-3793D01*
G01X614722Y1547803D01*
G02X614610Y1547769I-111J166D01*
G01X614508Y1547797D01*
G03X613739Y1548009I-769J-1290D01*
G01X613738D01*
G03X612236Y1546507I0J-1502D01*
G01Y1546504D01*
G03X612289Y1546109I1502J1D01*
G01X612294Y1546091D01*
X612297Y1546057D01*
Y1546055D01*
X612300Y1546019D01*
X612290Y1545984D01*
G02X612258Y1545920I-192J56D01*
G01X612245Y1545902D01*
X612234Y1545890D01*
X612231Y1545887D01*
X612230Y1545885D01*
X612210Y1545864D01*
G03X612167Y1545818I2821J-2680D01*
G03X612115Y1545761I2849J-2651D01*
G03X612113Y1545759I140J-142D01*
G03X611928Y1545531I2927J-2564D01*
G01X611924Y1545527D01*
X611922Y1545524D01*
X611901Y1545496D01*
X608825Y1543441D01*
G03X608231Y1542952I2187J-3261D01*
G01X601326Y1536047D01*
G03X600475Y1534774I2776J-2777D01*
G01X593887Y1518873D01*
G02X593715Y1518750I-185J77D01*
G01X593300Y1518722D01*
X593199Y1518776D01*
X593171Y1518825D01*
G03X591872Y1519573I-1299J-754D01*
G03Y1516569I0J-1502D01*
G03X592956Y1517031I0J1503D01*
G02X593300Y1516881I144J-139D01*
G03X593294Y1516661I3920J-217D01*
G01Y1510586D01*
G02X593166Y1510400I-200J1D01*
G01X592816Y1510266D01*
G02X592596Y1510319I-71J187D01*
G03X591481Y1510815I-1115J-1005D01*
G03Y1507811I0J-1502D01*
G03X592596Y1508307I0J1501D01*
G02X592816Y1508360I149J-134D01*
G01X593166Y1508226D01*
G02X593294Y1508040I-72J-187D01*
G01Y1502967D01*
G02X593166Y1502781I-200J1D01*
G01X592759Y1502624D01*
X592640Y1502652D01*
X592598Y1502698D01*
G03X591487Y1503189I-1111J-1011D01*
G03Y1500185I0J-1502D01*
G03X592598Y1500676I0J1502D01*
G01X592640Y1500722D01*
X592759Y1500750D01*
X593166Y1500593D01*
G02X593294Y1500407I-72J-187D01*
G01Y1475004D01*
G02X593235Y1474862I-200J0D01*
G01X589520Y1471147D01*
G03X589461Y1471005I141J-142D01*
G01Y1373986D01*
G02X589447Y1373911I-200J-1D01*
G01X589432Y1373875D01*
X586970Y1371413D01*
G02X586920Y1371377I-140J142D01*
G02X586829Y1371355I-91J178D01*
G01X576843D01*
G02X576768Y1371369I-1J200D01*
G01X576732Y1371384D01*
X574780Y1373336D01*
G02X574744Y1373386I142J140D01*
G02X574722Y1373477I178J91D01*
G01Y1498680D01*
G03X574663Y1498822I-200J0D01*
G01X567831Y1505654D01*
G02X567803Y1505689I141J142D01*
G02X567772Y1505795I169J107D01*
G01X567742Y1511327D01*
X567726Y1514288D01*
X567701Y1518837D01*
G03X567432Y1520240I-3891J-19D01*
G01X564548Y1527577D01*
G02X564544Y1527589I188J69D01*
G01X563783Y1529981D01*
G03X563644Y1530351I-3741J-1194D01*
G01X561637Y1534983D01*
G02X561635Y1534989I189J66D01*
G01X560796Y1537122D01*
G03X560511Y1537701I-3622J-1423D01*
G03X560016Y1538357I-3337J-2003D01*
G01X559998Y1538376D01*
X557406Y1541230D01*
G02X557354Y1541364I148J135D01*
G01Y1541412D01*
G02X557370Y1541489I200J-1D01*
G01X557466Y1541719D01*
G03X557475Y1541745I-184J78D01*
G01X557486Y1541793D01*
X557518Y1541830D01*
G02X557597Y1541885I151J-132D01*
G01X557598D01*
X557665Y1541911D01*
X557696Y1541913D01*
G03X559086Y1543411I-112J1498D01*
G03X557584Y1544913I-1502J0D01*
G03X556098Y1543636I0J-1503D01*
G02X555951Y1543472I-198J30D01*
G01X555923Y1543465D01*
X555918Y1543462D01*
X555616Y1543373D01*
X555590Y1543372D01*
X555557Y1543371D01*
G02X555407Y1543432I-6J200D01*
G01X552979Y1546100D01*
G03X551498Y1547114I-2880J-2617D01*
G01X545487Y1549431D01*
X545457Y1549443D01*
X545398Y1549466D01*
X542849Y1550448D01*
X528898Y1555825D01*
G02X528890Y1555829I85J180D01*
G01X527930Y1556250D01*
X527877Y1556303D01*
X527874Y1556309D01*
X527860Y1556368D01*
Y1556370D01*
G03X526771Y1557848I-2230J-503D01*
G03X525684Y1558153I-1142J-1980D01*
G01X525624D01*
G02X525426Y1558320I-1J200D01*
G01X525336Y1558866D01*
G02X525397Y1559044I197J32D01*
G01X525404Y1559051D01*
X525433Y1559061D01*
X525526Y1559076D01*
X525547Y1559075D01*
G03X525609Y1559073I93J1910D01*
G01X525632D01*
G03X525633Y1562897I-2J1912D01*
G01X525628D01*
G03X525528Y1562894I7J-1912D01*
G01X525510D01*
G02X525410Y1562921I0J200D01*
G01X525386Y1562935D01*
X525163Y1563148D01*
G02X525100Y1563293I137J146D01*
G01Y1563794D01*
G02X525146Y1563921I200J-1D01*
G01X525156Y1563933D01*
X525404Y1564169D01*
X525446Y1564183D01*
X525484Y1564196D01*
X525523Y1564194D01*
G03X525609Y1564191I110J1909D01*
G01X525632D01*
G03X525633Y1568015I-2J1912D01*
G01X525628D01*
G03X525528Y1568012I7J-1912D01*
G01X525510D01*
G02X525410Y1568039I0J200D01*
G01X525386Y1568053D01*
X525163Y1568266D01*
G02X525100Y1568411I137J146D01*
G01Y1574030D01*
G02X525146Y1574157I200J-1D01*
G01X525156Y1574169D01*
X525404Y1574405D01*
X525446Y1574419D01*
X525484Y1574432D01*
X525523Y1574430D01*
G03X525609Y1574427I110J1909D01*
G01X525632D01*
G03X525633Y1578251I-2J1912D01*
G01X525628D01*
G03X525528Y1578248I7J-1912D01*
G01X525510D01*
G02X525410Y1578275I0J200D01*
G01X525386Y1578289D01*
X525163Y1578502D01*
G02X525100Y1578647I137J146D01*
G01Y1579148D01*
G02X525146Y1579275I200J-1D01*
G01X525156Y1579287D01*
X525404Y1579523D01*
X525446Y1579537D01*
X525484Y1579550D01*
X525523Y1579548D01*
G03X525609Y1579545I110J1909D01*
G01X525632D01*
G03X525633Y1583369I-2J1912D01*
G01X525628D01*
G03X525528Y1583366I7J-1912D01*
G01X525510D01*
G02X525410Y1583393I0J200D01*
G01X525386Y1583407D01*
X525163Y1583620D01*
G02X525100Y1583765I137J146D01*
G01Y1589384D01*
G02X525146Y1589511I200J-1D01*
G01X525156Y1589523D01*
X525404Y1589759D01*
X525446Y1589773D01*
X525484Y1589786D01*
X525523Y1589784D01*
G03X525609Y1589781I110J1909D01*
G01X525632D01*
G03X525633Y1593605I-2J1912D01*
G01X525628D01*
G03X525528Y1593602I7J-1912D01*
G01X525510D01*
G02X525410Y1593629I0J200D01*
G01X525386Y1593643D01*
X525163Y1593856D01*
G02X525100Y1594001I137J146D01*
G01Y1594502D01*
G02X525146Y1594629I200J-1D01*
G01X525156Y1594641D01*
X525404Y1594877D01*
X525446Y1594891D01*
X525484Y1594904D01*
X525523Y1594902D01*
G03X525609Y1594899I110J1909D01*
G01X525632D01*
G03X527542Y1596811I-2J1912D01*
G03X525630Y1598723I-1912J0D01*
G01X525628D01*
G03X524920Y1598587I0J-1912D01*
G01X524883Y1598579D01*
X524828D01*
X524777Y1598587D01*
X524764Y1598591D01*
X524690Y1598613D01*
G02X524678Y1598617I57J192D01*
G02X524628Y1598644I69J188D01*
G01X524597Y1598702D01*
G03X523916Y1599616I-3456J-1864D01*
G01X521619Y1601913D01*
G03X520657Y1602620I-2779J-2774D01*
G02X520566Y1602717I92J178D01*
G03X516970Y1605068I-3596J-1575D01*
G01X516969D01*
G03X515208Y1604651I0J-3927D01*
G01X515176Y1604655D01*
X515159Y1604660D01*
G03X514759Y1604717I-396J-1346D01*
G01X514755D01*
G03X513353Y1603315I0J-1402D01*
G01Y1603313D01*
G03X513427Y1602861I1403J-2D01*
G01X513430Y1602844D01*
G03X513042Y1601142I3539J-1702D01*
G01Y1599638D01*
G03X513173Y1598633I3927J1D01*
G01X513180Y1598582D01*
X513173Y1598531D01*
G03X513094Y1598160I3796J-1002D01*
G01X513086Y1598110D01*
X513041Y1598052D01*
X513031Y1598040D01*
X513021Y1598030D01*
G02X512954Y1597986I-141J142D01*
G01X512868Y1597951D01*
X512866D01*
X512707Y1597887D01*
G02X512636Y1597872I-76J185D01*
G01X512557Y1597932D01*
G03X511995Y1598289I-2379J-3124D01*
G02X511904Y1598386I92J178D01*
G03X508307Y1600738I-3597J-1575D01*
G03X506952Y1600496I2J-3927D01*
G01X506900Y1600509D01*
G03X506885Y1600517I-819J-1518D01*
G01X506879Y1600520D01*
G03X506094Y1600709I-785J-1536D01*
G01X506092D01*
G03X505852Y1600692I2J-1725D01*
G01X505804Y1600685D01*
X505760Y1600700D01*
G02X505683Y1600748I65J189D01*
G01X504557Y1601874D01*
G03X504531Y1601900I-2765J-2739D01*
G01X504465Y1601966D01*
G03X504285Y1602135I-2752J-2751D01*
G03X503255Y1602788I-2573J-2920D01*
G01X503223Y1602802D01*
X503219Y1602806D01*
X503174Y1602866D01*
G03X499646Y1605068I-3528J-1725D01*
G01X499644D01*
G03X497943Y1604680I1J-3926D01*
G01X497884Y1604652D01*
X497861D01*
X497830Y1604660D01*
X497828Y1604661D01*
X497802Y1604668D01*
G03X497436Y1604717I-367J-1353D01*
G01X497432D01*
G03X496030Y1603320I0J-1402D01*
G01Y1603314D01*
G03X496094Y1602896I1402J1D01*
G01X496100Y1602877D01*
X496104Y1602838D01*
Y1602837D01*
G03X495720Y1601144I3542J-1694D01*
G01Y1599635D01*
G03X495846Y1598650I3926J2D01*
G01X495858Y1598604D01*
X495852Y1598577D01*
Y1598574D01*
X495846Y1598550D01*
X495835Y1598503D01*
X495746Y1598393D01*
X495736Y1598384D01*
X495708Y1598357D01*
X495503Y1598267D01*
X495501D01*
X495465Y1598249D01*
X495418D01*
G02X495327Y1598272I2J200D01*
G01X495326Y1598273D01*
G03X494930Y1598454I-1813J-3444D01*
G03X494506Y1598593I-1422J-3623D01*
G01X494503Y1598594D01*
X494472Y1598616D01*
G03X490985Y1600738I-3487J-1804D01*
G03X489288Y1600352I1J-3927D01*
G01X489268Y1600342D01*
X489224Y1600332D01*
X489159D01*
X489134Y1600339D01*
G03X488775Y1600386I-360J-1355D01*
G01X488748D01*
X488719Y1600385D01*
G03X488604Y1600375I64J-1400D01*
G01X488598D01*
X488569Y1600372D01*
X488485Y1600402D01*
X486973Y1601913D01*
G03X486445Y1602356I-2778J-2775D01*
G01X486431Y1602366D01*
X486272Y1602525D01*
G02X486228Y1602592I142J141D01*
G01X486214Y1602626D01*
Y1602671D01*
G03X486155Y1602812I-200J-1D01*
G01X485449Y1603518D01*
X485441Y1603528D01*
G03X484712Y1604258I-3119J-2385D01*
G01X484702Y1604266D01*
X483993Y1604974D01*
G03X483852Y1605033I-142J-141D01*
G01X482850D01*
X482837Y1605035D01*
G03X482323Y1605068I-508J-3893D01*
G03X481809Y1605035I-6J-3926D01*
G01X481796Y1605033D01*
X480794D01*
G03X480653Y1604974I1J-200D01*
G01X480444Y1604766D01*
G02X480303Y1604708I-141J142D01*
G01X480278D01*
X480268Y1604709D01*
G03X480113Y1604717I-150J-1395D01*
G01X480109D01*
G03X478707Y1603315I0J-1402D01*
G01Y1603312D01*
G03X478717Y1603148I1402J3D01*
G01Y1603144D01*
G02X478710Y1603065I-199J-22D01*
G01X478708Y1603059D01*
X478707Y1603057D01*
G02X478659Y1602980I-189J65D01*
G01X478491Y1602812D01*
G03X478432Y1602671I141J-142D01*
G01Y1601669D01*
X478430Y1601656D01*
G03X478396Y1601142I3868J-514D01*
G01Y1599638D01*
G03X478430Y1599124I3902J0D01*
G01X478432Y1599111D01*
Y1598170D01*
G02X478388Y1598045I-200J0D01*
G01X478357Y1598014D01*
G02X478334Y1597998I-125J156D01*
G01X478304Y1597983D01*
X478155Y1597924D01*
X478154D01*
X478054Y1597885D01*
X478052D01*
X478035Y1597877D01*
X478032Y1597876D01*
X478021Y1597878D01*
G02X477934Y1597915I33J197D01*
G01X477912Y1597932D01*
G03X477784Y1598025I-2371J-3129D01*
G01X477770Y1598035D01*
X477611Y1598194D01*
G02X477567Y1598261I142J141D01*
G01X477553Y1598295D01*
Y1598340D01*
G03X477494Y1598481I-200J-1D01*
G01X476786Y1599190D01*
X476778Y1599200D01*
G03X476051Y1599927I-3116J-2389D01*
G01X476041Y1599935D01*
X475332Y1600643D01*
G03X475191Y1600702I-142J-141D01*
G01X474189D01*
X474176Y1600704D01*
G03X473148I-514J-3868D01*
G01X473135Y1600702D01*
X472133D01*
G03X471992Y1600643I1J-200D01*
G01X471800Y1600451D01*
G02X471770Y1600426I-142J140D01*
G01X471718Y1600391D01*
X471717D01*
X471714Y1600389D01*
G02X471627Y1600375I-75J186D01*
G01X471610Y1600377D01*
G03X471450Y1600386I-159J-1393D01*
G01X471425D01*
X471396Y1600385D01*
G03X471281Y1600375I64J-1400D01*
G01X471275D01*
X471246Y1600372D01*
X471162Y1600402D01*
X469650Y1601913D01*
G03X469121Y1602357I-2779J-2774D01*
G01X469107Y1602367D01*
X468949Y1602525D01*
G02X468891Y1602666I142J141D01*
G01Y1602671D01*
G03X468832Y1602812I-200J-1D01*
G01X468124Y1603521D01*
X468116Y1603531D01*
G03X467389Y1604258I-3116J-2389D01*
G01X467379Y1604266D01*
X466670Y1604974D01*
G03X466529Y1605033I-142J-141D01*
G01X465527D01*
X465514Y1605035D01*
G03X465000Y1605068I-508J-3893D01*
G03X464486Y1605035I-6J-3926D01*
G01X464473Y1605033D01*
X463471D01*
G03X463330Y1604974I1J-200D01*
G01X463123Y1604767D01*
G02X463071Y1604729I-143J140D01*
G01X463039Y1604713D01*
X462982Y1604704D01*
X462953Y1604707D01*
G03X462808Y1604717I-169J-1392D01*
G01X462780D01*
G03X461384Y1603320I6J-1402D01*
G01Y1603318D01*
G03Y1603314I1402J-2D01*
G01Y1603313D01*
G03X461394Y1603146I1402J0D01*
G01X461400Y1603099D01*
X461385Y1603057D01*
G02X461338Y1602982I-189J66D01*
G01X461168Y1602812D01*
G03X461109Y1602671I141J-142D01*
G01Y1601669D01*
X461107Y1601656D01*
G03X461074Y1601142I3893J-508D01*
G01Y1599638D01*
G03X461107Y1599124I3926J-6D01*
G01X461109Y1599111D01*
Y1598179D01*
G02X461084Y1598083I-200J1D01*
G01X461072Y1598063D01*
G02X460988Y1597989I-169J107D01*
G01X460762Y1597895D01*
X460761D01*
X460734Y1597884D01*
X460677Y1597878D01*
X460653Y1597882D01*
G03X460461Y1598025I-2440J-3076D01*
G01X460447Y1598035D01*
X460288Y1598194D01*
G02X460244Y1598261I142J141D01*
G01X460230Y1598295D01*
Y1598340D01*
G03X460171Y1598481I-200J-1D01*
G01X459463Y1599190D01*
X459455Y1599200D01*
G03X458728Y1599927I-3116J-2389D01*
G01X458718Y1599935D01*
X458009Y1600643D01*
G03X457868Y1600702I-142J-141D01*
G01X456866D01*
X456853Y1600704D01*
G03X455825I-514J-3868D01*
G01X455812Y1600702D01*
X454810D01*
G03X454669Y1600643I1J-200D01*
G01X454477Y1600451D01*
G02X454447Y1600426I-142J140D01*
G01X454395Y1600391D01*
X454394D01*
X454391Y1600389D01*
G02X454304Y1600375I-75J186D01*
G01X454287Y1600377D01*
G03X454139Y1600386I-159J-1393D01*
G01X454120D01*
G03X452723Y1599001I5J-1402D01*
G01Y1598978D01*
G03X452733Y1598816I1402J5D01*
G01Y1598814D01*
G02X452684Y1598659I-199J-22D01*
G01X452507Y1598481D01*
G03X452448Y1598340I141J-142D01*
G01Y1597338D01*
X452446Y1597325D01*
G03X452412Y1596811I3868J-514D01*
G01Y1595307D01*
G03X452446Y1594793I3902J0D01*
G01X452448Y1594780D01*
Y1593723D01*
X452446Y1593710D01*
G03X452412Y1593196I3868J-514D01*
G01Y1591693D01*
G03X452446Y1591179I3902J0D01*
G01X452448Y1591166D01*
Y1590164D01*
G03X452507Y1590023I200J1D01*
G01X452588Y1589942D01*
G02X452637Y1589862I-141J-142D01*
G01X452651Y1589817D01*
X452643Y1589769D01*
G03X452623Y1589525I1482J-244D01*
G01Y1589522D01*
G03X453329Y1588248I1502J0D01*
G01X453344Y1588239D01*
G03X453464Y1588173I783J1282D01*
G03X454013Y1588024I661J1349D01*
G03X454106Y1588020I111J1498D01*
G01X454121D01*
G03X454127I3J1502D01*
G01X454129D01*
G03X454172Y1588021I-13J1502D01*
G01X454178D01*
G02X454376Y1587849I0J-200D01*
G01X454382Y1587807D01*
X454361Y1587722D01*
X454347Y1587697D01*
X454346Y1587696D01*
G03X454053Y1586622I1993J-1121D01*
G01Y1586580D01*
X454052Y1586558D01*
G03X455329Y1584523I2287J17D01*
G03X455359Y1584508I1038J2038D01*
G01X455474Y1584328D01*
Y1584070D01*
G02X455274Y1583870I-200J0D01*
G01X454929D01*
G03X454726Y1583667I0J-203D01*
G01Y1582555D01*
G02X454716Y1582495I-200J2D01*
G01X454697Y1582437D01*
X454686Y1582419D01*
G03X454427Y1581459I1653J-961D01*
G01Y1581457D01*
G03X454686Y1580496I1912J0D01*
G01X454696Y1580479D01*
X454716Y1580418D01*
G02X454726Y1580358I-190J-62D01*
G01Y1577437D01*
G02X454716Y1577377I-200J2D01*
G01X454697Y1577319D01*
X454686Y1577301D01*
G03X454427Y1576341I1653J-961D01*
G01Y1576339D01*
G03X454686Y1575378I1912J0D01*
G01X454696Y1575361D01*
X454716Y1575300D01*
G02X454726Y1575240I-190J-62D01*
G01Y1574129D01*
G03X454929Y1573926I203J0D01*
G01X455274D01*
G02X455474Y1573726I0J-200D01*
G01Y1573468D01*
X455360Y1573288D01*
G03Y1569153I978J-2067D01*
G01X455474Y1568973D01*
Y1568716D01*
G02X455274Y1568516I-200J0D01*
G01X454929D01*
G03X454726Y1568313I0J-203D01*
G01Y1567201D01*
G02X454716Y1567141I-200J2D01*
G01X454697Y1567083D01*
X454686Y1567065D01*
G03X454427Y1566105I1653J-961D01*
G01Y1566103D01*
G03X454686Y1565142I1912J0D01*
G01X454696Y1565125D01*
X454716Y1565064D01*
G02X454726Y1565004I-190J-62D01*
G01Y1562083D01*
G02X454716Y1562023I-200J2D01*
G01X454697Y1561965D01*
X454686Y1561947D01*
G03X454427Y1560987I1653J-961D01*
G01Y1560985D01*
G03X454686Y1560024I1912J0D01*
G01X454696Y1560007D01*
X454716Y1559946D01*
G02X454726Y1559886I-190J-62D01*
G01Y1558775D01*
G03X454929Y1558572I203J0D01*
G01X455567D01*
G02X455753Y1558446I0J-200D01*
G03X455769Y1558405I3665J1407D01*
G01X455803Y1558322D01*
G02X455800Y1558161I-185J-77D01*
G01X455775Y1558108D01*
X455743Y1558086D01*
X455717Y1558068D01*
X455676Y1558055D01*
X455675Y1558054D01*
G03X454053Y1555867I663J-2187D01*
G03X456339Y1553581I2286J0D01*
G01X456342D01*
G03X456871Y1553643I0J2286D01*
G01X456882Y1553646D01*
X456904Y1553649D01*
G02X457114Y1553527I25J-199D01*
G01X458328Y1550601D01*
X458490Y1550210D01*
G03X458563Y1550121I185J77D01*
G01X459430Y1549542D01*
X459432Y1549540D01*
G03X459494Y1549498I2214J3201D01*
G01X460099Y1549093D01*
G02X460184Y1548966I-111J-166D01*
G01X460300Y1548385D01*
X460302Y1548381D01*
X461516Y1547570D01*
X461520Y1547568D01*
G03X461725Y1547428I2297J3143D01*
G01X461729Y1547426D01*
X462745Y1546748D01*
X463090Y1546518D01*
G03X463160Y1546472I2173J3230D01*
G01X463162Y1546471D01*
X463996Y1545913D01*
X464237Y1545752D01*
X464427Y1545625D01*
X465291Y1545048D01*
X465293Y1545047D01*
G03X465331Y1545021I2216J3199D01*
G01X465332D01*
X465442Y1544947D01*
X465443Y1544945D01*
X466636Y1544148D01*
X466637D01*
X466779Y1544053D01*
G03X466814Y1544030I2155J3240D01*
G01X466815Y1544029D01*
X468119Y1543157D01*
X468120D01*
X469026Y1542553D01*
X469027Y1542552D01*
X469134Y1542480D01*
X469135Y1542478D01*
X470328Y1541681D01*
X470329D01*
X470471Y1541586D01*
G03X470506Y1541563I2155J3240D01*
G01X470507Y1541562D01*
X471811Y1540690D01*
X471812D01*
X472721Y1540084D01*
X472828Y1540012D01*
Y1540008D01*
X474066Y1539184D01*
X474163Y1539119D01*
G03X474198Y1539096I2155J3240D01*
G01X474199Y1539095D01*
X475073Y1538510D01*
Y1538509D01*
X475368Y1538313D01*
X475370D01*
X475503Y1538223D01*
X475504D01*
X476357Y1537654D01*
X476359Y1537653D01*
G03X476407Y1537620I2228J3190D01*
G01X476408D01*
X477855Y1536652D01*
G03X477890Y1536629I2154J3240D01*
G01X477891Y1536628D01*
X479129Y1535800D01*
G03X479279Y1535770I111J166D01*
G01X479779Y1535871D01*
G02X479904Y1535855I38J-196D01*
G01X479930Y1535843D01*
X480167Y1535685D01*
X480577Y1535411D01*
G03X480612Y1535392I113J166D01*
G01X480916Y1535266D01*
X480917D01*
X484003Y1533987D01*
X517042Y1520299D01*
X517060Y1520291D01*
X521619Y1517269D01*
X523119Y1516270D01*
G02X523146Y1516248I-112J-165D01*
G01X523198Y1516196D01*
X523442Y1515954D01*
G02X523493Y1515843I-148J-135D01*
G02X523494Y1515819I-199J-20D01*
G01Y1515737D01*
X523482Y1515704D01*
G03X523351Y1515106I2148J-784D01*
G01X523347Y1515052D01*
G03X523343Y1514922I2283J-135D01*
G03X524886Y1512758I2289J0D01*
G01X524913Y1512749D01*
X524935Y1512734D01*
G02X524977Y1512694I-116J-163D01*
G01X525035Y1512621D01*
X525036Y1512620D01*
G02X525079Y1512503I-157J-124D01*
G01X525080Y1512425D01*
Y1512423D01*
X525081Y1512324D01*
G02X524398Y1512036I-400J-5D01*
G01X524371Y1512063D01*
X524361Y1512077D01*
G03X523916Y1512608I-3220J-2246D01*
G01X521619Y1514905D01*
G03X521091Y1515348I-2778J-2775D01*
G01X521077Y1515358D01*
X520918Y1515517D01*
G02X520874Y1515584I142J141D01*
G01X520860Y1515618D01*
Y1515663D01*
G03X520801Y1515804I-200J-1D01*
G01X520093Y1516513D01*
X520085Y1516523D01*
G03X519358Y1517250I-3116J-2389D01*
G01X519348Y1517258D01*
X518639Y1517966D01*
G03X518498Y1518025I-142J-141D01*
G01X517496D01*
X517483Y1518027D01*
G03X516969Y1518060I-508J-3893D01*
G03X516455Y1518027I-6J-3926D01*
G01X516442Y1518025D01*
X515440D01*
G03X515299Y1517966I1J-200D01*
G01X515090Y1517758D01*
G02X514949Y1517700I-141J142D01*
G01X514924D01*
X514914Y1517701D01*
G03X514759Y1517709I-150J-1395D01*
G01X514755D01*
G03X513353Y1516307I0J-1402D01*
G01Y1516304D01*
G03X513363Y1516140I1402J3D01*
G01Y1516136D01*
G02X513356Y1516057I-199J-22D01*
G01X513354Y1516051D01*
X513353Y1516049D01*
G02X513305Y1515972I-189J65D01*
G01X513137Y1515804D01*
G03X513078Y1515663I141J-142D01*
G01Y1514661D01*
X513076Y1514648D01*
G03X513042Y1514134I3868J-514D01*
G01Y1512630D01*
G03X513076Y1512116I3902J0D01*
G01X513078Y1512103D01*
Y1511165D01*
G02X513033Y1511039I-200J0D01*
G02X513020Y1511024I-157J123D01*
G01X513015Y1511019D01*
X512985Y1510990D01*
X512746Y1510893D01*
X512732Y1510888D01*
G02X512624Y1510874I-79J184D01*
G01X512559Y1510923D01*
G03X512427Y1511019I-2375J-3127D01*
G01X512413Y1511030D01*
X512256Y1511187D01*
G02X512198Y1511328I142J141D01*
G01Y1511333D01*
G03X512139Y1511474I-200J-1D01*
G01X511431Y1512183D01*
X511423Y1512193D01*
G03X510696Y1512920I-3116J-2389D01*
G01X510686Y1512928D01*
X509977Y1513636D01*
G03X509836Y1513695I-142J-141D01*
G01X508834D01*
X508821Y1513697D01*
G03X508307Y1513730I-508J-3893D01*
G03X507793Y1513697I-6J-3926D01*
G01X507780Y1513695D01*
X506778D01*
G03X506637Y1513636I1J-200D01*
G01X506429Y1513428D01*
G02X506377Y1513390I-143J140D01*
G01X506345Y1513374D01*
X506287Y1513365D01*
X506279Y1513366D01*
G03X506091Y1513378I-183J-1390D01*
G01X506082D01*
G03X505938Y1513370I6J-1402D01*
G01X505893Y1513365D01*
X505808Y1513394D01*
X504296Y1514905D01*
G03X503768Y1515348I-2778J-2775D01*
G01X503754Y1515358D01*
X503595Y1515517D01*
G02X503551Y1515584I142J141D01*
G01X503537Y1515618D01*
Y1515663D01*
G03X503478Y1515804I-200J-1D01*
G01X502770Y1516513D01*
X502762Y1516523D01*
G03X502035Y1517250I-3116J-2389D01*
G01X502025Y1517258D01*
X501316Y1517966D01*
G03X501175Y1518025I-142J-141D01*
G01X500173D01*
X500160Y1518027D01*
G03X499646Y1518060I-508J-3893D01*
G03X499132Y1518027I-6J-3926D01*
G01X499119Y1518025D01*
X498117D01*
G03X497976Y1517966I1J-200D01*
G01X497769Y1517759D01*
G02X497717Y1517721I-143J140D01*
G01X497685Y1517705D01*
X497628Y1517696D01*
X497599Y1517699D01*
G03X497454Y1517709I-169J-1392D01*
G01X497426D01*
G03X496030Y1516312I6J-1402D01*
G01Y1516310D01*
G03Y1516306I1402J-2D01*
G01Y1516305D01*
G03X496040Y1516138I1402J0D01*
G01X496046Y1516091D01*
X496031Y1516049D01*
G02X495984Y1515974I-189J66D01*
G01X495814Y1515804D01*
G03X495755Y1515663I141J-142D01*
G01Y1514661D01*
X495753Y1514648D01*
G03X495720Y1514134I3893J-508D01*
G01Y1512630D01*
G03X495753Y1512116I3926J-6D01*
G01X495755Y1512103D01*
Y1511165D01*
G02X495754Y1511150I-200J6D01*
G02X495639Y1510983I-199J14D01*
G01X495458Y1510909D01*
X495456D01*
X495409Y1510889D01*
G02X495300Y1510875I-79J184D01*
G01X495235Y1510925D01*
G03X495107Y1511018I-2371J-3129D01*
G01X495093Y1511028D01*
X494934Y1511187D01*
G02X494890Y1511254I142J141D01*
G01X494876Y1511288D01*
Y1511333D01*
G03X494817Y1511474I-200J-1D01*
G01X494111Y1512180D01*
X494103Y1512190D01*
G03X493374Y1512920I-3119J-2385D01*
G01X493364Y1512928D01*
X492655Y1513636D01*
G03X492514Y1513695I-142J-141D01*
G01X491512D01*
X491499Y1513697D01*
G03X490985Y1513730I-508J-3893D01*
G03X490471Y1513697I-6J-3926D01*
G01X490458Y1513695D01*
X489456D01*
G03X489315Y1513636I1J-200D01*
G01X489107Y1513428D01*
G02X489055Y1513390I-143J140D01*
G01X489023Y1513374D01*
X488966Y1513365D01*
X488945Y1513367D01*
X488938Y1513368D01*
G03X488776Y1513378I-167J-1392D01*
G01X488766D01*
G03X488615Y1513370I-1J-1402D01*
G01X488570Y1513365D01*
X488485Y1513394D01*
X486973Y1514905D01*
G03X486445Y1515348I-2778J-2775D01*
G01X486431Y1515358D01*
X486272Y1515517D01*
G02X486228Y1515584I142J141D01*
G01X486214Y1515618D01*
Y1515663D01*
G03X486155Y1515804I-200J-1D01*
G01X485447Y1516513D01*
X485439Y1516523D01*
G03X484712Y1517250I-3116J-2389D01*
G01X484702Y1517258D01*
X483993Y1517966D01*
G03X483852Y1518025I-142J-141D01*
G01X482850D01*
X482837Y1518027D01*
G03X482323Y1518060I-508J-3893D01*
G03X481809Y1518027I-6J-3926D01*
G01X481796Y1518025D01*
X480794D01*
G03X480653Y1517966I1J-200D01*
G01X480444Y1517758D01*
G02X480303Y1517700I-141J142D01*
G01X480278D01*
X480268Y1517701D01*
G03X480113Y1517709I-150J-1395D01*
G01X480109D01*
G03X478707Y1516307I0J-1402D01*
G01Y1516304D01*
G03X478717Y1516140I1402J3D01*
G01Y1516136D01*
G02X478710Y1516057I-199J-22D01*
G01X478708Y1516051D01*
X478707Y1516049D01*
G02X478659Y1515972I-189J65D01*
G01X478491Y1515804D01*
G03X478432Y1515663I141J-142D01*
G01Y1514661D01*
X478430Y1514648D01*
G03X478396Y1514134I3868J-514D01*
G01Y1512630D01*
G03X478430Y1512116I3902J0D01*
G01X478432Y1512103D01*
Y1511165D01*
G02X478318Y1510985I-200J0D01*
G01X478244Y1510953D01*
X478242D01*
X478107Y1510898D01*
X478105D01*
X478080Y1510888D01*
X477993D01*
G02X477957Y1510891I-1J200D01*
G01X477907Y1510929D01*
G03X477784Y1511018I-2363J-3136D01*
G01X477770Y1511028D01*
X477611Y1511187D01*
G02X477567Y1511254I142J141D01*
G01X477553Y1511288D01*
Y1511333D01*
G03X477494Y1511474I-200J-1D01*
G01X476786Y1512183D01*
X476778Y1512193D01*
G03X476051Y1512920I-3116J-2389D01*
G01X476041Y1512928D01*
X475332Y1513636D01*
G03X475191Y1513695I-142J-141D01*
G01X474189D01*
X474176Y1513697D01*
G03X473662Y1513730I-508J-3893D01*
G03X473148Y1513697I-6J-3926D01*
G01X473135Y1513695D01*
X472133D01*
G03X471992Y1513636I1J-200D01*
G01X471784Y1513428D01*
G02X471732Y1513390I-143J140D01*
G01X471700Y1513374D01*
X471643Y1513365D01*
X471622Y1513367D01*
X471615Y1513368D01*
G03X471453Y1513378I-167J-1392D01*
G01X471443D01*
G03X471292Y1513370I-1J-1402D01*
G01X471247Y1513365D01*
X471162Y1513394D01*
X469650Y1514905D01*
G03X469122Y1515348I-2778J-2775D01*
G01X469108Y1515358D01*
X468949Y1515517D01*
G02X468905Y1515584I142J141D01*
G01X468891Y1515618D01*
Y1515663D01*
G03X468832Y1515804I-200J-1D01*
G01X468124Y1516513D01*
X468116Y1516523D01*
G03X467389Y1517250I-3116J-2389D01*
G01X467379Y1517258D01*
X466670Y1517966D01*
G03X466529Y1518025I-142J-141D01*
G01X465527D01*
X465514Y1518027D01*
G03X465000Y1518060I-508J-3893D01*
G03X464486Y1518027I-6J-3926D01*
G01X464473Y1518025D01*
X463471D01*
G03X463330Y1517966I1J-200D01*
G01X463123Y1517759D01*
G02X463071Y1517721I-143J140D01*
G01X463039Y1517705D01*
X462982Y1517696D01*
X462953Y1517699D01*
G03X462808Y1517709I-169J-1392D01*
G01X462780D01*
G03X461384Y1516312I6J-1402D01*
G01Y1516310D01*
G03Y1516306I1402J-2D01*
G01Y1516305D01*
G03X461394Y1516138I1402J0D01*
G01X461400Y1516091D01*
X461385Y1516049D01*
G02X461338Y1515974I-189J66D01*
G01X461168Y1515804D01*
G03X461109Y1515663I141J-142D01*
G01Y1514661D01*
X461107Y1514648D01*
G03X461074Y1514134I3893J-508D01*
G01Y1512630D01*
G03X461107Y1512116I3926J-6D01*
G01X461109Y1512103D01*
Y1511163D01*
G02X460991Y1510981I-200J0D01*
G01X460825Y1510914D01*
X460823D01*
X460760Y1510888D01*
G02X460654Y1510876I-75J185D01*
G01X460589Y1510925D01*
G03X460461Y1511018I-2371J-3129D01*
G01X460447Y1511028D01*
X460288Y1511187D01*
G02X460244Y1511254I142J141D01*
G01X460230Y1511288D01*
Y1511333D01*
G03X460171Y1511474I-200J-1D01*
G01X459465Y1512180D01*
X459457Y1512190D01*
G03X458725Y1512922I-3118J-2386D01*
G01X458715Y1512930D01*
X458009Y1513636D01*
G03X457868Y1513695I-142J-141D01*
G01X456866D01*
X456853Y1513697D01*
G03X456339Y1513730I-508J-3893D01*
G03X455825Y1513697I-6J-3926D01*
G01X455812Y1513695D01*
X454810D01*
G03X454669Y1513636I1J-200D01*
G01X454476Y1513443D01*
G02X454446Y1513418I-142J140D01*
G01X454394Y1513383D01*
X454393D01*
X454390Y1513381D01*
G02X454303Y1513367I-75J186D01*
G01X454286Y1513369D01*
G03X454125Y1513378I-159J-1393D01*
G03X452723Y1511976I0J-1402D01*
G01Y1511970D01*
G03X452732Y1511807I1403J-4D01*
G01Y1511806D01*
G02X452675Y1511643I-199J-22D01*
G01X452507Y1511474D01*
G03X452448Y1511333I141J-142D01*
G01Y1510331D01*
X452446Y1510318D01*
G03X452412Y1509804I3868J-514D01*
G01Y1508300D01*
G03X452446Y1507786I3902J0D01*
G01X452448Y1507773D01*
Y1506716D01*
X452446Y1506703D01*
G03X452412Y1506189I3868J-514D01*
G01Y1504685D01*
G03X452446Y1504171I3902J0D01*
G01X452448Y1504158D01*
Y1503156D01*
G03X452507Y1503015I200J1D01*
G01X452588Y1502934D01*
G02X452637Y1502854I-141J-142D01*
G01X452651Y1502809D01*
X452643Y1502761D01*
G03X452623Y1502517I1482J-244D01*
G01Y1502514D01*
G03X453329Y1501240I1502J0D01*
G01X453344Y1501231D01*
G03X453464Y1501165I783J1282D01*
G03X454013Y1501016I661J1349D01*
G03X454106Y1501012I111J1498D01*
G01X454121D01*
G03X454127I3J1502D01*
G01X454129D01*
G03X454172Y1501013I-13J1502D01*
G01X454178D01*
G02X454376Y1500841I0J-200D01*
G01X454382Y1500799D01*
X454361Y1500714D01*
X454347Y1500689D01*
G03X454088Y1499967I1992J-1122D01*
G03X454058Y1499725I2250J-402D01*
G01X454055Y1499677D01*
G03X454052Y1499567I2284J-117D01*
G01Y1499487D01*
X454055Y1499460D01*
Y1499454D01*
G03X455229Y1497568I2283J113D01*
G01X455260Y1497552D01*
G03X455265Y1497549I1179J1959D01*
G03X455273Y1497545I93J177D01*
G03X455275Y1497544I1023J2044D01*
G01X455276Y1497543D01*
G03X455362Y1497498I1103J2003D01*
G01X455388Y1497485D01*
X455413Y1497462D01*
G02X455448Y1497421I-133J-149D01*
G01X455459Y1497404D01*
X455474Y1497350D01*
Y1496930D01*
G02X455324Y1496862I-150J131D01*
G01X454929D01*
G03X454726Y1496659I0J-203D01*
G01Y1495548D01*
G02X454716Y1495487I-200J1D01*
G01X454698Y1495434D01*
X454688Y1495416D01*
G03X454426Y1494450I1650J-966D01*
G01Y1494448D01*
G03X454688Y1493483I1913J1D01*
G01X454699Y1493464D01*
X454716Y1493411D01*
X454726Y1493381D01*
Y1490430D01*
G02X454716Y1490369I-200J1D01*
G01X454698Y1490316D01*
X454688Y1490298D01*
G03X454426Y1489332I1650J-966D01*
G01Y1489330D01*
G03X454688Y1488365I1913J1D01*
G01X454699Y1488346D01*
X454716Y1488293D01*
X454726Y1488263D01*
Y1487121D01*
G03X454929Y1486918I203J0D01*
G01X455324D01*
G02X455474Y1486850I0J-199D01*
G01Y1486460D01*
G02X455446Y1486358I-200J0D01*
G01X455443Y1486353D01*
X455420Y1486333D01*
X455419Y1486332D01*
X455357Y1486278D01*
X455333Y1486266D01*
X455332D01*
G03Y1482160I1008J-2053D01*
G01X455333D01*
X455357Y1482148D01*
X455418Y1482095D01*
G02X455424Y1482089I-138J-144D01*
G02X455457Y1482049I-136J-146D01*
G01X455474Y1482021D01*
Y1481576D01*
G02X455324Y1481508I-150J131D01*
G01X454929D01*
G03X454726Y1481305I0J-203D01*
G01Y1480352D01*
G02X454725Y1480334I-200J2D01*
G01X454718Y1480291D01*
G02X454713Y1480270I-197J36D01*
G01X454699Y1480219D01*
X454680Y1480181D01*
X454663Y1480149D01*
X454659Y1480142D01*
G03X454358Y1479096I1679J-1050D01*
G01Y1479093D01*
G03X454476Y1478421I1981J1D01*
G01X454482Y1478405D01*
X454485Y1478390D01*
X454499Y1478354D01*
X454492Y1478304D01*
G02X454454Y1478212I-198J28D01*
G01X454315Y1478025D01*
X454306Y1478016D01*
X454304Y1478013D01*
X454287Y1477996D01*
G02X454146Y1477938I-141J142D01*
G01X454123D01*
G03X454121I-1J-1402D01*
G03X453568Y1477823I3J-1402D01*
G01X453566Y1477822D01*
X453547Y1477814D01*
X453505Y1477805D01*
G03X453473Y1477795I43J-195D01*
G01X453451Y1477786D01*
X453445Y1477784D01*
G03X453375Y1477738I73J-187D01*
G01X453334Y1477697D01*
X453314Y1477680D01*
X453307Y1477675D01*
G03X452994Y1477365I818J-1139D01*
G03X452723Y1476537I1131J-829D01*
G01Y1476525D01*
G03X452872Y1475906I1401J10D01*
G03X453202Y1475478I1256J627D01*
G01X453218Y1475464D01*
X453273Y1475391D01*
X453287Y1475360D01*
X453289Y1475355D01*
X453305Y1475318D01*
G02X453322Y1475238I-183J-81D01*
G01Y1473242D01*
G02X453317Y1473198I-200J0D01*
G01X453308Y1473165D01*
X453302Y1473138D01*
X453257Y1473056D01*
G02X453223Y1473011I-175J97D01*
G01X453205Y1472993D01*
X453196Y1472986D01*
G03Y1470624I928J-1181D01*
G01X453205Y1470617D01*
X453226Y1470596D01*
G02X453262Y1470547I-141J-142D01*
G01X453300Y1470474D01*
Y1470472D01*
X453322Y1470450D01*
Y1467214D01*
G02X453311Y1467149I-200J0D01*
G01X453299Y1467116D01*
G02X453290Y1467094I-189J65D01*
G01X453246Y1467008D01*
X453216Y1466982D01*
G03X452873Y1466544I911J-1067D01*
G03Y1465282I1252J-631D01*
G03X453206Y1464854I1253J631D01*
G01X453212Y1464849D01*
X453229Y1464832D01*
G02X453269Y1464774I-142J-141D01*
G01X453282Y1464746D01*
X453286Y1464742D01*
X453305Y1464698D01*
G02X453322Y1464618I-183J-81D01*
G01Y1462483D01*
G02X453311Y1462418I-200J0D01*
G01X453299Y1462385D01*
G02X453290Y1462363I-189J65D01*
G01X453246Y1462277D01*
X453216Y1462251D01*
G03X452873Y1461813I911J-1067D01*
G03Y1460551I1252J-631D01*
G03X453206Y1460123I1253J631D01*
G01X453212Y1460118D01*
X453229Y1460101D01*
G02X453269Y1460043I-142J-141D01*
G01X453282Y1460015D01*
X453286Y1460011D01*
X453305Y1459967D01*
G02X453322Y1459887I-183J-81D01*
G01Y1454266D01*
G02X453308Y1454191I-200J-1D01*
G01X453293Y1454155D01*
X436948Y1437810D01*
G03X436889Y1437668I141J-142D01*
G01Y1386098D01*
G02X436869Y1386010I-200J-1D01*
G03X436476Y1384297I3533J-1712D01*
G03X436869Y1382584I3926J-1D01*
G02X436889Y1382496I-180J-87D01*
G01Y1374186D01*
G02X436869Y1374098I-200J-1D01*
G03X436476Y1372385I3533J-1712D01*
G03X436869Y1370672I3926J-1D01*
G02X436889Y1370584I-180J-87D01*
G01Y1360373D01*
X436885Y1360354D01*
G03X436860Y1360099I1277J-254D01*
G03X436885Y1359844I1302J-1D01*
G01X436889Y1359825D01*
Y1348461D01*
X436885Y1348442D01*
G03X436860Y1348187I1277J-254D01*
G03X436885Y1347932I1302J-1D01*
G01X436889Y1347913D01*
Y1335359D01*
G03X436948Y1335217I200J0D01*
G01X444385Y1327780D01*
G03X444527Y1327721I142J141D01*
G01X462389D01*
G02X462491Y1327693I0J-200D01*
G01X510196Y1299098D01*
G03X511075Y1298709I2017J3369D01*
G01X531764Y1292433D01*
G02X531847Y1292383I-59J-191D01*
G01X547155Y1277075D01*
G02X547214Y1276933I-141J-142D01*
G01Y1263759D01*
G02X547155Y1263617I-200J0D01*
G01X537669Y1254131D01*
G02X537527Y1254072I-142J141D01*
G01X378152D01*
G02X378010Y1254131I0J200D01*
G01X373193Y1258948D01*
G02X373134Y1259090I141J142D01*
G01Y1311217D01*
G02X373192Y1311357I200J-1D01*
G01X373234Y1311400D01*
X373417Y1311583D01*
G03X373476Y1311725I-141J142D01*
G01Y1333945D01*
G02X373535Y1334087I200J0D01*
G01X376536Y1337088D01*
G03X376595Y1337230I-141J142D01*
G01Y1341638D01*
G02X376654Y1341780I200J0D01*
G01X377159Y1342285D01*
G03X377218Y1342427I-141J142D01*
G01Y1434161D01*
G03X377159Y1434303I-200J0D01*
G01X361284Y1450178D01*
G02X361275Y1450188I144J139D01*
G01X361268Y1450196D01*
G02X361232Y1450368I158J123D01*
G01X361270Y1450497D01*
X361302Y1450605D01*
G02X361315Y1450637I191J-59D01*
G01X361354Y1450717D01*
G02X361397Y1450775I180J-88D01*
G01X361438Y1450813D01*
G02X361482Y1450845I139J-144D01*
G01X361504Y1450856D01*
X361528Y1450862D01*
G03X362975Y1452717I-466J1855D01*
G03X361063Y1454629I-1912J0D01*
G03X359197Y1453133I0J-1912D01*
G01Y1453131D01*
X359196Y1453130D01*
G02X359146Y1453036I-195J43D01*
G01X359127Y1453017D01*
X359081Y1452990D01*
X359013Y1452972D01*
X359011D01*
X358720Y1452888D01*
G02X358523Y1452939I-55J192D01*
G01X354095Y1457367D01*
G02X354059Y1457417I142J140D01*
G02X354037Y1457508I178J91D01*
G01Y1457578D01*
G02X354044Y1457630I200J0D01*
G01X354050Y1457652D01*
X354063Y1457675D01*
G03X354313Y1458606I-1662J945D01*
G01Y1458638D01*
G03X352555Y1460527I-1912J-17D01*
G02X352427Y1460589I18J199D01*
G01X352345Y1460674D01*
G02X352290Y1460812I145J138D01*
G01Y1461551D01*
G02X352345Y1461689I200J0D01*
G01X352427Y1461774D01*
G02X352555Y1461836I146J-137D01*
G03Y1465646I-154J1905D01*
G02X352427Y1465708I18J199D01*
G01X352345Y1465793D01*
G02X352290Y1465931I145J138D01*
G01Y1471926D01*
X352319Y1471998D01*
X352321Y1472000D01*
G02X352417Y1472054I142J-140D01*
G01X352466Y1472066D01*
X352486Y1472067D01*
G03X354313Y1473977I-85J1910D01*
G03X352484Y1475887I-1912J0D01*
G01X352465Y1475888D01*
X352413Y1475900D01*
G02X352365Y1475920I52J193D01*
G02X352321Y1475954I99J174D01*
G01X352319Y1475956D01*
X352290Y1476028D01*
Y1477044D01*
X352319Y1477116D01*
X352321Y1477118D01*
G02X352417Y1477172I142J-140D01*
G01X352466Y1477184D01*
X352486Y1477185D01*
G03X354313Y1479095I-85J1910D01*
G03X352555Y1481000I-1911J0D01*
G02X352427Y1481062I18J199D01*
G01X352345Y1481147D01*
G02X352290Y1481285I145J138D01*
G01Y1487141D01*
G02X352345Y1487279I200J0D01*
G01X352427Y1487364D01*
G02X352555Y1487426I146J-137D01*
G03Y1491236I-154J1905D01*
G02X352427Y1491298I18J199D01*
G01X352345Y1491383D01*
G02X352290Y1491521I145J138D01*
G01Y1492259D01*
G02X352345Y1492397I200J0D01*
G01X352427Y1492482D01*
G02X352555Y1492544I146J-137D01*
G03X354313Y1494449I-153J1905D01*
G03X352401Y1496361I-1912J0D01*
G01X352400D01*
G03X352110Y1496339I-1J-1912D01*
G02X351900Y1496450I-30J198D01*
G03X351692Y1496826I-3535J-1710D01*
G01X351665Y1496896D01*
G03X350615Y1498062I-1477J-274D01*
G01X350590Y1498070D01*
X349107Y1499552D01*
G03X347542Y1500511I-2777J-2775D01*
G02X347462Y1500560I62J190D01*
G01X347380Y1500642D01*
X346864Y1501159D01*
X346856Y1501169D01*
G03X346129Y1501896I-3116J-2389D01*
G01X346119Y1501904D01*
X345410Y1502612D01*
G03X345269Y1502671I-142J-141D01*
G01X344267D01*
X344254Y1502673D01*
G03X343740Y1502706I-508J-3893D01*
G03X343226Y1502673I-6J-3926D01*
G01X343213Y1502671D01*
X342211D01*
G03X342070Y1502612I1J-200D01*
G01X341946Y1502489D01*
G02X341866Y1502440I-142J141D01*
G01X341821Y1502426D01*
X341773Y1502434D01*
G03X341590Y1502453I-246J-1482D01*
G01X341578D01*
G03X341565Y1502454I-122J-1496D01*
G01X341519D01*
G03X340025Y1500952I8J-1502D01*
G01Y1500946D01*
G03X340045Y1500705I1501J3D01*
G01X340053Y1500657D01*
X340039Y1500612D01*
G02X339990Y1500532I-190J62D01*
G01X339908Y1500450D01*
G03X339849Y1500309I141J-142D01*
G01Y1499307D01*
X339847Y1499294D01*
G03X339814Y1498780I3893J-508D01*
G01Y1497276D01*
G03X339847Y1496762I3926J-6D01*
G01X339849Y1496749D01*
Y1496235D01*
G02X339751Y1496063I-200J0D01*
G01X339408Y1495860D01*
X339303Y1495858D01*
X339256Y1495884D01*
G03X339028Y1496001I-1906J-3433D01*
G01X338941Y1496079D01*
G03X338910Y1496119I-172J-101D01*
G01X338202Y1496828D01*
X338194Y1496838D01*
G03X337467Y1497565I-3116J-2389D01*
G01X337457Y1497573D01*
X336748Y1498281D01*
G03X336607Y1498340I-142J-141D01*
G01X335605D01*
X335592Y1498342D01*
G03X334564I-514J-3868D01*
G01X334551Y1498340D01*
X333549D01*
G03X333408Y1498281I1J-200D01*
G01X333288Y1498161D01*
G02X333220Y1498117I-140J142D01*
G01X331784Y1499552D01*
G03X330219Y1500511I-2777J-2775D01*
G02X330139Y1500560I62J190D01*
G01X330055Y1500644D01*
X329541Y1501159D01*
X329533Y1501169D01*
G03X328806Y1501896I-3116J-2389D01*
G01X328796Y1501904D01*
X328087Y1502612D01*
G03X327946Y1502671I-142J-141D01*
G01X326944D01*
X326931Y1502673D01*
G03X326417Y1502706I-508J-3893D01*
G03X325903Y1502673I-6J-3926D01*
G01X325890Y1502671D01*
X324888D01*
G03X324747Y1502612I1J-200D01*
G01X324627Y1502492D01*
G02X324486Y1502434I-141J142D01*
G01X324450D01*
X324435Y1502436D01*
G03X324206Y1502454I-232J-1484D01*
G01X324183D01*
G03X323193Y1502064I20J-1502D01*
G01X323191Y1502061D01*
X323180Y1502051D01*
G03X323176Y1502047I1059J-1063D01*
G01X323157Y1502029D01*
X323113Y1502005D01*
X323077Y1501996D01*
X322960Y1501963D01*
X322922Y1501967D01*
G03X322702Y1501768I-20J-199D01*
G01Y1500947D01*
G03X322720Y1500713I1503J-2D01*
G01X322722Y1500702D01*
X322723Y1500672D01*
G02X322665Y1500530I-200J-1D01*
G01X322585Y1500450D01*
G03X322526Y1500309I141J-142D01*
G01Y1499307D01*
X322524Y1499294D01*
G03X322490Y1498780I3868J-514D01*
G01Y1497276D01*
G03X322524Y1496762I3902J0D01*
G01X322526Y1496749D01*
Y1496235D01*
G02X322428Y1496063I-200J0D01*
G01X322131Y1495888D01*
G02X322029Y1495860I-102J172D01*
G01X321933Y1495885D01*
G03X321706Y1496001I-1899J-3437D01*
G02X321619Y1496079I84J181D01*
G03X321588Y1496119I-172J-101D01*
G01X320880Y1496828D01*
X320872Y1496838D01*
G03X320145Y1497565I-3116J-2389D01*
G01X320135Y1497573D01*
X319426Y1498281D01*
G03X319285Y1498340I-142J-141D01*
G01X318283D01*
X318270Y1498342D01*
G03X317242I-514J-3868D01*
G01X317229Y1498340D01*
X316227D01*
G03X316086Y1498281I1J-200D01*
G01X315965Y1498160D01*
G02X315897Y1498116I-140J143D01*
G01X314461Y1499552D01*
G03X312896Y1500511I-2777J-2775D01*
G02X312816Y1500560I62J190D01*
G01X312734Y1500642D01*
X312218Y1501159D01*
X312210Y1501169D01*
G03X311483Y1501896I-3116J-2389D01*
G01X311473Y1501904D01*
X310764Y1502612D01*
G03X310623Y1502671I-142J-141D01*
G01X309621D01*
X309608Y1502673D01*
G03X309094Y1502706I-508J-3893D01*
G03X308580Y1502673I-6J-3926D01*
G01X308567Y1502671D01*
X307565D01*
G03X307424Y1502612I1J-200D01*
G01X307300Y1502489D01*
G02X307220Y1502440I-142J141D01*
G01X307175Y1502426D01*
X307127Y1502434D01*
G03X306944Y1502453I-246J-1482D01*
G01X306932D01*
G03X306919Y1502454I-122J-1496D01*
G01X306873D01*
G03X305379Y1500952I8J-1502D01*
G01Y1500946D01*
G03X305399Y1500705I1501J3D01*
G01X305407Y1500657D01*
X305393Y1500612D01*
G02X305344Y1500532I-190J62D01*
G01X305262Y1500450D01*
G03X305203Y1500309I141J-142D01*
G01Y1499307D01*
X305201Y1499294D01*
G03X305168Y1498780I3893J-508D01*
G01Y1497276D01*
G03X305201Y1496762I3926J-6D01*
G01X305203Y1496749D01*
Y1496235D01*
G02X305105Y1496063I-200J0D01*
G01X304808Y1495888D01*
G02X304706Y1495860I-102J172D01*
G01X304610Y1495885D01*
G03X304383Y1496001I-1899J-3437D01*
G02X304296Y1496079I84J181D01*
G03X304265Y1496119I-172J-101D01*
G01X303557Y1496828D01*
X303549Y1496838D01*
G03X302822Y1497565I-3116J-2389D01*
G01X302812Y1497573D01*
X302103Y1498281D01*
G03X301962Y1498340I-142J-141D01*
G01X300960D01*
X300947Y1498342D01*
G03X299919I-514J-3868D01*
G01X299906Y1498340D01*
X298904D01*
G03X298763Y1498281I1J-200D01*
G01X298642Y1498160D01*
G02X298574Y1498116I-140J143D01*
G01X297138Y1499552D01*
G03X295573Y1500511I-2777J-2775D01*
G02X295493Y1500560I62J190D01*
G01X295407Y1500646D01*
X294895Y1501159D01*
X294887Y1501169D01*
G03X294160Y1501896I-3116J-2389D01*
G01X294150Y1501904D01*
X293441Y1502612D01*
G03X293300Y1502671I-142J-141D01*
G01X292298D01*
X292285Y1502673D01*
G03X291771Y1502706I-508J-3893D01*
G03X291257Y1502673I-6J-3926D01*
G01X291244Y1502671D01*
X290242D01*
G03X290101Y1502612I1J-200D01*
G01X289981Y1502492D01*
G02X289840Y1502434I-141J142D01*
G01X289804D01*
X289789Y1502436D01*
G03X289560Y1502454I-232J-1484D01*
G01X289537D01*
G03X288547Y1502064I20J-1502D01*
G01X288545Y1502061D01*
X288534Y1502051D01*
G03X288530Y1502047I1059J-1063D01*
G01X288511Y1502029D01*
X288467Y1502005D01*
X288431Y1501996D01*
X288314Y1501963D01*
X288276Y1501967D01*
G03X288056Y1501768I-20J-199D01*
G01Y1500947D01*
G03X288074Y1500713I1503J-2D01*
G01X288076Y1500702D01*
X288077Y1500672D01*
G02X288019Y1500530I-200J-1D01*
G01X287939Y1500450D01*
G03X287880Y1500309I141J-142D01*
G01Y1499307D01*
X287878Y1499294D01*
G03X287844Y1498780I3868J-514D01*
G01Y1497276D01*
G03X287878Y1496762I3902J0D01*
G01X287880Y1496749D01*
Y1496235D01*
G02X287782Y1496063I-200J0D01*
G01X287485Y1495888D01*
G02X287383Y1495860I-102J172D01*
G01X287287Y1495885D01*
G03X287060Y1496001I-1899J-3437D01*
G02X286973Y1496079I84J181D01*
G03X286942Y1496119I-172J-101D01*
G01X286234Y1496828D01*
X286226Y1496838D01*
G03X285496Y1497567I-3115J-2390D01*
G01X285486Y1497575D01*
X284780Y1498281D01*
G03X284639Y1498340I-142J-141D01*
G01X283637D01*
X283624Y1498342D01*
G03X283272Y1498373I-520J-3892D01*
G01X283138Y1498432D01*
X283055Y1498517D01*
G02X282998Y1498657I143J140D01*
G01Y1502074D01*
G02X283198Y1502274I200J0D01*
G01X284520D01*
G03X284722Y1502476I0J202D01*
G01Y1503583D01*
G02X284728Y1503630I200J-2D01*
G01X284744Y1503690D01*
X284759Y1503715D01*
G03Y1505655I-1649J970D01*
G01X284744Y1505680D01*
X284728Y1505740D01*
G02X284722Y1505787I194J49D01*
G01Y1508702D01*
G02X284728Y1508749I200J-2D01*
G01X284744Y1508809D01*
X284759Y1508834D01*
G03Y1510774I-1649J970D01*
G01X284744Y1510799D01*
X284728Y1510859D01*
G02X284722Y1510906I194J49D01*
G01Y1512014D01*
G03X284520Y1512216I-202J0D01*
G01X283403D01*
G02X283237Y1512305I0J200D01*
G01X283209Y1512347D01*
X283199Y1512446D01*
X283255Y1512582D01*
X283341Y1512646D01*
X283395Y1512653D01*
G03X285397Y1514922I-285J2269D01*
G01X285396Y1514937D01*
Y1514943D01*
G03X285386Y1515149I-2287J-8D01*
G01X285380Y1515215D01*
X285447Y1515327D01*
X290385Y1517372D01*
X290481Y1517364D01*
X290500Y1517352D01*
G03X290704Y1517230I1273J1897D01*
G03X290950Y1517118I1068J2020D01*
G03X291751Y1516966I820J2134D01*
G01X291758D01*
X291771Y1516965D01*
G03X294009Y1518779I0J2288D01*
G01X294019Y1518827D01*
X294082Y1518903D01*
X337533Y1536902D01*
G03X338806Y1537754I-1505J3626D01*
G01X351139Y1550087D01*
G03X352290Y1552863I-2775J2777D01*
G01Y1558545D01*
G02X352390Y1558572I100J-172D01*
G01X353811D01*
G03X354014Y1558775I0J203D01*
G01Y1559920D01*
X354025Y1559952D01*
X354040Y1559997D01*
X354043Y1560003D01*
X354051Y1560016D01*
G03X354314Y1560984I-1650J968D01*
G01Y1560985D01*
G03X354056Y1561943I-1912J-1D01*
G01X354053Y1561948D01*
X354052Y1561950D01*
X354042Y1561968D01*
X354024Y1562023D01*
G02X354014Y1562083I190J62D01*
G01Y1565038D01*
X354025Y1565070D01*
X354040Y1565115D01*
X354043Y1565121D01*
X354051Y1565134D01*
G03X354314Y1566102I-1650J968D01*
G01Y1566103D01*
G03X354056Y1567061I-1912J-1D01*
G01X354053Y1567066D01*
X354052Y1567068D01*
X354042Y1567086D01*
X354024Y1567141D01*
G02X354014Y1567201I190J62D01*
G01Y1568313D01*
G03X353811Y1568516I-203J0D01*
G01X352390D01*
G02X352369Y1568517I-1J200D01*
G02X352290Y1568543I22J199D01*
G01Y1574148D01*
G02X352345Y1574286I200J0D01*
G01X352427Y1574371D01*
G02X352555Y1574433I146J-137D01*
G03Y1578245I-154J1906D01*
G02X352427Y1578307I18J199D01*
G01X352345Y1578392D01*
G02X352290Y1578530I145J138D01*
G01Y1579266D01*
G02X352345Y1579404I200J0D01*
G01X352427Y1579489D01*
G02X352555Y1579551I146J-137D01*
G03Y1583363I-154J1906D01*
G02X352427Y1583425I18J199D01*
G01X352345Y1583510D01*
G02X352290Y1583648I145J138D01*
G01Y1589502D01*
G02X352345Y1589640I200J0D01*
G01X352427Y1589725D01*
G02X352555Y1589787I146J-137D01*
G03Y1593599I-154J1906D01*
G02X352427Y1593661I18J199D01*
G01X352345Y1593746D01*
G02X352290Y1593884I145J138D01*
G01Y1594620D01*
G02X352345Y1594758I200J0D01*
G01X352427Y1594843D01*
G02X352555Y1594905I146J-137D01*
G03X354314Y1596811I-153J1906D01*
G03X352401Y1598724I-1913J0D01*
G03X352194Y1598712I7J-1913D01*
G01X352148Y1598707D01*
X352106Y1598722D01*
G02X352031Y1598769I66J189D01*
G01X351806Y1598994D01*
X351792Y1599019D01*
G03X351693Y1599188I-3437J-1900D01*
G01X351666Y1599258D01*
G03X351046Y1600218I-1478J-274D01*
G03X350619Y1600424I-858J-1234D01*
G01X350589Y1600433D01*
X349107Y1601914D01*
G03X348246Y1602566I-2778J-2774D01*
G01X348221Y1602580D01*
X347843Y1602958D01*
G03X347829Y1602971I-143J-140D01*
G01X347820Y1602978D01*
X347785Y1603013D01*
X347733D01*
X347723Y1603014D01*
G03X347703Y1603015I-20J-199D01*
G01X347426D01*
G02X347334Y1603053I28J198D01*
G01X346856Y1603532D01*
X346848Y1603542D01*
G03X346141Y1604249I-3107J-2400D01*
G01X346133Y1604255D01*
X345410Y1604978D01*
G03X345396Y1604991I-143J-140D01*
G01X345387Y1604998D01*
X345352Y1605033D01*
X345300D01*
X345290Y1605034D01*
G03X345270Y1605035I-20J-199D01*
G01X344252D01*
X344239Y1605037D01*
G03X343740Y1605068I-492J-3895D01*
G03X343241Y1605037I-7J-3926D01*
G01X343228Y1605035D01*
X342210D01*
G03X342190Y1605034I0J-200D01*
G01X342180Y1605033D01*
X342128D01*
X342093Y1604998D01*
X342084Y1604991D01*
G03X342070Y1604978I129J-153D01*
G01X341947Y1604855D01*
G02X341880Y1604811I-141J142D01*
G01X341846Y1604797D01*
X341772D01*
X341757Y1604799D01*
G03X341650Y1604812I-235J-1484D01*
G03X341569Y1604817I-133J-1496D01*
G01X341515D01*
G03X341153Y1604770I11J-1502D01*
G03X340622Y1604514I374J-1455D01*
G03X340516Y1604426I905J-1199D01*
G01X340500Y1604411D01*
X340419Y1604364D01*
X340393Y1604357D01*
X340283Y1604326D01*
X340245Y1604330D01*
G03X340025Y1604131I-20J-199D01*
G01Y1603311D01*
G03X340045Y1603071I1502J4D01*
G01X340046Y1603063D01*
X340047Y1603052D01*
G02X339989Y1602897I-199J-14D01*
G01X339904Y1602812D01*
G03X339891Y1602798I140J-143D01*
G01X339884Y1602789D01*
X339849Y1602754D01*
Y1602702D01*
X339848Y1602692D01*
G03X339847Y1602672I199J-20D01*
G01Y1601654D01*
X339845Y1601641D01*
G03X339814Y1601142I3895J-492D01*
G01Y1599638D01*
G03X339845Y1599139I3926J-7D01*
G01X339847Y1599126D01*
Y1598598D01*
G02X339749Y1598426I-200J0D01*
G01X339406Y1598223D01*
X339301Y1598221D01*
X339254Y1598247D01*
G03X339028Y1598363I-1905J-3433D01*
G01X338941Y1598441D01*
G03X338910Y1598481I-172J-101D01*
G01X338201Y1599191D01*
X338193Y1599201D01*
G03X337464Y1599929I-3115J-2390D01*
G01X337454Y1599937D01*
X336748Y1600643D01*
G03X336607Y1600702I-142J-141D01*
G01X335605D01*
X335592Y1600704D01*
G03X334564I-514J-3868D01*
G01X334551Y1600702D01*
X333549D01*
G03X333408Y1600643I1J-200D01*
G01X333298Y1600533D01*
X333297D01*
X333251Y1600487D01*
X333221Y1600478D01*
X331784Y1601914D01*
G03X330219Y1602873I-2777J-2775D01*
G02X330139Y1602922I62J190D01*
G01X329706Y1603356D01*
X329540Y1603522D01*
X329532Y1603532D01*
G03X328803Y1604260I-3115J-2390D01*
G01X328793Y1604268D01*
X328087Y1604974D01*
G03X327946Y1605033I-142J-141D01*
G01X326944D01*
X326931Y1605035D01*
G03X326417Y1605068I-508J-3893D01*
G03X325903Y1605035I-6J-3926D01*
G01X325890Y1605033D01*
X324888D01*
G03X324747Y1604974I1J-200D01*
G01X324624Y1604852D01*
G02X324544Y1604803I-142J141D01*
G01X324499Y1604789D01*
X324451Y1604797D01*
X324449D01*
X324434Y1604799D01*
G03X324339Y1604811I-236J-1483D01*
G03X324246Y1604817I-143J-1495D01*
G01X324192D01*
G03X322702Y1603315I12J-1502D01*
G01Y1603293D01*
G03X322720Y1603080I1502J20D01*
G01X322721Y1603074D01*
X322722Y1603063D01*
X322723Y1603044D01*
G02X322666Y1602894I-200J-10D01*
G01X322586Y1602813D01*
X322585Y1602812D01*
G03X322526Y1602671I141J-142D01*
G01Y1601669D01*
X322524Y1601656D01*
G03X322490Y1601142I3868J-514D01*
G01Y1599638D01*
G03X322524Y1599124I3902J0D01*
G01X322526Y1599111D01*
Y1598597D01*
G02X322428Y1598425I-200J0D01*
G01X322131Y1598250D01*
G02X322029Y1598222I-102J172D01*
G01X321933Y1598247D01*
G03X321706Y1598363I-1899J-3437D01*
G02X321619Y1598441I84J181D01*
G03X321588Y1598481I-172J-101D01*
G01X320879Y1599191D01*
X320871Y1599201D01*
G03X320142Y1599929I-3115J-2390D01*
G01X320132Y1599937D01*
X319426Y1600643D01*
G03X319285Y1600702I-142J-141D01*
G01X318283D01*
X318270Y1600704D01*
G03X317242I-514J-3868D01*
G01X317229Y1600702D01*
X316227D01*
G03X316086Y1600643I1J-200D01*
G01X315976Y1600533D01*
X315975D01*
X315929Y1600487D01*
X315898Y1600477D01*
X314461Y1601914D01*
G03X312896Y1602873I-2777J-2775D01*
G02X312816Y1602922I62J190D01*
G01X312383Y1603356D01*
X312217Y1603522D01*
X312209Y1603532D01*
G03X311480Y1604260I-3115J-2390D01*
G01X311470Y1604268D01*
X310764Y1604974D01*
G03X310623Y1605033I-142J-141D01*
G01X309621D01*
X309608Y1605035D01*
G03X309094Y1605068I-508J-3893D01*
G03X308580Y1605035I-6J-3926D01*
G01X308567Y1605033D01*
X307565D01*
G03X307424Y1604974I1J-200D01*
G01X307301Y1604852D01*
G02X307221Y1604803I-142J141D01*
G01X307176Y1604789D01*
X307128Y1604797D01*
X307126D01*
X307111Y1604799D01*
G03X307016Y1604811I-236J-1483D01*
G03X306923Y1604817I-143J-1495D01*
G01X306869D01*
G03X306507Y1604770I11J-1502D01*
G03X305976Y1604514I374J-1455D01*
G03X305870Y1604426I905J-1199D01*
G01X305854Y1604411D01*
X305773Y1604364D01*
X305747Y1604357D01*
X305637Y1604326D01*
X305599Y1604330D01*
G03X305379Y1604131I-20J-199D01*
G01Y1603311D01*
G03X305399Y1603068I1502J1D01*
G01X305402Y1603051D01*
Y1603032D01*
G02X305366Y1602921I-200J4D01*
G02X305343Y1602893I-165J112D01*
G01X305262Y1602812D01*
G03X305203Y1602671I141J-142D01*
G01Y1601669D01*
X305201Y1601656D01*
G03X305168Y1601142I3893J-508D01*
G01Y1599638D01*
G03X305201Y1599124I3926J-6D01*
G01X305203Y1599111D01*
Y1598597D01*
G02X305105Y1598425I-200J0D01*
G01X304808Y1598250D01*
G02X304706Y1598222I-102J172D01*
G01X304610Y1598247D01*
G03X304383Y1598363I-1899J-3437D01*
G02X304296Y1598441I84J181D01*
G03X304265Y1598481I-172J-101D01*
G01X303557Y1599190D01*
X303549Y1599200D01*
G03X302822Y1599927I-3116J-2389D01*
G01X302812Y1599935D01*
X302103Y1600643D01*
G03X301962Y1600702I-142J-141D01*
G01X300960D01*
X300947Y1600704D01*
G03X299919I-514J-3868D01*
G01X299906Y1600702D01*
X298904D01*
G03X298763Y1600643I1J-200D01*
G01X298606Y1600487D01*
X298576Y1600477D01*
X297138Y1601914D01*
G03X295573Y1602873I-2777J-2775D01*
G02X295493Y1602922I62J190D01*
G01X294897Y1603518D01*
X294889Y1603528D01*
G03X294160Y1604258I-3119J-2385D01*
G01X294150Y1604266D01*
X293441Y1604974D01*
G03X293300Y1605033I-142J-141D01*
G01X292298D01*
X292285Y1605035D01*
G03X291771Y1605068I-508J-3893D01*
G03X291257Y1605035I-6J-3926D01*
G01X291244Y1605033D01*
X290242D01*
G03X290101Y1604974I1J-200D01*
G01X289978Y1604852D01*
G02X289898Y1604803I-142J141D01*
G01X289853Y1604789D01*
X289805Y1604797D01*
G03X289601Y1604817I-248J-1482D01*
G01X289546D01*
G03X288056Y1603315I12J-1502D01*
G01Y1603293D01*
G03X288076Y1603067I1502J19D01*
G01X288079Y1603035D01*
G02X288020Y1602893I-200J0D01*
G01X287939Y1602812D01*
G03X287880Y1602671I141J-142D01*
G01Y1601669D01*
X287878Y1601656D01*
G03X287844Y1601142I3868J-514D01*
G01Y1599638D01*
G03X287878Y1599124I3902J0D01*
G01X287880Y1599111D01*
Y1598597D01*
G02X287782Y1598425I-200J0D01*
G01X287485Y1598250D01*
G02X287383Y1598222I-102J172D01*
G01X287287Y1598247D01*
G03X287060Y1598363I-1899J-3437D01*
G02X286973Y1598441I84J181D01*
G03X286942Y1598481I-172J-101D01*
G01X286233Y1599191D01*
X286225Y1599201D01*
G03X285496Y1599929I-3115J-2390D01*
G01X285486Y1599937D01*
X284780Y1600643D01*
G03X284639Y1600702I-142J-141D01*
G01X283637D01*
X283624Y1600704D01*
G03X282596I-514J-3868D01*
G01X282583Y1600702D01*
X281581D01*
G03X281440Y1600643I1J-200D01*
G01X281330Y1600533D01*
X281329D01*
X281317Y1600521D01*
G02X281237Y1600472I-142J141D01*
G01X281192Y1600458D01*
X281144Y1600466D01*
G03X280895Y1600486I-244J-1482D01*
G03X279395Y1598984I2J-1502D01*
G03X279413Y1598748I1502J-4D01*
G01X279414Y1598740D01*
X279415Y1598737D01*
X279416Y1598720D01*
G02X279359Y1598563I-199J-17D01*
G01X279279Y1598482D01*
X279278Y1598481D01*
G03X279219Y1598340I141J-142D01*
G01Y1597338D01*
X279217Y1597325D01*
G03X279184Y1596811I3893J-508D01*
G01Y1595307D01*
G03X279217Y1594793I3926J-6D01*
G01X279219Y1594780D01*
Y1593724D01*
X279217Y1593711D01*
G03X279184Y1593197I3893J-508D01*
G01Y1591693D01*
G03X279217Y1591179I3926J-6D01*
G01X279219Y1591166D01*
Y1590164D01*
G03X279278Y1590023I200J1D01*
G01X279358Y1589943D01*
G02X279415Y1589776I-141J-141D01*
G01X279414Y1589769D01*
G03X279395Y1589528I1483J-238D01*
G01Y1589480D01*
G03X280653Y1588039I1502J42D01*
G01X280696Y1588032D01*
X280775Y1587980D01*
G02X280801Y1587958I-116J-163D01*
G01X280848Y1587911D01*
G02X280880Y1587869I-142J-141D01*
G01X280920Y1587799D01*
Y1587797D01*
X281000Y1587655D01*
G02X281022Y1587562I-178J-91D01*
G01X281021Y1587529D01*
X281012Y1587487D01*
X281006Y1587471D01*
X281004Y1587467D01*
G03X280969Y1587379I2107J-889D01*
G03X280889Y1587118I2142J-799D01*
G03X280824Y1586600I2221J-542D01*
G01Y1586564D01*
G03X282415Y1584397I2286J11D01*
G01X282416D01*
G02X282517Y1584324I-61J-191D01*
G01X282535Y1584300D01*
X282554Y1584240D01*
Y1584070D01*
G02X282354Y1583870I-200J0D01*
G01X281700D01*
G03X281519Y1583759I0J-203D01*
G01X281516Y1583753D01*
X281513Y1583744D01*
G03X281498Y1583668I187J-76D01*
G01Y1582559D01*
G02X281492Y1582512I-200J2D01*
G01X281476Y1582452D01*
X281461Y1582427D01*
G03Y1580487I1649J-970D01*
G01X281476Y1580462D01*
X281492Y1580402D01*
G02X281498Y1580355I-194J-49D01*
G01Y1577441D01*
G02X281492Y1577394I-200J2D01*
G01X281483Y1577361D01*
X281467Y1577322D01*
X281455Y1577297D01*
G03X281197Y1576339I1655J-959D01*
G03X281465Y1575363I1913J0D01*
G01X281474Y1575348D01*
X281486Y1575317D01*
G02X281495Y1575285I-188J-70D01*
G02X281498Y1575249I-197J-35D01*
G01Y1574693D01*
X281497Y1574129D01*
G03X281699Y1573926I203J0D01*
G01X282354D01*
G02X282554Y1573726I0J-200D01*
G01Y1573588D01*
G02X282515Y1573470I-200J1D01*
G01X282497Y1573446D01*
X282447Y1573409D01*
X282415Y1573399D01*
G03Y1569043I695J-2178D01*
G01X282416D01*
G02X282517Y1568970I-61J-191D01*
G01X282535Y1568946D01*
X282554Y1568886D01*
Y1568716D01*
G02X282354Y1568516I-200J0D01*
G01X281700D01*
G03X281519Y1568405I0J-203D01*
G01X281516Y1568399D01*
X281513Y1568390D01*
G03X281498Y1568314I187J-76D01*
G01Y1567205D01*
G02X281492Y1567158I-200J2D01*
G01X281476Y1567098D01*
X281461Y1567073D01*
G03Y1565133I1649J-970D01*
G01X281476Y1565108D01*
X281492Y1565048D01*
G02X281498Y1565001I-194J-49D01*
G01Y1562087D01*
G02X281492Y1562040I-200J2D01*
G01X281483Y1562007D01*
X281467Y1561968D01*
X281455Y1561943D01*
G03X281197Y1560985I1655J-959D01*
G03X281465Y1560009I1913J0D01*
G01X281474Y1559994D01*
X281486Y1559963D01*
G02X281495Y1559931I-188J-70D01*
G02X281498Y1559895I-197J-35D01*
G01Y1559339D01*
X281497Y1558775D01*
G03X281699Y1558572I203J0D01*
G01X282354D01*
G02X282554Y1558372I0J-200D01*
G01Y1558234D01*
G02X282515Y1558116I-200J1D01*
G01X282497Y1558092D01*
X282447Y1558055D01*
X282415Y1558045D01*
G03X280824Y1555867I695J-2178D01*
G01Y1555848D01*
G03X280828Y1555737I2286J27D01*
G01Y1555715D01*
G02X280807Y1555626I-200J0D01*
G01X280791Y1555594D01*
X280737Y1555519D01*
G02X280730Y1555509I-167J110D01*
G02X280675Y1555463I-154J128D01*
G01X280630Y1555437D01*
X280614Y1555431D01*
G03X280529Y1555398I1366J-3643D01*
G01X278920Y1554732D01*
G03X278571Y1554567I1487J-3596D01*
G01X278562Y1554562D01*
X278472Y1554525D01*
X278470Y1554524D01*
G03X278342Y1554472I1401J-3631D01*
G01X278333Y1554468D01*
X277765Y1554232D01*
X277764D01*
X276846Y1553852D01*
X276762Y1553817D01*
X276751Y1553813D01*
X276741Y1553810D01*
G03X276391Y1553684I1142J-3720D01*
G01X274782Y1553018D01*
G03X274112Y1552660I1490J-3595D01*
G03X273688Y1552334I2154J-3241D01*
G01X273662Y1552311D01*
X273539Y1552260D01*
X273505Y1552258D01*
G03X272253Y1551970I234J-3884D01*
G01X270644Y1551304D01*
G03X269105Y1550154I1488J-3596D01*
G01X269088Y1550133D01*
X269070Y1550120D01*
G02X269029Y1550097I-118J162D01*
G01X266597Y1549086D01*
G03X265990Y1548770I1486J-3596D01*
G03X265334Y1548243I2095J-3280D01*
G01X265132Y1548041D01*
X265101Y1548021D01*
X265075Y1548004D01*
X265045Y1547995D01*
G03X263397Y1547014I1106J-3733D01*
G01X262166Y1545783D01*
G03X261423Y1544745I2752J-2754D01*
G01X261417Y1544731D01*
X261383Y1544680D01*
X261368Y1544666D01*
X261311Y1544609D01*
X261295Y1544601D01*
X261280Y1544594D01*
G03X260231Y1543846I1704J-3499D01*
G01X259000Y1542615D01*
G03X258024Y1540967I2756J-2745D01*
G01X258016Y1540942D01*
X258005Y1540923D01*
G02X257974Y1540883I-172J102D01*
G01X257236Y1540145D01*
G03X256525Y1539169I2752J-2752D01*
G01X255517Y1537207D01*
G02X255400Y1537108I-178J92D01*
G01X255169Y1537034D01*
X254837Y1536927D01*
X254833Y1536923D01*
X254403Y1536085D01*
X254135Y1535562D01*
X254132Y1535556D01*
G03X254128Y1535548I3478J-1744D01*
G01X254116Y1535526D01*
X253907Y1535316D01*
G03X253055Y1534043I2774J-2778D01*
G01X252669Y1533110D01*
G02X252499Y1533132I-35J398D01*
G01X252464Y1533146D01*
G02X252264Y1533356I170J362D01*
G03X250876Y1534284I-1388J-574D01*
G03X249374Y1532782I0J-1502D01*
G03X250870Y1531280I1502J0D01*
G01X250878D01*
G03X251622Y1531478I-1J1502D01*
G01X251629Y1531481D01*
X251643Y1531488D01*
G02X251707Y1531506I85J-181D01*
G01X251883Y1531433D01*
G02X251927Y1531320I-155J-126D01*
G01X251793Y1530995D01*
X251789Y1530988D01*
X251745Y1530901D01*
X251743Y1530897D01*
X251742Y1530896D01*
G03X251701Y1530818I3424J-1850D01*
G01Y1530817D01*
X251548Y1530519D01*
X250925Y1529304D01*
G03X250902Y1529259I3454J-1794D01*
G01X250900Y1529253D01*
G03X250878Y1529212I3417J-1860D01*
G01Y1529211D01*
X250877Y1529209D01*
X250228Y1527943D01*
G03X250227Y1527941I178J-90D01*
G01X250224Y1527934D01*
X250210Y1527907D01*
X250207Y1527867D01*
G03X250216Y1527791I199J-15D01*
G01X250303Y1527520D01*
G02X250297Y1527382I-191J-61D01*
G01X249535Y1525544D01*
G02X249528Y1525530I-182J82D01*
G01X246610Y1519839D01*
G03X246224Y1518641I3463J-1777D01*
G01X246223Y1518633D01*
X246216Y1518602D01*
X246212Y1518591D01*
G02X246113Y1518476I-190J63D01*
G01X246077Y1518458D01*
X246000Y1518452D01*
X245962Y1518464D01*
G03X245506Y1518535I-456J-1432D01*
G01X245500D01*
G03X243998Y1517033I0J-1502D01*
G03X245328Y1515541I1502J0D01*
G01X245330D01*
X245342Y1515539D01*
G02X245452Y1515479I-36J-197D01*
G02X245465Y1515464I-144J-138D01*
G01X245611Y1515273D01*
G03X245624Y1515258I158J123D01*
G01X245652Y1515229D01*
X245669Y1515187D01*
G02X245680Y1515084I-187J-72D01*
G01X245373Y1513077D01*
X245316Y1512706D01*
G02X245314Y1512699I-193J51D01*
G01X245309Y1512681D01*
G02X245184Y1512555I-190J63D01*
G01X245085Y1512524D01*
X245084D01*
X244852Y1512451D01*
G03X244756Y1512349I87J-179D01*
G03X243553Y1512975I-1220J-876D01*
G01X243522D01*
G03X242033Y1511473I13J-1502D01*
G03X243520Y1509971I1502J0D01*
G01X243537D01*
G03X244242Y1510147I-1J1502D01*
G01X244243Y1510148D01*
G03X244247Y1510150I-670J1345D01*
G01X244253Y1510153D01*
X244295Y1510172D01*
X244317Y1510177D01*
X244350Y1510186D01*
X244406Y1510185D01*
X244431Y1510178D01*
X244464Y1510169D01*
X244673Y1510024D01*
X244691D01*
X244747Y1509975D01*
G03X244764Y1509962I130J152D01*
G01X244775Y1509955D01*
G02X244865Y1509756I-108J-169D01*
G01X236427Y1454624D01*
X231891Y1424992D01*
G03X231890Y1424984I198J-29D01*
G01Y1424962D01*
X231889Y1424957D01*
Y1360896D01*
X231882Y1360869D01*
G03X231758Y1360207I3783J-1051D01*
G01X230163Y1344010D01*
G02X230105Y1343888I-199J20D01*
G01X226419Y1340202D01*
G03X226360Y1340060I141J-142D01*
G01Y1334171D01*
X222934Y1264487D01*
G03X222930Y1264365I3887J-189D01*
G01Y1264324D01*
G03Y1264296I3891J-14D01*
G01Y1260636D01*
G03X223135Y1259392I3892J2D01*
G01X223146Y1259361D01*
G03X223185Y1259260I3649J1351D01*
G01X223188Y1259251D01*
X223199Y1259212D01*
X223206Y1259179D01*
G02X223210Y1259138I-196J-40D01*
G01Y1256096D01*
G02X223091Y1255913I-200J0D01*
G03Y1253535I531J-1189D01*
G02X223210Y1253352I-81J-183D01*
G01Y1252356D01*
G02X223091Y1252173I-200J0D01*
G03X222320Y1250984I531J-1189D01*
G01Y1250982D01*
G03X222327Y1250848I1302J1D01*
G01X222332Y1250803D01*
X222302Y1250718D01*
X222049Y1250466D01*
G02X221908Y1250408I-141J142D01*
G01X221887Y1250409D01*
G03X221282Y1250329I-136J-1296D01*
G01X221280D01*
G03X221266Y1250323I506J-1200D01*
G02X221013Y1250580I-65J189D01*
G03X221083Y1250984I-1131J404D01*
G03X219881Y1249782I-1202J0D01*
G03X220024Y1249790I4J1202D01*
G01X220071Y1249796D01*
X220159Y1249764D01*
X220446Y1249464D01*
X220473Y1249375D01*
X220470Y1249354D01*
G03X220448Y1249116I1280J-238D01*
G01Y1247244D01*
X220447Y1245373D01*
G03X221749Y1244070I1303J0D01*
G01X221750D01*
G03X221976Y1244090I-1J1303D01*
G01X221979D01*
X222013Y1244096D01*
X222102Y1244068D01*
X222368Y1243813D01*
G02X222429Y1243647I-138J-145D01*
G01Y1243646D01*
G03X222420Y1243503I1193J-147D01*
G03X223097Y1242422I1202J0D01*
G01X223098D01*
G02X223210Y1242243I-88J-180D01*
G01Y1241135D01*
G02X223091Y1240952I-200J0D01*
G03Y1238574I531J-1189D01*
G02X223210Y1238391I-81J-183D01*
G01Y1237395D01*
G02X223091Y1237212I-200J0D01*
G03Y1234834I531J-1189D01*
G02X223210Y1234651I-81J-183D01*
G01Y1233655D01*
G02X223091Y1233472I-200J0D01*
G03Y1231094I531J-1189D01*
G02X223210Y1230911I-81J-183D01*
G01Y1229803D01*
G02X223098Y1229624I-200J1D01*
G01X223097D01*
G03X222420Y1228543I525J-1081D01*
G03X222429Y1228399I1202J3D01*
G01X222435Y1228352D01*
X222403Y1228264D01*
X222103Y1227976D01*
X222014Y1227948D01*
X221996Y1227951D01*
G03X221754Y1227974I-244J-1279D01*
G01X221751D01*
X221715Y1227975D01*
G03X220448Y1226673I36J-1303D01*
G01Y1222930D01*
G03X220501Y1222564I1303J2D01*
G01X220502Y1222559D01*
G02X220311Y1222301I-191J-58D01*
G01X220269Y1222307D01*
X220241Y1222313D01*
G03X219881Y1222364I-361J-1251D01*
G03X218785Y1221764I0J-1301D01*
G02X218617Y1221672I-168J108D01*
G01X217405D01*
G02X217237Y1221764I0J200D01*
G03X216141Y1222364I-1096J-701D01*
G01X216139D01*
G03X216005Y1222357I1J-1302D01*
G01X215984Y1222356D01*
G02X215843Y1222414I0J200D01*
G01X215590Y1222666D01*
X215560Y1222751D01*
X215565Y1222796D01*
G03X215572Y1222930I-1295J135D01*
G01Y1223211D01*
G02X215638Y1223359I200J-1D01*
G01X215892Y1223586D01*
X215972Y1223612D01*
X216014Y1223608D01*
G03X216141Y1223601I130J1195D01*
G03Y1226005I0J1202D01*
G03X216015Y1225998I4J-1202D01*
G01X216013D01*
X215972Y1225994D01*
X215892Y1226020D01*
X215638Y1226247D01*
G02X215572Y1226395I134J149D01*
G01Y1226673D01*
G03X215552Y1226899I-1302J-1D01*
G01Y1226901D01*
X215546Y1226934D01*
X215574Y1227023D01*
X215828Y1227289D01*
G02X215973Y1227351I145J-138D01*
G01X215997Y1227350D01*
G03X216141Y1227341I147J1193D01*
G03X214939Y1228543I0J1202D01*
G03X214948Y1228399I1202J3D01*
G01X214949Y1228375D01*
G02X214887Y1228230I-200J0D01*
G01X214621Y1227976D01*
X214532Y1227948D01*
X214498Y1227954D01*
G03X214271Y1227974I-227J-1282D01*
G01X214270D01*
G03X212968Y1226672I0J-1302D01*
G01Y1222930D01*
G03X212975Y1222797I1302J2D01*
G01X212976Y1222776D01*
G02X212918Y1222635I-200J0D01*
G01X212666Y1222382D01*
X212581Y1222352D01*
X212536Y1222357D01*
G03X212401Y1222364I-135J-1295D01*
G03X211305Y1221764I0J-1301D01*
G02X211137Y1221672I-168J108D01*
G01X209925D01*
G02X209757Y1221764I0J200D01*
G03X208661Y1222364I-1096J-701D01*
G01X208659D01*
G03X208525Y1222357I1J-1302D01*
G01X208504Y1222356D01*
G02X208363Y1222414I0J200D01*
G01X208110Y1222666D01*
X208080Y1222751D01*
X208085Y1222796D01*
G03X208092Y1222930I-1295J135D01*
G01Y1223211D01*
G02X208158Y1223359I200J-1D01*
G01X208412Y1223586D01*
X208492Y1223612D01*
X208534Y1223608D01*
G03X208661Y1223601I130J1195D01*
G03Y1226005I0J1202D01*
G03X208535Y1225998I4J-1202D01*
G01X208533D01*
X208492Y1225994D01*
X208412Y1226020D01*
X208158Y1226247D01*
G02X208092Y1226395I134J149D01*
G01Y1226673D01*
G03X208072Y1226899I-1302J-1D01*
G01Y1226901D01*
X208066Y1226934D01*
X208094Y1227023D01*
X208348Y1227289D01*
G02X208493Y1227351I145J-138D01*
G01X208517Y1227350D01*
G03X208661Y1227341I147J1193D01*
G03X207459Y1228543I0J1202D01*
G03X207468Y1228399I1202J3D01*
G01X207469Y1228375D01*
G02X207407Y1228230I-200J0D01*
G01X207141Y1227976D01*
X207052Y1227948D01*
X207018Y1227954D01*
G03X206791Y1227974I-227J-1282D01*
G01X206790D01*
G03X205488Y1226672I0J-1302D01*
G01Y1222930D01*
G03X205495Y1222797I1302J2D01*
G01X205496Y1222776D01*
G02X205438Y1222635I-200J0D01*
G01X205186Y1222382D01*
X205101Y1222352D01*
X205056Y1222357D01*
G03X204921Y1222364I-135J-1295D01*
G03X203825Y1221764I0J-1301D01*
G02X203657Y1221672I-168J108D01*
G01X202445D01*
G02X202277Y1221764I0J200D01*
G03X201181Y1222364I-1096J-701D01*
G01X201179D01*
G03X201045Y1222357I1J-1302D01*
G01X201024Y1222356D01*
G02X200883Y1222414I0J200D01*
G01X200630Y1222666D01*
X200600Y1222751D01*
X200605Y1222796D01*
G03X200612Y1222930I-1295J135D01*
G01Y1223211D01*
G02X200678Y1223359I200J-1D01*
G01X200932Y1223586D01*
X201012Y1223612D01*
X201054Y1223608D01*
G03X201181Y1223601I130J1195D01*
G03Y1226005I0J1202D01*
G03X201055Y1225998I4J-1202D01*
G01X201053D01*
X201012Y1225994D01*
X200932Y1226020D01*
X200678Y1226247D01*
G02X200612Y1226395I134J149D01*
G01Y1226673D01*
G03X200592Y1226899I-1302J-1D01*
G01Y1226901D01*
X200586Y1226934D01*
X200614Y1227023D01*
X200868Y1227289D01*
G02X201013Y1227351I145J-138D01*
G01X201037Y1227350D01*
G03X201181Y1227341I147J1193D01*
G03X199979Y1228543I0J1202D01*
G03X199988Y1228399I1202J3D01*
G01X199989Y1228375D01*
G02X199927Y1228230I-200J0D01*
G01X199661Y1227976D01*
X199572Y1227948D01*
X199538Y1227954D01*
G03X199311Y1227974I-227J-1282D01*
G01X199310D01*
G03X198008Y1226672I0J-1302D01*
G01Y1222930D01*
G03X198015Y1222796I1302J1D01*
G01X198020Y1222752D01*
X197990Y1222667D01*
X197705Y1222382D01*
X197620Y1222352D01*
X197576Y1222357D01*
G03X197442Y1222364I-135J-1295D01*
G01X197440D01*
G03X196344Y1221764I0J-1301D01*
G02X196176Y1221672I-168J108D01*
G01X194964D01*
G02X194796Y1221764I0J200D01*
G03X193700Y1222364I-1096J-701D01*
G01X193698D01*
G03X193564Y1222357I1J-1302D01*
G01X193520Y1222352D01*
X193435Y1222382D01*
X193150Y1222666D01*
X193120Y1222751D01*
X193125Y1222796D01*
G03X193132Y1222918I-1296J136D01*
G01Y1223211D01*
G02X193198Y1223359I200J-1D01*
G01X193419Y1223558D01*
G02X193573Y1223608I134J-149D01*
G01X193574D01*
G03X193700Y1223601I130J1195D01*
G03Y1226005I0J1202D01*
G03X193575Y1225998I5J-1202D01*
G01X193573D01*
G02X193419Y1226048I-20J199D01*
G01X193198Y1226247D01*
G02X193132Y1226395I134J149D01*
G01Y1226675D01*
G03X193112Y1226900I-1303J-2D01*
G01Y1226902D01*
X193107Y1226934D01*
X193134Y1227023D01*
X193420Y1227324D01*
X193510Y1227356D01*
X193556Y1227350D01*
G03X193700Y1227341I147J1193D01*
G03X192498Y1228543I0J1202D01*
G03X192507Y1228399I1202J3D01*
G01X192513Y1228353D01*
X192481Y1228263D01*
X192180Y1227977D01*
X192091Y1227950D01*
X192058Y1227955D01*
G03X191832Y1227975I-227J-1283D01*
G01X191829D01*
G03X190526Y1226672I0J-1303D01*
G01Y1222930D01*
G03X190579Y1222564I1303J2D01*
G01X190580Y1222559D01*
G02X190389Y1222302I-191J-57D01*
G01X190346Y1222308D01*
X190319Y1222314D01*
G03X189962Y1222364I-357J-1252D01*
G01X189960D01*
G03X188864Y1221764I0J-1301D01*
G02X188696Y1221672I-168J108D01*
G01X187484D01*
G02X187316Y1221764I0J200D01*
G03X186220Y1222364I-1096J-701D01*
G01X186218D01*
G03X186084Y1222357I1J-1302D01*
G01X186040Y1222352D01*
X185955Y1222382D01*
X185670Y1222666D01*
X185640Y1222751D01*
X185645Y1222796D01*
G03X185652Y1222918I-1296J136D01*
G01Y1223211D01*
G02X185718Y1223359I200J-1D01*
G01X185939Y1223558D01*
G02X186093Y1223608I134J-149D01*
G01X186094D01*
G03X186220Y1223601I130J1195D01*
G03Y1226005I0J1202D01*
G03X186095Y1225998I5J-1202D01*
G01X186093D01*
G02X185939Y1226048I-20J199D01*
G01X185718Y1226247D01*
G02X185652Y1226395I134J149D01*
G01Y1226675D01*
G03X185632Y1226900I-1303J-2D01*
G01Y1226902D01*
X185627Y1226934D01*
X185654Y1227023D01*
X185940Y1227324D01*
X186030Y1227356D01*
X186076Y1227350D01*
G03X186220Y1227341I147J1193D01*
G03X185018Y1228543I0J1202D01*
G03X185027Y1228399I1202J3D01*
G01X185033Y1228353D01*
X185001Y1228263D01*
X184700Y1227977D01*
X184611Y1227950D01*
X184578Y1227955D01*
G03X184352Y1227975I-227J-1283D01*
G01X184349D01*
G03X183046Y1226672I0J-1303D01*
G01Y1222930D01*
G03X183099Y1222564I1303J2D01*
G01X183100Y1222559D01*
G02X182909Y1222302I-191J-57D01*
G01X182866Y1222308D01*
X182839Y1222314D01*
G03X182482Y1222364I-357J-1252D01*
G01X182480D01*
G03X181384Y1221764I0J-1301D01*
G02X181216Y1221672I-168J108D01*
G01X180004D01*
G02X179836Y1221764I0J200D01*
G03X178740Y1222364I-1096J-701D01*
G01X178738D01*
G03X178604Y1222357I1J-1302D01*
G01X178560Y1222352D01*
X178475Y1222382D01*
X178190Y1222666D01*
X178160Y1222751D01*
X178165Y1222796D01*
G03X178172Y1222918I-1296J136D01*
G01Y1223211D01*
G02X178238Y1223359I200J-1D01*
G01X178459Y1223558D01*
G02X178613Y1223608I134J-149D01*
G01X178614D01*
G03X178740Y1223601I130J1195D01*
G03Y1226005I0J1202D01*
G03X178615Y1225998I5J-1202D01*
G01X178613D01*
G02X178459Y1226048I-20J199D01*
G01X178238Y1226247D01*
G02X178172Y1226395I134J149D01*
G01Y1226675D01*
G03X178152Y1226900I-1303J-2D01*
G01Y1226902D01*
X178147Y1226934D01*
X178174Y1227023D01*
X178460Y1227324D01*
X178550Y1227356D01*
X178596Y1227350D01*
G03X178740Y1227341I147J1193D01*
G03X177538Y1228543I0J1202D01*
G03X177547Y1228399I1202J3D01*
G01X177553Y1228353D01*
X177521Y1228263D01*
X177220Y1227977D01*
X177131Y1227950D01*
X177098Y1227955D01*
G03X176872Y1227975I-227J-1283D01*
G01X176869D01*
G03X175566Y1226672I0J-1303D01*
G01Y1222930D01*
G03X175619Y1222564I1303J2D01*
G01X175620Y1222559D01*
G02X175429Y1222301I-191J-58D01*
G01X175387Y1222307D01*
X175359Y1222313D01*
G03X174999Y1222364I-361J-1251D01*
G03X173903Y1221764I0J-1301D01*
G02X173735Y1221672I-168J108D01*
G01X172523D01*
G02X172355Y1221764I0J200D01*
G03X171259Y1222364I-1096J-701D01*
G01X171257D01*
G03X171123Y1222357I1J-1302D01*
G01X171102Y1222356D01*
G02X170961Y1222414I0J200D01*
G01X170708Y1222666D01*
X170678Y1222751D01*
X170683Y1222796D01*
G03X170690Y1222930I-1295J135D01*
G01Y1223211D01*
G02X170756Y1223359I200J-1D01*
G01X171010Y1223586D01*
X171090Y1223612D01*
X171132Y1223608D01*
G03X171259Y1223601I130J1195D01*
G03Y1226005I0J1202D01*
G03X171133Y1225998I4J-1202D01*
G01X171131D01*
X171090Y1225994D01*
X171010Y1226020D01*
X170756Y1226247D01*
G02X170690Y1226395I134J149D01*
G01Y1226673D01*
G03X170670Y1226899I-1302J-1D01*
G01Y1226901D01*
X170664Y1226934D01*
X170692Y1227023D01*
X170946Y1227289D01*
G02X171091Y1227351I145J-138D01*
G01X171115Y1227350D01*
G03X171259Y1227341I147J1193D01*
G03Y1229745I0J1202D01*
G03X171187Y1229743I-3J-1202D01*
G01X171186D01*
G02X171004Y1229838I-12J200D01*
G01X170820Y1230139D01*
G02X170790Y1230244I170J105D01*
G01X170818Y1230345D01*
G03X171070Y1230856I-3297J1943D01*
G01X171255Y1230981D01*
X171259D01*
G03X172561Y1232283I0J1302D01*
G03X171488Y1233565I-1302J0D01*
G02X171324Y1233740I35J197D01*
G03X171265Y1234112I-3804J-413D01*
G01X171261Y1234153D01*
X171265Y1234194D01*
G03X171324Y1234566I-3745J785D01*
G02X171488Y1234741I199J-22D01*
G03X172561Y1236023I-229J1282D01*
G03X171259Y1237325I-1302J0D01*
G01X171255D01*
X171070Y1237450D01*
G03X170667Y1238199I-3551J-1428D01*
G01X170640Y1238257D01*
G03X170233Y1238885I-1250J-364D01*
G03X169949Y1239068I-841J-994D01*
G02X169945Y1239070I87J180D01*
G01X169910Y1239087D01*
X169850Y1239184D01*
Y1242150D01*
G02X169960Y1242328I200J-1D01*
G01X170281Y1242489D01*
G02X170490Y1242471I90J-179D01*
G03X171259Y1242216I769J1032D01*
G03Y1244790I0J1287D01*
G03X171122Y1244783I-3J-1287D01*
G01X171121D01*
G02X170959Y1244841I-20J199D01*
G01X170706Y1245095D01*
X170677Y1245181D01*
X170682Y1245226D01*
G03X170690Y1245373I-1295J144D01*
G01Y1245565D01*
G02X170756Y1245713I200J-1D01*
G01X171008Y1245940D01*
X171088Y1245966D01*
X171130Y1245962D01*
G03X171259Y1245956I124J1281D01*
G03Y1248530I0J1287D01*
G03X171130Y1248524I-5J-1287D01*
G01X171088Y1248520D01*
X171008Y1248546D01*
X170756Y1248773D01*
G02X170690Y1248921I134J149D01*
G01Y1249113D01*
G03X170218Y1250117I-1304J0D01*
G03X169936Y1250295I-832J-1005D01*
G01X169910Y1250308D01*
X169850Y1250404D01*
Y1258018D01*
X169864Y1258090D01*
G03X170130Y1259509I-3660J1420D01*
G01Y1265161D01*
G02X170157Y1265261I200J0D01*
G01X188592Y1296897D01*
G03X188749Y1297195I-3392J1978D01*
G01X208135Y1338183D01*
G03X208342Y1338722I-3552J1673D01*
G01X209259Y1341747D01*
G02X209274Y1341783I191J-59D01*
G01X209289Y1341811D01*
G03X209622Y1342688I-3445J1810D01*
G01X209956Y1344039D01*
G02X209959Y1344049I193J-52D01*
G01X210644Y1346311D01*
G03X210814Y1347451I-3757J1143D01*
G01Y1362613D01*
G03X209663Y1365389I-3926J-1D01*
G01X209224Y1365828D01*
G02X209166Y1365970I142J141D01*
G01Y1395498D01*
G03X209143Y1395590I-200J-1D01*
G01X204036Y1405413D01*
G02X204023Y1405565I178J92D01*
G01Y1405566D01*
G03X204092Y1405999I-1333J434D01*
G03X203378Y1407221I-1403J0D01*
G01X203344Y1407240D01*
X203294Y1407302D01*
X203196Y1407651D01*
X203205Y1407729D01*
X203225Y1407764D01*
G03X203414Y1408492I-1313J730D01*
G01Y1408495D01*
G03X201912Y1409998I-1503J0D01*
G01X201779D01*
G02X201663Y1410035I0J200D01*
G01X201638Y1410053D01*
X201608Y1410089D01*
X201597Y1410110D01*
X185319Y1441408D01*
X180208Y1451253D01*
G02X180190Y1451336I182J83D01*
G01X180292Y1451510D01*
G03X181459Y1453504I-1120J1994D01*
G03X179173Y1455790I-2286J0D01*
G03X179062Y1455787I6J-2286D01*
G01Y1456183D01*
G02X179162Y1456210I100J-172D01*
G01X180583D01*
G03X180786Y1456413I0J203D01*
G01Y1457557D01*
X180797Y1457589D01*
X180815Y1457642D01*
X180825Y1457660D01*
G03X181085Y1458622I-1652J963D01*
G01Y1458647D01*
G03X181069Y1458872I-1912J-23D01*
G03X180826Y1459584I-1896J-250D01*
G01X180817Y1459599D01*
X180809Y1459620D01*
X180796Y1459660D01*
G02X180786Y1459720I190J62D01*
G01Y1462676D01*
X180797Y1462708D01*
X180815Y1462761D01*
X180825Y1462779D01*
G03X181085Y1463741I-1652J963D01*
G01Y1463766D01*
G03X181069Y1463991I-1912J-23D01*
G03X180826Y1464703I-1896J-250D01*
G01X180817Y1464718D01*
X180809Y1464739D01*
X180796Y1464779D01*
G02X180786Y1464839I190J62D01*
G01Y1465951D01*
G03X180583Y1466154I-203J0D01*
G01X179162D01*
G02X179062Y1466181I0J199D01*
G01Y1471537D01*
G02X179162Y1471564I100J-172D01*
G01X180583D01*
G03X180786Y1471767I0J203D01*
G01Y1472912D01*
X180797Y1472944D01*
X180815Y1472997D01*
X180825Y1473015D01*
G03X181085Y1473977I-1652J963D01*
G01Y1474002D01*
G03X181069Y1474227I-1912J-23D01*
G03X180826Y1474939I-1896J-250D01*
G01X180817Y1474954D01*
X180809Y1474975D01*
X180796Y1475015D01*
G02X180786Y1475075I190J62D01*
G01Y1478030D01*
X180797Y1478062D01*
X180815Y1478115D01*
X180825Y1478133D01*
G03X181085Y1479095I-1652J963D01*
G01Y1479120D01*
G03X181069Y1479345I-1912J-23D01*
G03X180826Y1480057I-1896J-250D01*
G01X180817Y1480072D01*
X180809Y1480093D01*
X180796Y1480133D01*
G02X180786Y1480193I190J62D01*
G01Y1481305D01*
G03X180583Y1481508I-203J0D01*
G01X178969D01*
G02X178783Y1481634I0J200D01*
G03X177911Y1482959I-3648J-1451D01*
G01X176672Y1484198D01*
G03X174045Y1485345I-2776J-2776D01*
G02X173881Y1485442I8J200D01*
G03X170512Y1487352I-3369J-2016D01*
G01X170509D01*
G03X168873Y1486994I2J-3926D01*
G01X168859Y1486997D01*
X168830Y1487003D01*
G03X168623Y1487065I-533J-1404D01*
G03X168532Y1487082I-321J-1467D01*
G01X168531D01*
X168517Y1487084D01*
G03X168507Y1487086I-299J-1470D01*
G01X168491Y1487088D01*
X168489D01*
X168484Y1487089D01*
X168483D01*
G03X168465Y1487091I-175J-1492D01*
G01X168463D01*
G03X168362Y1487099I-169J-1492D01*
G01X168350D01*
G03X168337Y1487100I-122J-1496D01*
G01X168291D01*
G03X166797Y1485598I8J-1502D01*
G01Y1485592D01*
G03X166886Y1485085I1502J2D01*
G01X166890Y1485075D01*
X166892Y1485067D01*
X166899Y1485047D01*
X166909Y1484990D01*
Y1484988D01*
X166885Y1484931D01*
G03X166586Y1483430I3627J-1503D01*
G01Y1481919D01*
G03X166716Y1480918I3926J1D01*
G01X166723Y1480867D01*
X166716Y1480816D01*
G03X166705Y1480774I3793J-1016D01*
G01X166590Y1480639D01*
X166257Y1480495D01*
X166164Y1480499D01*
X166123Y1480522D01*
G03X165443Y1480820I-1909J-3431D01*
G02X165328Y1480917I62J190D01*
G03X161850Y1483022I-3478J-1821D01*
G03X160552Y1482801I1J-3927D01*
G01X160485Y1482790D01*
G02X160344Y1482848I0J200D01*
G01X158993Y1484198D01*
G03X156722Y1485316I-2777J-2776D01*
G01X156575Y1485413D01*
G03X153189Y1487352I-3386J-1987D01*
G01X153188D01*
G03X151615Y1487023I0J-3926D01*
G01X151549Y1486994D01*
X151516Y1487001D01*
X151488Y1487011D01*
X151464Y1487019D01*
G03X151430Y1487031I-517J-1411D01*
G01X151428D01*
G03X150976Y1487101I-453J-1433D01*
G03X149965Y1486710I0J-1503D01*
G01X149963Y1486707D01*
X149952Y1486697D01*
G03X149948Y1486693I1060J-1064D01*
G01X149929Y1486675D01*
X149885Y1486651D01*
X149849Y1486642D01*
X149732Y1486609D01*
X149694Y1486613D01*
G03X149474Y1486414I-20J-199D01*
G01Y1485593D01*
G03X149582Y1485034I1503J0D01*
G01X149589Y1484995D01*
G03X149262Y1483427I3599J-1569D01*
G01Y1481922D01*
G03X149393Y1480918I3927J2D01*
G01X149400Y1480867D01*
X149393Y1480816D01*
G03X149382Y1480774I3793J-1016D01*
G01X149370Y1480728D01*
X149311Y1480659D01*
X148934Y1480496D01*
X148841Y1480500D01*
X148800Y1480523D01*
G03X148121Y1480820I-1906J-3433D01*
G01X148006Y1480918D01*
G03X144528Y1483022I-3478J-1823D01*
G03X143486Y1482881I1J-3927D01*
G02X143291Y1482933I-53J193D01*
G03X143266Y1482958I-2789J-2764D01*
G01X142026Y1484198D01*
G03X139399Y1485345I-2776J-2776D01*
G02X139235Y1485442I8J200D01*
G03X135866Y1487352I-3369J-2016D01*
G01X135863D01*
G03X134229Y1486995I2J-3926D01*
G01X134211Y1486998D01*
X134185Y1487003D01*
X134169Y1487009D01*
G03X134098Y1487033I-516J-1411D01*
G01X134054Y1487046D01*
G03X133933Y1487074I-399J-1448D01*
G03X133737Y1487098I-280J-1476D01*
G03X133684Y1487100I-83J-1500D01*
G01X133644D01*
G03X132151Y1485598I9J-1502D01*
G01Y1485594D01*
G03X132219Y1485148I1501J1D01*
G01X132220Y1485146D01*
X132230Y1485116D01*
G03X132232Y1485110I1425J472D01*
G01X132233Y1485107D01*
X132237Y1485096D01*
G03X132259Y1485038I1415J504D01*
G01X132267Y1485015D01*
X132269Y1484999D01*
G03X131940Y1483428I3597J-1573D01*
G01Y1481919D01*
G03X132070Y1480918I3926J1D01*
G01X132077Y1480867D01*
X132070Y1480816D01*
G03X132059Y1480774I3793J-1016D01*
G01X132047Y1480728D01*
X131988Y1480659D01*
X131611Y1480496D01*
X131518Y1480500D01*
X131477Y1480523D01*
G03X130798Y1480820I-1906J-3433D01*
G01X130683Y1480918D01*
G03X127205Y1483022I-3478J-1823D01*
G03X126163Y1482881I1J-3927D01*
G02X125968Y1482933I-53J193D01*
G03X125943Y1482958I-2789J-2764D01*
G01X124703Y1484198D01*
G03X122076Y1485345I-2776J-2776D01*
G02X121912Y1485442I8J200D01*
G03X118543Y1487352I-3369J-2016D01*
G01X118542D01*
G03X116969Y1487023I0J-3926D01*
G01X116903Y1486994D01*
X116870Y1487001D01*
X116842Y1487011D01*
X116818Y1487019D01*
G03X116784Y1487031I-517J-1411D01*
G01X116782D01*
G03X116330Y1487101I-453J-1433D01*
G03X115319Y1486710I0J-1503D01*
G01X115317Y1486707D01*
X115306Y1486697D01*
G03X115302Y1486693I1060J-1064D01*
G01X115283Y1486675D01*
X115239Y1486651D01*
X115203Y1486642D01*
X115086Y1486609D01*
X115048Y1486613D01*
G03X114828Y1486414I-20J-199D01*
G01Y1485593D01*
G03X114936Y1485034I1503J0D01*
G01X114943Y1484995D01*
G03X114616Y1483427I3599J-1569D01*
G01Y1481922D01*
G03X114747Y1480918I3927J2D01*
G01X114754Y1480867D01*
X114747Y1480816D01*
G03X114736Y1480774I3793J-1016D01*
G01X114724Y1480728D01*
X114665Y1480659D01*
X114288Y1480496D01*
X114195Y1480500D01*
X114154Y1480523D01*
G03X113475Y1480820I-1906J-3433D01*
G02X113360Y1480917I62J190D01*
G03X109910Y1483021I-3478J-1822D01*
G01X109909D01*
G02X109770Y1483080I3J200D01*
G01X109722Y1483128D01*
G02X109686Y1483178I142J140D01*
G02X109664Y1483269I178J91D01*
G01Y1486718D01*
G02X109864Y1486918I200J0D01*
G01X111292D01*
G03X111473Y1487029I0J203D01*
G01X111476Y1487035D01*
X111479Y1487044D01*
G03X111494Y1487120I-187J76D01*
G01Y1488229D01*
G02X111500Y1488276I200J-2D01*
G01X111516Y1488336D01*
X111531Y1488361D01*
G03Y1490301I-1649J970D01*
G01X111516Y1490326D01*
X111500Y1490386D01*
G02X111494Y1490433I194J49D01*
G01Y1493345D01*
G02X111501Y1493396I200J-1D01*
G01X111516Y1493455D01*
X111531Y1493480D01*
G03X111540Y1493496I-1662J945D01*
G01X111541Y1493498D01*
X111559Y1493529D01*
G03X111795Y1494442I-1677J920D01*
G01X111794Y1494472D01*
Y1494474D01*
G03X111793Y1494523I-1911J-14D01*
G01Y1494525D01*
G03X111708Y1495017I-1911J-77D01*
G03X111530Y1495420I-1827J-566D01*
G01X111527Y1495425D01*
X111516Y1495446D01*
X111506Y1495473D01*
G02X111494Y1495540I188J68D01*
G01Y1496095D01*
X111495Y1496659D01*
G03X111293Y1496862I-203J0D01*
G01X109864D01*
G02X109664Y1497062I0J200D01*
G01Y1502074D01*
G02X109864Y1502274I200J0D01*
G01X111292D01*
G03X111494Y1502476I0J202D01*
G01Y1503583D01*
G02X111500Y1503630I200J-2D01*
G01X111516Y1503690D01*
X111531Y1503715D01*
G03Y1505655I-1649J970D01*
G01X111516Y1505680D01*
X111500Y1505740D01*
G02X111494Y1505787I194J49D01*
G01Y1508702D01*
G02X111500Y1508749I200J-2D01*
G01X111516Y1508809D01*
X111531Y1508834D01*
G03Y1510774I-1649J970D01*
G01X111516Y1510799D01*
X111500Y1510859D01*
G02X111494Y1510906I194J49D01*
G01Y1512014D01*
G03X111292Y1512216I-202J0D01*
G01X110389D01*
G02X110221Y1512308I0J200D01*
G01X110193Y1512351D01*
X110185Y1512451D01*
X110263Y1512622D01*
X110335Y1512680D01*
X110374Y1512689D01*
G03X110545Y1512734I-496J2232D01*
G03X112085Y1514309I-663J2188D01*
G03X112168Y1514886I-2203J611D01*
G01Y1514924D01*
G03X112164Y1515074I-2287J14D01*
G01Y1515076D01*
X112163Y1515105D01*
X112230Y1515211D01*
X117227Y1517282D01*
G02X117402Y1517271I76J-185D01*
G01X117403Y1517270D01*
G03X118542Y1516966I1140J1984D01*
G01X118543D01*
G03X120732Y1518593I0J2286D01*
G01Y1518594D01*
G02X120923Y1518736I191J-58D01*
G01X121962D01*
G03X123465Y1519035I0J3927D01*
G01X161882Y1534952D01*
G03X163155Y1535803I-1504J3627D01*
G01X177911Y1550559D01*
G03X179062Y1553335I-2775J2777D01*
G01Y1558545D01*
G02X179162Y1558572I100J-172D01*
G01X180583D01*
G03X180786Y1558775I0J203D01*
G01Y1559920D01*
X180797Y1559952D01*
X180815Y1560005D01*
X180825Y1560023D01*
G03X181085Y1560985I-1652J963D01*
G01Y1561010D01*
G03X181069Y1561235I-1912J-23D01*
G03X180826Y1561947I-1896J-250D01*
G01X180817Y1561962D01*
X180809Y1561983D01*
X180796Y1562023D01*
G02X180786Y1562083I190J62D01*
G01Y1565038D01*
X180797Y1565070D01*
X180815Y1565123D01*
X180825Y1565141D01*
G03X181085Y1566103I-1652J963D01*
G01Y1566128D01*
G03X181069Y1566353I-1912J-23D01*
G03X180826Y1567065I-1896J-250D01*
G01X180817Y1567080D01*
X180809Y1567101D01*
X180796Y1567141D01*
G02X180786Y1567201I190J62D01*
G01Y1568313D01*
G03X180583Y1568516I-203J0D01*
G01X179162D01*
G02X179062Y1568543I0J199D01*
G01Y1573899D01*
G02X179162Y1573926I100J-172D01*
G01X180583D01*
G03X180786Y1574129I0J203D01*
G01Y1575274D01*
X180797Y1575306D01*
X180815Y1575359D01*
X180825Y1575377D01*
G03X181085Y1576339I-1652J963D01*
G01Y1576364D01*
G03X181069Y1576589I-1912J-23D01*
G03X180826Y1577301I-1896J-250D01*
G01X180817Y1577316D01*
X180809Y1577337D01*
X180796Y1577377D01*
G02X180786Y1577437I190J62D01*
G01Y1580392D01*
X180797Y1580424D01*
X180815Y1580477D01*
X180825Y1580495D01*
G03X181085Y1581457I-1652J963D01*
G01Y1581482D01*
G03X181069Y1581707I-1912J-23D01*
G03X180826Y1582419I-1896J-250D01*
G01X180817Y1582434D01*
X180809Y1582455D01*
X180796Y1582495D01*
G02X180786Y1582555I190J62D01*
G01Y1583667D01*
G03X180583Y1583870I-203J0D01*
G01X178969D01*
G02X178783Y1583996I0J200D01*
G03X177911Y1585321I-3648J-1451D01*
G01X176672Y1586560D01*
G03X174045Y1587707I-2776J-2776D01*
G02X173881Y1587804I8J200D01*
G03X170512Y1589714I-3369J-2016D01*
G01X170509D01*
G03X168873Y1589356I2J-3926D01*
G02X168832Y1589366I27J198D01*
G01X168819Y1589370D01*
X168812Y1589372D01*
X168811D01*
G03X168532Y1589444I-513J-1412D01*
G01X168531D01*
X168517Y1589446D01*
G03X168507Y1589448I-299J-1470D01*
G01X168491Y1589450D01*
X168489D01*
X168484Y1589451D01*
X168483D01*
G03X168465Y1589453I-175J-1492D01*
G01X168463D01*
G03X168362Y1589461I-169J-1492D01*
G01X168350D01*
G03X168337Y1589462I-122J-1496D01*
G01X168291D01*
G03X166797Y1587960I8J-1502D01*
G01Y1587954D01*
G03X166886Y1587447I1502J2D01*
G01X166890Y1587437D01*
X166892Y1587429D01*
X166899Y1587409D01*
X166909Y1587352D01*
Y1587350D01*
X166885Y1587293D01*
G03X166586Y1585792I3627J-1503D01*
G01Y1584281D01*
G03X166716Y1583280I3926J1D01*
G01X166723Y1583229D01*
X166716Y1583178D01*
G03X166705Y1583136I3793J-1016D01*
G01X166590Y1583001D01*
X166257Y1582857D01*
X166164Y1582861D01*
X166123Y1582884D01*
G03X165443Y1583182I-1909J-3431D01*
G02X165328Y1583279I62J190D01*
G03X161850Y1585384I-3478J-1821D01*
G03X160552Y1585163I1J-3927D01*
G01X160485Y1585152D01*
G02X160344Y1585210I0J200D01*
G01X158993Y1586560D01*
G03X156722Y1587678I-2777J-2776D01*
G01X156575Y1587775D01*
G03X153189Y1589714I-3386J-1987D01*
G01X153188D01*
G03X151615Y1589385I0J-3926D01*
G01X151549Y1589356D01*
X151516Y1589363D01*
X151488Y1589373D01*
X151464Y1589381D01*
G03X151430Y1589393I-517J-1411D01*
G01X151428D01*
G03X150976Y1589463I-453J-1433D01*
G03X149965Y1589072I0J-1503D01*
G01X149963Y1589069D01*
X149952Y1589059D01*
G03X149948Y1589055I1060J-1064D01*
G01X149929Y1589037D01*
X149885Y1589013D01*
X149849Y1589004D01*
X149732Y1588971D01*
X149694Y1588975D01*
G03X149474Y1588776I-20J-199D01*
G01Y1587955D01*
G03X149582Y1587396I1503J0D01*
G01X149589Y1587357D01*
G03X149262Y1585789I3599J-1569D01*
G01Y1584284D01*
G03X149393Y1583280I3927J2D01*
G01X149400Y1583229D01*
X149393Y1583178D01*
G03X149382Y1583136I3793J-1016D01*
G01X149370Y1583090D01*
X149311Y1583021D01*
X148934Y1582858D01*
X148841Y1582862D01*
X148800Y1582885D01*
G03X148121Y1583182I-1906J-3433D01*
G01X148006Y1583280D01*
G03X144528Y1585384I-3478J-1823D01*
G03X143486Y1585243I1J-3927D01*
G02X143291Y1585295I-53J193D01*
G03X143266Y1585320I-2789J-2764D01*
G01X142026Y1586560D01*
G03X139399Y1587707I-2776J-2776D01*
G02X139235Y1587804I8J200D01*
G03X135866Y1589714I-3369J-2016D01*
G01X135863D01*
G03X134227Y1589356I2J-3926D01*
G02X134186Y1589366I27J198D01*
G01X134173Y1589370D01*
X134166Y1589372D01*
X134165D01*
G03X133886Y1589444I-513J-1412D01*
G01X133885D01*
X133871Y1589446D01*
G03X133861Y1589448I-299J-1470D01*
G01X133845Y1589450D01*
X133843D01*
X133838Y1589451D01*
X133837D01*
G03X133819Y1589453I-175J-1492D01*
G01X133817D01*
G03X133716Y1589461I-169J-1492D01*
G01X133704D01*
G03X133691Y1589462I-122J-1496D01*
G01X133645D01*
G03X132151Y1587960I8J-1502D01*
G01Y1587954D01*
G03X132240Y1587447I1502J2D01*
G01X132244Y1587437D01*
X132246Y1587429D01*
X132253Y1587409D01*
X132263Y1587352D01*
Y1587350D01*
X132239Y1587293D01*
G03X131940Y1585792I3627J-1503D01*
G01Y1584281D01*
G03X132070Y1583280I3926J1D01*
G01X132077Y1583229D01*
X132070Y1583178D01*
G03X132059Y1583136I3793J-1016D01*
G01X132047Y1583090D01*
X131988Y1583021D01*
X131611Y1582858D01*
X131518Y1582862D01*
X131477Y1582885D01*
G03X130798Y1583182I-1906J-3433D01*
G01X130683Y1583280D01*
G03X127205Y1585384I-3478J-1823D01*
G03X126163Y1585243I1J-3927D01*
G02X125968Y1585295I-53J193D01*
G03X125943Y1585320I-2789J-2764D01*
G01X124703Y1586560D01*
G03X122076Y1587707I-2776J-2776D01*
G02X121912Y1587804I8J200D01*
G03X118543Y1589714I-3369J-2016D01*
G01X118542D01*
G03X116969Y1589385I0J-3926D01*
G01X116903Y1589356D01*
X116870Y1589363D01*
X116842Y1589373D01*
X116818Y1589381D01*
G03X116784Y1589393I-517J-1411D01*
G01X116782D01*
G03X116330Y1589463I-453J-1433D01*
G03X115319Y1589072I0J-1503D01*
G01X115317Y1589069D01*
X115306Y1589059D01*
G03X115302Y1589055I1060J-1064D01*
G01X115283Y1589037D01*
X115239Y1589013D01*
X115203Y1589004D01*
X115086Y1588971D01*
X115048Y1588975D01*
G03X114828Y1588776I-20J-199D01*
G01Y1587955D01*
G03X114936Y1587396I1503J0D01*
G01X114943Y1587357D01*
G03X114616Y1585789I3599J-1569D01*
G01Y1584284D01*
G03X114747Y1583280I3927J2D01*
G01X114754Y1583229D01*
X114747Y1583178D01*
G03X114736Y1583136I3793J-1016D01*
G01X114724Y1583090D01*
X114665Y1583021D01*
X114288Y1582858D01*
X114195Y1582862D01*
X114154Y1582885D01*
G03X113475Y1583182I-1906J-3433D01*
G01X113360Y1583280D01*
G03X109882Y1585384I-3478J-1823D01*
G03X108244Y1585025I2J-3927D01*
G01X108207Y1585033D01*
G03X107690Y1585131I-534J-1405D01*
G01X107673D01*
G03X106658Y1584740I-4J-1502D01*
G01X106656Y1584738D01*
X106641Y1584724D01*
X106622Y1584706D01*
X106578Y1584682D01*
X106542Y1584673D01*
X106425Y1584640D01*
X106387Y1584644D01*
G03X106167Y1584445I-20J-199D01*
G01Y1583626D01*
G03X106267Y1583088I1502J1D01*
G01X106273Y1583073D01*
X106282Y1583031D01*
Y1583023D01*
G03X105956Y1581457I3598J-1566D01*
G01Y1579953D01*
G03X105987Y1579454I3926J-7D01*
G01X105989Y1579441D01*
Y1578355D01*
X105987Y1578342D01*
G03X105956Y1577843I3895J-492D01*
G01Y1576339D01*
G03X105987Y1575840I3926J-7D01*
G01X105989Y1575827D01*
Y1574809D01*
G03X106048Y1574667I200J0D01*
G01X106129Y1574586D01*
G02X106186Y1574446I-143J-140D01*
G01Y1574406D01*
X106184Y1574391D01*
G03X106167Y1574178I1485J-226D01*
G01Y1574167D01*
G03X107664Y1572665I1502J0D01*
G01X107701D01*
G03X107715Y1572666I-100J1497D01*
G01X107722D01*
G02X107916Y1572419I0J-200D01*
G01X107904Y1572369D01*
X107890Y1572344D01*
G03X107596Y1571264I1992J-1122D01*
G01Y1571256D01*
X107595Y1571221D01*
G03X109242Y1569025I2288J0D01*
G01X109257Y1569021D01*
X109283Y1569009D01*
X109311Y1568993D01*
G02X109360Y1568953I-100J-173D01*
G01X109429Y1568864D01*
G02X109467Y1568751I-162J-117D01*
G01Y1568716D01*
G02X109267Y1568516I-200J0D01*
G01X108472D01*
G03X108291Y1568405I0J-203D01*
G01X108288Y1568399D01*
X108285Y1568390D01*
G03X108270Y1568314I187J-76D01*
G01Y1567205D01*
G02X108264Y1567158I-200J2D01*
G01X108248Y1567098D01*
X108233Y1567073D01*
G03Y1565133I1649J-970D01*
G01X108248Y1565108D01*
X108264Y1565048D01*
G02X108270Y1565001I-194J-49D01*
G01Y1562087D01*
G02X108262Y1562032I-200J1D01*
G01X108256Y1562010D01*
X108249Y1561982D01*
X108234Y1561957D01*
G03X107969Y1560986I1648J-971D01*
G01Y1560985D01*
G03X108038Y1560478I1912J2D01*
G03X108242Y1560003I1843J510D01*
G01X108263Y1559953D01*
X108270Y1559929D01*
Y1559339D01*
X108269Y1558775D01*
G03X108471Y1558572I203J0D01*
G01X109267D01*
G02X109467Y1558372I0J-200D01*
G01Y1558314D01*
X109448Y1558266D01*
X109437Y1558237D01*
X109358Y1558135D01*
X109331Y1558117D01*
X109261Y1558069D01*
X109231Y1558059D01*
G03X107596Y1555867I652J-2192D01*
G01Y1555854D01*
G03X107657Y1555341I2286J12D01*
G01Y1555340D01*
X107663Y1555318D01*
G02X107634Y1555162I-195J-44D01*
G01Y1555161D01*
X106970Y1554168D01*
Y1554166D01*
X106898Y1554058D01*
X106643Y1553677D01*
G02X106553Y1553603I-167J111D01*
G01X105527Y1553178D01*
X105525D01*
X105405Y1553127D01*
X105403Y1553128D01*
X103916Y1552510D01*
X102427Y1551894D01*
X102426Y1551892D01*
X101390Y1551463D01*
X101388D01*
X101268Y1551412D01*
X101266Y1551413D01*
X99779Y1550795D01*
X98290Y1550179D01*
X98283Y1550165D01*
X98236Y1550051D01*
Y1550049D01*
X98045Y1549592D01*
G02X97954Y1549499I-181J86D01*
G01X95520Y1548490D01*
G03X95455Y1548446I77J-184D01*
G01X95419Y1548410D01*
X95412Y1548402D01*
G02X94804Y1548509I-260J304D01*
G03X93496Y1549271I-1308J-742D01*
G03X91993Y1547768I0J-1503D01*
G03X92437Y1546702I1502J0D01*
G02Y1546135I-282J-284D01*
G01X91371Y1545069D01*
G03X91341Y1545039I2738J-2768D01*
G01X91340Y1545037D01*
X87123Y1540821D01*
G03X87064Y1540679I141J-142D01*
G01Y1540228D01*
G02X87005Y1540086I-200J0D01*
G01X81905Y1534985D01*
G03X81460Y1534454I2775J-2777D01*
G01X81450Y1534440D01*
X81346Y1534336D01*
G03X80819Y1533680I2753J-2751D01*
G03X80503Y1533073I3280J-2093D01*
G01X80133Y1532181D01*
X80128Y1532173D01*
X77454Y1525719D01*
G02X77452Y1525713I-191J60D01*
G01X74319Y1518751D01*
G03X73981Y1517376I3581J-1609D01*
G01X73926Y1516478D01*
G02X73918Y1516431I-200J10D01*
G01X61023Y1475204D01*
X61021Y1475197D01*
X61014Y1475175D01*
Y1250961D01*
X61031Y1250920D01*
X63650Y1244595D01*
X63716Y1244436D01*
X64815Y1241782D01*
X67129Y1236192D01*
X67135Y1236151D01*
Y1213192D01*
G02X67134Y1213173I-200J1D01*
G01X67124Y1213111D01*
X67118Y1213093D01*
X67092Y1213017D01*
X67070Y1212990D01*
G03X67060Y1211131I1175J-936D01*
G01X67072Y1211116D01*
X67097Y1211069D01*
X67105Y1211054D01*
X67125Y1210993D01*
G02X67135Y1210933I-190J-62D01*
G01Y1192013D01*
X67132Y1191996D01*
X67125Y1191954D01*
X67110Y1191905D01*
X67107Y1191899D01*
G03X66029Y1186674I12224J-5246D01*
G01Y1186653D01*
G03X67111Y1181398I13302J0D01*
G01X67114Y1181392D01*
X67136Y1181341D01*
X67135Y1181299D01*
Y1012170D01*
G02X67121Y1012095I-200J-1D01*
G01X67106Y1012059D01*
X59948Y1004901D01*
G02X59898Y1004865I-140J142D01*
G02X59807Y1004843I-91J178D01*
G01X50102D01*
G02X49921Y1004959I1J200D01*
G01X49886Y1005035D01*
Y1005037D01*
X49789Y1005254D01*
G02X49771Y1005336I182J83D01*
G01Y1005397D01*
G02X49784Y1005467I200J-1D01*
G01X49796Y1005500D01*
X49820Y1005528D01*
G03X50185Y1006510I-1138J982D01*
G03X48683Y1008012I-1502J0D01*
G03X47191Y1006686I0J-1502D01*
G01X47185Y1006632D01*
G03X47562Y1005509I1498J-122D01*
G01X47563Y1005508D01*
G02X47611Y1005406I-150J-133D01*
G01X47615Y1005379D01*
X47608Y1005322D01*
X47522Y1005128D01*
X47448Y1004962D01*
Y1004961D01*
G02X47284Y1004844I-182J82D01*
G02X47266Y1004843I-20J199D01*
G01X43646D01*
G02X43460Y1004969I0J200D01*
G01X43416Y1005095D01*
Y1005097D01*
X43334Y1005333D01*
X43332Y1005342D01*
X43324Y1005366D01*
X43323Y1005427D01*
X43332Y1005456D01*
G02X43399Y1005555I192J-57D01*
G01X43400Y1005556D01*
G03X43972Y1006736I-931J1180D01*
G01Y1006768D01*
X43971Y1006798D01*
G03X40969I-1501J-60D01*
G01X40968Y1006768D01*
Y1006732D01*
G03X41538Y1005560I1502J6D01*
G01X41570Y1005535D01*
X41593Y1005493D01*
G02X41594Y1005490I-186J-64D01*
G02X41617Y1005416I-176J-95D01*
G01Y1005412D01*
X41627Y1005279D01*
X41616Y1005244D01*
X41612Y1005229D01*
G02X41574Y1005154I-193J51D01*
G01X41543Y1005116D01*
G03X41505Y1005043I155J-127D01*
G01Y1005042D01*
X41502Y1005032D01*
X41481Y1004974D01*
G02X41426Y1004894I-187J70D01*
G02X41295Y1004843I-133J149D01*
G01X38095D01*
G02X37992Y1004872I1J200D01*
G01X37966Y1004888D01*
X37932Y1004926D01*
X37919Y1004950D01*
X37899Y1004988D01*
X37754Y1005265D01*
G02X37732Y1005369I178J92D01*
G01X37735Y1005423D01*
X37767Y1005470D01*
G03X38031Y1006320I-1238J851D01*
G01Y1006344D01*
G03X36529Y1007823I-1502J-23D01*
G01X36512D01*
G03X35682Y1007562I16J-1502D01*
G03X35444Y1007361I845J-1242D01*
G01X35417Y1007333D01*
X35276Y1007271D01*
X35231Y1007272D01*
G03X35027Y1007073I-4J-200D01*
G01Y1006320D01*
G03X35277Y1005490I1502J0D01*
G01X35291Y1005469D01*
X35325Y1005373D01*
X35321Y1005328D01*
X35317Y1005286D01*
X35154Y1004977D01*
X35152Y1004973D01*
X35150Y1004971D01*
G03X35142Y1004956I172J-101D01*
G02X35068Y1004873I-180J86D01*
G01X35045Y1004858D01*
X34991Y1004843D01*
X31899D01*
G02X31852Y1004849I2J200D01*
G02X31717Y1004960I47J194D01*
G01X31653Y1005101D01*
Y1005103D01*
X31567Y1005295D01*
G02X31552Y1005407I183J81D01*
G01X31557Y1005436D01*
X31580Y1005487D01*
X31600Y1005509D01*
G03X31981Y1006509I-1122J1000D01*
G03X30479Y1008011I-1502J0D01*
G03X28987Y1006685I0J-1502D01*
G01X28981Y1006631D01*
G03X29357Y1005509I1498J-122D01*
G01X29358Y1005508D01*
G02X29406Y1005406I-150J-133D01*
G01X29410Y1005378D01*
X29403Y1005321D01*
X29241Y1004961D01*
G02X29059Y1004843I-182J82D01*
G01X25952D01*
G02X25787Y1004951I13J200D01*
G01X25775Y1004975D01*
X25627Y1005278D01*
G02X25608Y1005385I180J87D01*
G01X25610Y1005412D01*
X25631Y1005464D01*
X25648Y1005486D01*
G03X25958Y1006399I-1192J914D01*
G01Y1006433D01*
G03X24456Y1007903I-1502J-32D01*
G03X22954Y1006432I0J-1502D01*
G01Y1006399D01*
G03X23264Y1005486I1502J1D01*
G01X23281Y1005464D01*
X23302Y1005412D01*
X23304Y1005385D01*
G02X23285Y1005278I-199J-20D01*
G01X23160Y1005021D01*
X23159Y1005020D01*
X23126Y1004954D01*
G02X23046Y1004869I-179J89D01*
G02X22948Y1004843I-99J174D01*
G01X3940D01*
G02X3798Y1004902I0J200D01*
G01X2559Y1006141D01*
G02X2500Y1006283I141J142D01*
G01Y1637794D01*
G02X2700Y1637993I200J-1D01*
G01X2737Y1637990D01*
G03X3014Y1637964I278J1476D01*
G01X3017D01*
G03X4235Y1638587I0J1502D01*
G02X4397Y1638670I162J-117D01*
G01X206537D01*
G02X206569Y1638667I-3J-200D01*
G01X206571D01*
G02X206677Y1638613I-34J-197D01*
G01X207270Y1638020D01*
G02X207323Y1637918I-143J-139D01*
G02X207327Y1637880I-196J-40D01*
G01Y1552964D01*
G03X207386Y1552822I200J0D01*
G01X208170Y1552038D01*
G03X208312Y1551979I142J141D01*
G01X261783D01*
G03X261925Y1552038I0J200D01*
G01X262055Y1552168D01*
G03X262114Y1552310I-141J142D01*
G01Y1638340D01*
G02X262118Y1638378I200J-2D01*
G02X262171Y1638480I196J-37D01*
G01X262304Y1638613D01*
G02X262406Y1638666I139J-143D01*
G02X262444Y1638670I40J-196D01*
G01X555012D01*
G02X555210Y1638501I0J-200D01*
G01Y1552383D01*
G03X555466Y1552083I304J0D01*
G01X555475Y1552081D01*
X555496Y1552070D01*
G02X555506Y1552064I-98J-174D01*
G02X555541Y1552036I-107J-169D01*
G01X555850Y1551727D01*
G03X555992Y1551668I142J141D01*
G01X608170D01*
G03X608312Y1551727I0J200D01*
G01X608338Y1551753D01*
X608353Y1551789D01*
G03X608368Y1551865I-185J76D01*
G01Y1552391D01*
G02X608405Y1552507I200J0D01*
G01X608570Y1552672D01*
Y1638502D01*
G02X608767Y1638670I197J-32D01*
G37*
G36*
G01X173112Y554909D02*
G03X172893Y554893I0J-1502D01*
G01X172882Y554891D01*
X172862Y554890D01*
G02X172723Y554937I-10J200D01*
G01X172674Y554979D01*
G02X172603Y555126I129J153D01*
G01X172508Y563969D01*
X172481Y566477D01*
X172464Y568030D01*
G02X172509Y568159I200J3D01*
G01X172706Y568377D01*
G02X172824Y568433I140J-143D01*
G01X172827D01*
G03X172874Y568438I-135J1496D01*
G01X172875D01*
G02X173006Y568408I23J-199D01*
G01X173239Y568245D01*
G02X173311Y568145I-118J-161D01*
G01X173314Y568131D01*
G03X174776Y566973I1462J344D01*
G03X175345Y567085I0J1501D01*
G02X175436Y567099I75J-185D01*
G01X175480Y567096D01*
X175806Y566902D01*
G02X175892Y566767I-112J-166D01*
G01X175893Y566759D01*
Y566758D01*
G03X177385Y565427I1492J171D01*
G03X178887Y566928I0J1502D01*
G01Y566929D01*
G03X178885Y567013I-1502J6D01*
G02X178886Y567035I200J2D01*
G03X178899Y567228I-1489J197D01*
G01Y567229D01*
G03X178400Y568348I-1504J0D01*
G01X178368Y568377D01*
X178351Y568415D01*
X178338Y568443D01*
X178325Y568548D01*
X178324Y568554D01*
X178363Y568615D01*
G03X178601Y569426I-1263J811D01*
G03X178599Y569512I-1502J8D01*
G02X178600Y569540I200J7D01*
G03X178611Y569723I-1502J182D01*
G01Y569726D01*
G03X177100Y571238I-1512J0D01*
G01X177099D01*
G03X176936Y571228I11J-1511D01*
G01X176897Y571224D01*
X176862Y571233D01*
G02X176806Y571258I52J193D01*
G01X176658Y571367D01*
X176655Y571370D01*
X176630Y571390D01*
G02X176600Y571423I132J150D01*
G01X176592Y571436D01*
G02X176568Y571491I169J107D01*
G03X175033Y572813I-1535J-230D01*
G03X173596Y571846I0J-1551D01*
G01X173593Y571838D01*
X173586Y571824D01*
G02X173501Y571742I-175J97D01*
G01X173414Y571704D01*
X173412D01*
X173363Y571683D01*
G02X173290Y571667I-79J184D01*
G01X173253Y571666D01*
X173217Y571679D01*
G03X173077Y571723I-533J-1450D01*
G01X173069Y571725D01*
X173055Y571729D01*
X173039Y571733D01*
X173011Y571753D01*
G02X172962Y571803I116J163D01*
G01X172849Y571981D01*
Y571983D01*
X172841Y571995D01*
Y572070D01*
G03X172835Y572201I-1502J-3D01*
G01X172834Y572211D01*
Y572219D01*
X172835Y572235D01*
G03X172841Y572367I-1496J134D01*
G01Y572370D01*
G03X172447Y573385I-1503J1D01*
G02X172445Y573387I140J142D01*
G01X172406Y573431D01*
Y573472D01*
X172367Y577050D01*
X172360Y577660D01*
Y577674D01*
X172516Y580200D01*
X173893Y602590D01*
Y602594D01*
X184221Y735009D01*
X193396Y852624D01*
G02X193499Y852665I123J-158D01*
G02X193517Y852666I20J-199D01*
G01X208360D01*
G02X208377Y852665I-3J-200D01*
G02X208542Y852532I-24J-199D01*
G01X208550Y852508D01*
G02X208561Y852453I-189J-66D01*
G01X216859Y693047D01*
X220066Y631416D01*
G02X220024Y631283I-200J-10D01*
G01X220002Y631255D01*
X219942Y631218D01*
X219908Y631211D01*
X219898Y631208D01*
X219893Y631207D01*
G03X218753Y629749I362J-1458D01*
G03X220066Y628259I1502J0D01*
G01X220081Y628257D01*
G02X220189Y628196I-40J-196D01*
G01X220212Y628171D01*
X220225Y628141D01*
G02X220240Y628084I-184J-79D01*
G01X220667Y619834D01*
G02X220663Y619804I-199J11D01*
G01X220619Y619717D01*
G02X220604Y619696I-169J105D01*
G01X220591Y619680D01*
X220447Y619521D01*
G02X220445Y619519I-142J140D01*
G01X220423Y619495D01*
G02X220360Y619449I-147J136D01*
G01X220325Y619433D01*
X220283Y619431D01*
G03X218831Y617930I50J-1501D01*
G03X220333Y616428I1502J0D01*
G03X220441Y616432I-2J1502D01*
G01X220473Y616434D01*
X220481Y616435D01*
X220519Y616422D01*
G02X220583Y616386I-64J-189D01*
G01X220620Y616353D01*
X220810Y616183D01*
G02X220812Y616181I-140J-142D01*
G02X220825Y616165I-148J-134D01*
G01X220849Y616125D01*
G02X220861Y616092I-181J-85D01*
G01Y616090D01*
G02X220866Y616067I-193J-54D01*
G01X221277Y608177D01*
X221266Y608143D01*
X221260Y608123D01*
X221246Y608088D01*
G03X221144Y607542I1400J-544D01*
G01Y607518D01*
G03X221327Y606823I1502J24D01*
G01X221338Y606803D01*
X221350Y606760D01*
X221593Y602103D01*
X221824Y597653D01*
Y597636D01*
G02X221800Y597547I-200J6D01*
G01X221786Y597523D01*
X221623Y597335D01*
X221607Y597316D01*
X221596Y597304D01*
X221559Y597285D01*
X221500Y597280D01*
G03X220048Y596599I192J-2298D01*
G02X220046Y596597I-142J140D01*
G01X205640Y582190D01*
G02X205556Y582140I-141J142D01*
G02X205499Y582132I-56J192D01*
G01X196172D01*
G03X194542Y581457I0J-2306D01*
G01X192432Y579348D01*
G03X191932Y578599I1632J-1631D01*
G03X191756Y577723I2131J-884D01*
G01Y577716D01*
G03X192452Y576065I2306J0D01*
G02X192454Y576063I-140J-142D01*
G01X194148Y574369D01*
G03X195778Y573694I1630J1631D01*
G01X201300D01*
G03X202682Y574154I0J2306D01*
G02X202912Y574161I120J-160D01*
G03X203740Y573912I828J1252D01*
G03X205242Y575414I0J1502D01*
G01Y575444D01*
X206450D01*
G03X206946Y575498I0J2307D01*
G02X207115Y575459I44J-195D01*
G01X207357Y575264D01*
G02X207432Y575108I-125J-156D01*
G01Y557786D01*
G02X207410Y557695I-200J0D01*
G02X207374Y557645I-178J90D01*
G01X203043Y553314D01*
G03X202368Y551683I1631J-1630D01*
G01X202367Y551635D01*
G03X204674Y549376I2307J49D01*
G01X204710D01*
G03X205567Y549556I-37J2307D01*
G03X206306Y550052I-892J2127D01*
G01X211370Y555116D01*
G03X212046Y556747I-1631J1632D01*
G01Y577307D01*
G02X212050Y577345I200J-2D01*
G02X212103Y577447I196J-37D01*
G01X221818Y587162D01*
G02X221931Y587218I141J-142D01*
G02X222384Y586868I56J-395D01*
G02X222385Y586856I-199J-23D01*
G01X222824Y578433D01*
X223280Y569661D01*
Y569660D01*
G02X223241Y569530I-200J-11D01*
G01X223221Y569503D01*
X223165Y569465D01*
X223130Y569456D01*
G03X222008Y568177I370J-1456D01*
G01Y568176D01*
X222004Y568143D01*
G03X221998Y568015I1496J-134D01*
G03Y568000I1502J-7D01*
G01Y567994D01*
G03X223284Y566513I1503J6D01*
G01X223319Y566506D01*
X223369Y566483D01*
X223391Y566463D01*
G02X223448Y566370I-136J-147D01*
G01X223452Y566352D01*
G02X223453Y566341I-198J-24D01*
G01X223480Y565840D01*
X223538Y564729D01*
Y564713D01*
X223529Y564654D01*
X223521Y564628D01*
X223505Y564603D01*
X223463Y564539D01*
X222967Y563782D01*
X222966Y563781D01*
X222959Y563773D01*
X222958Y563772D01*
G03X222888Y563685I1135J-985D01*
G01X222846Y563629D01*
G02X222634Y563628I-107J169D01*
G01X222531Y563691D01*
G03X222296Y562800I1574J-892D01*
G03X223538Y561082I1809J0D01*
G01X223541Y561081D01*
G02X223633Y561015I-66J-189D01*
G01X223698Y560933D01*
G02X223740Y560821I-158J-123D01*
G01X223760Y560445D01*
Y560407D01*
X223748Y560368D01*
G02X223727Y560324I-189J63D01*
G01X223709Y560296D01*
X223658Y560257D01*
X223621Y560244D01*
G03X222538Y558800I421J-1444D01*
G03X223741Y557327I1503J0D01*
G01X223767Y557321D01*
X223831Y557289D01*
G02X223934Y557131I-96J-175D01*
G01X223954Y556728D01*
X223962Y556559D01*
Y556541D01*
G02X223904Y556408I-200J8D01*
G01X223876Y556380D01*
X223825Y556344D01*
X223812Y556337D01*
G03X222997Y555000I689J-1337D01*
G03X223003Y554870I1503J4D01*
G01X223008Y554824D01*
G03X223940Y553604I1493J174D01*
G01X223952Y553599D01*
X223968Y553590D01*
X224006Y553571D01*
X224075Y553479D01*
X224078Y553473D01*
X224088Y553461D01*
G02X224106Y553435I-155J-127D01*
G02X224128Y553369I-176J-95D01*
G01X224173Y552523D01*
X224216Y551678D01*
G02X224215Y551657I-200J-1D01*
G01X224212Y551642D01*
G02X224211Y551638I-194J46D01*
G03X224209Y551632I188J-66D01*
G02X224208Y551627I-196J37D01*
G01X224207Y551626D01*
X224204Y551615D01*
G02X224172Y551557I-189J66D01*
G01X224145Y551526D01*
X224113Y551489D01*
G02X224097Y551473I-149J133D01*
G02X224059Y551446I-134J148D01*
G01X224013Y551421D01*
X224010Y551419D01*
X223968Y551396D01*
X223934Y551390D01*
G03X222588Y549800I266J-1590D01*
G03X223060Y548661I1610J0D01*
G02X223118Y548504I-142J-141D01*
G01X223108Y548369D01*
X223105Y548329D01*
X223067Y548253D01*
X223035Y548226D01*
G03X222498Y547075I965J-1151D01*
G03X224000Y545573I1502J0D01*
G01X224011D01*
G03X224127Y545577I6J1503D01*
G01X224154Y545579D01*
X224159D01*
X224167Y545580D01*
X224204Y545568D01*
G02X224269Y545531I-65J-189D01*
G01X224358Y545454D01*
X224373Y545442D01*
X224489Y545338D01*
G02X224536Y545276I-133J-150D01*
G01X224553Y545239D01*
X224608Y544174D01*
X224713Y542144D01*
Y542127D01*
G02X224708Y542088I-200J6D01*
G02X224631Y541974I-194J48D01*
G01X224596Y541953D01*
X224588Y541949D01*
X224579Y541946D01*
G03X223494Y540500I421J-1446D01*
G03X224657Y539033I1507J0D01*
G01X224664Y539031D01*
X224684Y539025D01*
X224730Y539007D01*
X224747Y538997D01*
X224819Y538915D01*
X224823Y538910D01*
G03X224828Y538905I144J139D01*
G01X224855Y538878D01*
X224871Y538843D01*
G02X224887Y538783I-183J-81D01*
G01X225120Y534333D01*
X225259Y531634D01*
G02X225221Y531527I-199J11D01*
G02X225132Y531458I-162J117D01*
G01X225110Y531452D01*
G03X223997Y530007I390J-1452D01*
G01Y530000D01*
G03X225267Y528515I1503J0D01*
G01X225268D01*
X225339Y528474D01*
G02X225392Y528426I-105J-170D01*
G02X225432Y528326I-159J-121D01*
G01X232895Y384941D01*
X234139Y361044D01*
Y361031D01*
G02X234074Y360886I-200J3D01*
G01X233824Y360684D01*
X233797Y360662D01*
X233766Y360651D01*
G02X233698Y360639I-68J188D01*
G01X233641D01*
X233617Y360645D01*
G03X233261Y360688I-357J-1459D01*
G01X233258D01*
G03Y357684I0J-1502D01*
G03X233789Y357781I0J1502D01*
G01X233790D01*
G02X233881Y357793I71J-187D01*
G01X233928Y357788D01*
X234129Y357656D01*
G03X234182Y357632I108J168D01*
G02X234326Y357457I-55J-192D01*
G01X234339Y357214D01*
X234344Y357118D01*
X234409Y355864D01*
X234766Y349008D01*
X235056Y343434D01*
X235046Y343390D01*
X235021Y343338D01*
X235004Y343313D01*
X235002Y343310D01*
X235000Y343308D01*
Y343307D01*
X234988Y343290D01*
X234972Y343262D01*
G03X234761Y342496I1292J-768D01*
G01X234762Y342456D01*
G03X235114Y341526I1503J37D01*
G01X235115Y341525D01*
X235133Y341503D01*
X235146Y341474D01*
X235149Y341468D01*
G02X235162Y341414I-186J-73D01*
G01X235184Y340977D01*
X235201Y340650D01*
Y340648D01*
X235206Y340545D01*
G02X235205Y340524I-200J-1D01*
G01X235200Y340491D01*
X235158Y340407D01*
X235142Y340389D01*
G03X234778Y339409I1138J-980D01*
G01Y339407D01*
G03X235262Y338304I1501J1D01*
G01X235272Y338294D01*
G02X235329Y338177I-141J-141D01*
G01X235332Y338140D01*
X235337Y338032D01*
Y338030D01*
X235339Y337988D01*
X235324Y337950D01*
G02X235279Y337880I-187J71D01*
G01X235218Y337819D01*
X235176Y337805D01*
X235167Y337799D01*
X235159Y337794D01*
G03X235127Y337767I112J-166D01*
G01X235120Y337760D01*
X235106Y337745D01*
X235059Y337695D01*
X235026Y337681D01*
X234982Y337664D01*
X234946Y337663D01*
G03X234663Y334694I40J-1502D01*
G03X234969Y334659I323J1467D01*
G01X234997D01*
G03X235089Y334663I-19J1502D01*
G01X235121D01*
G02X235246Y334618I-1J-200D01*
G01X235264Y334603D01*
X235269Y334598D01*
X235465Y334425D01*
G02X235532Y334286I-133J-150D01*
G01X239214Y263547D01*
X239717Y253887D01*
Y253875D01*
X239694Y247535D01*
X239688Y245755D01*
G02X239487Y245566I-200J11D01*
G01X239434D01*
X239388Y245593D01*
X239386D01*
G03X239324Y245628I-769J-1290D01*
G01X239297Y245641D01*
G03X239002Y245752I-674J-1343D01*
G01X238986Y245756D01*
G03X238637Y245799I-357J-1459D01*
G01X238615D01*
G03X238299Y245764I6J-1503D01*
G01X238293Y245763D01*
X238277Y245759D01*
X238276D01*
X238256Y245754D01*
X238224Y245750D01*
G02X238076Y245799I-16J199D01*
G01X238056Y245819D01*
X237836Y246075D01*
G02X237792Y246200I156J125D01*
G01Y246255D01*
X237803Y246313D01*
X237812Y246345D01*
X237815Y246353D01*
G03X237908Y246863I-1409J520D01*
G01Y246883D01*
G03X236406Y248376I-1502J-9D01*
G03Y245372I0J-1502D01*
G01X236410D01*
G03X236763Y245414I0J1502D01*
G01X236779Y245418D01*
X236807Y245421D01*
G02X236968Y245361I17J-199D01*
G01X236974Y245354D01*
X236975Y245353D01*
X237056Y245259D01*
X237213Y245077D01*
G02X237254Y244976I-158J-123D01*
G01X237255Y244969D01*
X237260Y244925D01*
X237245Y244888D01*
G03X237164Y244642I1381J-591D01*
G03X237126Y244380I1462J-346D01*
G03X237124Y244314I1500J-78D01*
G01Y244292D01*
G03X238606Y242795I1502J5D01*
G01X238630D01*
G03X238632I1J1502D01*
G03X239126Y242880I-4J1502D01*
G01X239139Y242885D01*
X239201Y242897D01*
G02X239216I7J-200D01*
G01X239232Y242896D01*
G02X239322Y242861I-25J-198D01*
G01X239323D01*
X239539Y242709D01*
X239597Y242668D01*
G02X239623Y242644I-122J-159D01*
G01X239635Y242630D01*
G02X239676Y242516I-159J-122D01*
G01X239675Y242317D01*
X239668Y240152D01*
Y240077D01*
Y240073D01*
X239676Y239551D01*
X239657Y239520D01*
G03X239619Y237972I1269J-806D01*
G03X239674Y237882I1309J738D01*
G01X239687Y237862D01*
X239695Y237836D01*
G02X239703Y237781I-192J-56D01*
G01X239805Y231214D01*
G02X239795Y231146I-200J-5D01*
G01X239783Y231112D01*
X239756Y231081D01*
G03X239406Y230124I1153J-964D01*
G01X239407Y230084D01*
G03X239546Y229484I1502J32D01*
G03X239569Y229437I1361J637D01*
G03X239808Y229093I1342J677D01*
G02X239810Y229091I-140J-142D01*
G01X239814Y229087D01*
X239841Y229019D01*
X240005Y218486D01*
Y218476D01*
X239815Y213631D01*
X239156Y196799D01*
G02X239103Y196671I-200J8D01*
G01X239076Y196644D01*
X238781Y196484D01*
X238763Y196476D01*
X238746Y196467D01*
G02X238677Y196448I-87J180D01*
G01X238640Y196445D01*
X238556Y196469D01*
X238533Y196482D01*
G03X237792Y196678I-742J-1306D01*
G01X237777D01*
G03X237626Y196669I14J-1502D01*
G03X236859Y196354I165J-1493D01*
G01X236840Y196339D01*
X236818Y196329D01*
X236797Y196318D01*
X236753Y196308D01*
X236646D01*
G03X236563Y196290I0J-200D01*
G01X236510Y196266D01*
G02X236302Y196291I-84J181D01*
G01X236274Y196313D01*
X236256Y196327D01*
X236253Y196329D01*
G03X235292Y196678I-962J-1152D01*
G01X235253D01*
G03X234409Y196392I38J-1502D01*
G01X234375Y196368D01*
X234355Y196351D01*
G02X234326Y196333I-120J161D01*
G01X234318Y196329D01*
G02X234229Y196308I-89J179D01*
G01X234146D01*
G03X234063Y196290I0J-200D01*
G01X234010Y196266D01*
G02X233802Y196291I-84J181D01*
G01X233774Y196313D01*
X233756Y196327D01*
X233753Y196329D01*
G03X232792Y196678I-962J-1152D01*
G01X232753D01*
G03X231909Y196392I38J-1502D01*
G01X231875Y196368D01*
X231855Y196351D01*
G02X231826Y196333I-120J161D01*
G01X231818Y196329D01*
G02X231729Y196308I-89J179D01*
G01X231646D01*
G03X231563Y196290I0J-200D01*
G01X231510Y196266D01*
G02X231302Y196291I-84J181D01*
G01X231274Y196313D01*
X231256Y196327D01*
X231253Y196329D01*
G03X230292Y196678I-962J-1152D01*
G01X230291D01*
G03Y193674I0J-1502D01*
G01X230292D01*
G03X231226Y194000I0J1502D01*
G01X231245Y194015D01*
X231274Y194028D01*
G02X231352Y194044I78J-184D01*
G01X231436D01*
G03X231519Y194062I0J200D01*
G01X231572Y194086D01*
G02X231780Y194061I84J-181D01*
G01X231808Y194039D01*
X231826Y194025D01*
X231829Y194023D01*
G03X232790Y193674I962J1152D01*
G01X232829D01*
G03X233725Y193999I-38J1502D01*
G01X233745Y194015D01*
X233776Y194029D01*
G02X233852Y194044I76J-185D01*
G01X233936D01*
G03X234019Y194062I0J200D01*
G01X234072Y194086D01*
G02X234280Y194061I84J-181D01*
G01X234308Y194039D01*
X234326Y194025D01*
X234329Y194023D01*
G03X235290Y193674I962J1152D01*
G01X235329D01*
G03X236225Y193999I-38J1502D01*
G01X236245Y194015D01*
X236276Y194029D01*
G02X236352Y194044I76J-185D01*
G01X236436D01*
G03X236507Y194057I0J200D01*
G01X236510Y194058D01*
X236514Y194060D01*
G03X236519Y194062I-72J187D01*
G01X236520D01*
X236573Y194086D01*
G02X236730Y194085I77J-184D01*
G01X236780Y194059D01*
X236788Y194055D01*
X236802Y194044D01*
X236811Y194037D01*
X236814Y194034D01*
G03X237791Y193674I977J1146D01*
G01X237814D01*
G03X238236Y193741I-22J1502D01*
G01X238299Y193762D01*
G03X238388Y193797I-505J1415D01*
G01X238402Y193804D01*
X238408Y193806D01*
G03X238416Y193810I-666J1342D01*
G01X238429Y193816D01*
X238449Y193825D01*
X238508Y193838D01*
G02X238538Y193840I28J-198D01*
G01X238586Y193838D01*
X238650Y193814D01*
X238669Y193801D01*
X238935Y193625D01*
G02X239025Y193463I-110J-167D01*
G01X238971Y192073D01*
X238672Y184460D01*
G02X238671Y184441I-200J1D01*
G01X234986Y157164D01*
G03X234951Y156699I3891J-527D01*
G01X234930Y155394D01*
X234920Y155350D01*
X234910Y155331D01*
G03X234503Y153648I3519J-1742D01*
G01X234477Y151975D01*
Y151974D01*
G03X234472Y151780I3862J-197D01*
G01Y151777D01*
G03X234473Y151696I3892J8D01*
G01Y151686D01*
G03X234472Y151638I3925J-106D01*
G01Y151636D01*
G03X234490Y151262I3927J2D01*
G03X234585Y150706I3908J382D01*
G01Y150705D01*
X234594Y150665D01*
X234532Y150284D01*
G03X234509Y150120I3841J-622D01*
G03X234482Y149658I3864J-458D01*
G01Y149573D01*
G03Y149570I200J-2D01*
G01X234483Y149534D01*
X234480Y149515D01*
G03X234430Y148948I3876J-628D01*
G01X234400Y147001D01*
Y146937D01*
G03Y146935I3926J-1D01*
G03X234548Y145867I3926J0D01*
G01X234552Y145854D01*
Y145853D01*
X234559Y145828D01*
X234562Y145711D01*
Y145709D01*
X234565Y145557D01*
G02X234557Y145497I-200J-4D01*
G01X234551Y145482D01*
Y145481D01*
X234548Y145473D01*
G03X234536Y145446I3550J-1594D01*
G01X234535Y145445D01*
G03X234530Y145432I3626J-1402D01*
G01X234518Y145402D01*
X234435Y145308D01*
X234403Y145286D01*
X234325Y145247D01*
G02X234236Y145226I-89J179D01*
G01X234200D01*
X234163Y145230D01*
X234149Y145233D01*
X234138Y145235D01*
X234131Y145237D01*
G03X233846Y145264I-284J-1475D01*
G01X233841D01*
G03X232341Y143762I2J-1502D01*
G03X233842Y142260I1502J0D01*
G01X233843D01*
G03X233920Y142262I0J1502D01*
G01X233927D01*
X234003Y142234D01*
X234032Y142207D01*
X234041Y142199D01*
X234043Y142197D01*
X234234Y142026D01*
G02X234298Y141911I-133J-149D01*
G01X234299Y141895D01*
G03X234317Y141734I3876J352D01*
G01Y141732D01*
G03X234334Y141612I3861J486D01*
G01Y141611D01*
G03X234336Y141599I3840J634D01*
G01X234339Y141582D01*
G03X234390Y141332I3837J653D01*
G03X234616Y140663I3785J906D01*
G01X234625Y140643D01*
X234634Y140602D01*
X234641Y140550D01*
X234634Y140502D01*
X234559Y140221D01*
X234551Y140190D01*
X234537Y140139D01*
Y140137D01*
X234495Y139986D01*
X234484Y139946D01*
X234450Y139904D01*
G02X234410Y139869I-150J132D01*
G01X234334Y139822D01*
X234331Y139821D01*
X234220Y139755D01*
G02X234120Y139728I-100J173D01*
G01X234076D01*
X234025Y139735D01*
G03X233113Y139842I-910J-3820D01*
G01X233096D01*
G03X231008Y139230I17J-3927D01*
G01X231000Y139232D01*
X230984Y139235D01*
G03X230714Y139259I-267J-1478D01*
G01X230712D01*
G03X229210Y137772I0J-1502D01*
G01Y137756D01*
G03X229346Y137132I1502J1D01*
G01X229355Y137112D01*
X229362Y137079D01*
G03X229186Y135917I3750J-1162D01*
G01Y135915D01*
G03X229538Y134289I3928J-1D01*
G02Y134141I-186J-74D01*
G03X229186Y132515I3576J-1625D01*
G01Y132511D01*
G03X229362Y131351I3926J2D01*
G01X229358Y131333D01*
X229344Y131292D01*
X229340Y131283D01*
G03X229210Y130685I1372J-611D01*
G01Y130664D01*
G03X230703Y129168I1502J6D01*
G01X230714D01*
G03X230984Y129192I3J1502D01*
G01X231011Y129197D01*
G03X233079Y128588I2101J3318D01*
G01X233127D01*
G03X235213Y129198I-16J3927D01*
G01X235217Y129197D01*
G03X235238Y129193I292J1474D01*
G03X235249Y129191I274J1477D01*
G03X235299Y129183I262J1479D01*
G01X235301D01*
G03X235525Y129167I219J1486D01*
G01X235532D01*
G03X235599Y129169I-11J1504D01*
G03X235963Y129235I-84J1500D01*
G03X235971Y129237I-44J194D01*
G03X235981Y129241I-553J1397D01*
G01X235996Y129246D01*
X236028Y129251D01*
G02X236175Y129216I31J-198D01*
G01X236356Y129087D01*
X236453Y129018D01*
X236465Y129005D01*
G02X236488Y128976I-145J-138D01*
G01X236486Y128902D01*
Y128828D01*
G03X236838Y127202I3928J-1D01*
G02Y127054I-186J-74D01*
G03X236486Y125429I3576J-1625D01*
G01Y125427D01*
G03X236487Y125314I3926J-22D01*
G03X236491Y125212I3925J103D01*
G01X236495Y125137D01*
G02X236477Y125112I-171J104D01*
G01X236403Y125025D01*
X236394Y125014D01*
G02X236355Y124982I-145J137D01*
G01X236348Y124979D01*
X236347Y124978D01*
X236306Y124956D01*
X236267Y124952D01*
G03X236197Y124944I407J-3870D01*
G01X236143Y124947D01*
G03X235512Y125086I-631J-1363D01*
G01X235475D01*
G03X235247Y125063I36J-1502D01*
G01X235220Y125058D01*
X235216Y125057D01*
G03X233112Y125668I-2103J-3315D01*
G01X233075Y125669D01*
G03X231100Y125114I38J-3927D01*
G01X231086Y125105D01*
G02X231000Y125086I-85J181D01*
G01X230712D01*
G03X229210Y123593I0J-1502D01*
G01Y123582D01*
G03X229355Y122937I1503J-1D01*
G01X229362Y122908D01*
G03X229186Y121759I3751J-1162D01*
G01Y121742D01*
G03X229538Y120116I3928J-1D01*
G02Y119968I-186J-74D01*
G03X229186Y118342I3576J-1625D01*
G01Y118340D01*
G03X229363Y117176I3926J2D01*
G01X229356Y117146D01*
X229347Y117127D01*
G03X229210Y116500I1365J-627D01*
G01Y116497D01*
G03X230712Y114995I1502J0D01*
G01X230716D01*
G03X230974Y115017I2J1502D01*
G01X231012Y115024D01*
G03X233112Y114415I2100J3318D01*
G03X235212Y115024I0J3927D01*
G01X235237Y115019D01*
G03X235512Y114995I268J1478D01*
G01X235528D01*
G03X235980Y115069I-14J1502D01*
G01X235982Y115070D01*
X235995Y115074D01*
X236018Y115079D01*
G02X236180Y115041I39J-196D01*
G01X236181Y115040D01*
X236185Y115038D01*
X236445Y114850D01*
G02X236488Y114803I-124J-157D01*
G01X236486Y114730D01*
Y114655D01*
G03X236838Y113029I3928J-1D01*
G02Y112881I-186J-74D01*
G03X236486Y111255I3576J-1625D01*
G03X236555Y110517I3926J-5D01*
G03X236622Y110228I3856J742D01*
G03X236662Y110090I3790J1024D01*
G01Y110089D01*
X236655Y110056D01*
G03X236646Y110036I1366J-627D01*
G01X236645Y110034D01*
G03X236510Y109430I1367J-623D01*
G01Y109409D01*
G03X238012Y107908I1502J1D01*
G03X238287Y107932I7J1503D01*
G01X238295Y107934D01*
G03X238305Y107936I-290J1474D01*
G01X238308D01*
X238313Y107937D01*
G03X238482Y107835I2113J3310D01*
G03X238486Y107833I91J178D01*
G03X238499Y107826I1868J3453D01*
G01X238568Y107788D01*
G02X238580Y107759I-179J-91D01*
G01X238660Y107462D01*
X238659Y107408D01*
X238652Y107382D01*
X238635Y107321D01*
X238623Y107300D01*
G03X238429Y106562I1308J-738D01*
G01Y106526D01*
X238430Y106510D01*
Y106507D01*
G03X238439Y106388I1501J54D01*
G03X238606Y105854I1492J173D01*
G03X239004Y105379I1325J706D01*
G01X239012Y105373D01*
X239040Y105346D01*
X239091Y105284D01*
X239101Y105263D01*
X239111Y105217D01*
X239095Y104911D01*
X239093Y104862D01*
X239034Y104761D01*
G02X239003Y104720I-174J99D01*
G01X238974Y104691D01*
X238942Y104664D01*
X238933Y104658D01*
G03X238269Y103411I839J-1247D01*
G03X241275I1503J0D01*
G03X240680Y104609I-1504J0D01*
G01X240667Y104619D01*
X240652Y104634D01*
X240628Y104665D01*
G02X240595Y104771I167J110D01*
G01X240610Y105105D01*
X240629Y105142D01*
X240633Y105151D01*
X240668Y105210D01*
X240682Y105233D01*
X240744Y105297D01*
X240769Y105314D01*
G03X241433Y106557I-838J1247D01*
G01Y106580D01*
G03X241419Y106768I-1502J-17D01*
G01Y106770D01*
G03X241417Y106782I-1483J-241D01*
G01Y106783D01*
X241414Y106800D01*
Y106801D01*
G03X241412Y106813I-1482J-241D01*
G03X241408Y106835I-1480J-258D01*
G01Y106837D01*
G03X241405Y106852I-1474J-287D01*
G01X241401Y106870D01*
G03X241354Y107042I-1470J-309D01*
G01X241341Y107080D01*
X241345Y107154D01*
X241357Y107181D01*
X241479Y107425D01*
X241491Y107444D01*
G02X241515Y107471I161J-119D01*
G01X241542Y107494D01*
X241589Y107509D01*
G03X242485Y107920I-1176J3746D01*
G01X242519D01*
G03X242712Y107907I197J1490D01*
G03X242788Y107909I-2J1503D01*
G01X242826Y107912D01*
G03X243915Y108510I-114J1498D01*
G01X243923Y108520D01*
G03X246098Y109624I-602J3880D01*
G01X251618Y115143D01*
X251630Y115149D01*
G03X251642Y115155I-666J1347D01*
G01X251646Y115157D01*
G03X252303Y115814I-682J1339D01*
G01X252305Y115818D01*
G03X252311Y115830I-1341J678D01*
G01X252317Y115842D01*
X252787Y116312D01*
X257511Y121037D01*
G03X257874Y121454I-2773J2780D01*
G03X258098Y121785I-3136J2363D01*
G01X258102Y121792D01*
X258126Y121825D01*
G03X258335Y122072I-2864J2635D01*
G03X258531Y122346I-3064J2399D01*
G03X258596Y122450I-3267J2114D01*
G01X258600Y122458D01*
X258606Y122467D01*
G03X258630Y122507I-3325J2022D01*
G03X258662Y122562I-3348J1985D01*
G01Y122563D01*
X258686Y122607D01*
X258690Y122615D01*
G03X258862Y122977I-3424J1849D01*
G01X261186Y128586D01*
X261467Y129263D01*
G02X261500Y129316I184J-78D01*
G01X261519Y129339D01*
X261553Y129358D01*
G03X262324Y130665I-731J1312D01*
G01Y130681D01*
G03X262321Y130771I-1502J-5D01*
G01Y130773D01*
G03X262279Y131035I-1498J-106D01*
G01X262273Y131059D01*
X262263Y131102D01*
G02X262260Y131133I197J35D01*
G01X262263Y131183D01*
X265367Y138679D01*
X268410Y146026D01*
G03X268594Y146590I-3596J1485D01*
G01X268597Y146601D01*
G02X268600Y146611I193J-52D01*
G01X268635Y146693D01*
Y146695D01*
X268681Y146805D01*
X268682D01*
X268702Y146853D01*
Y146855D01*
G03X269010Y148378I-3618J1524D01*
G01Y148443D01*
Y148447D01*
X268933Y153088D01*
X268913Y154276D01*
G03X268830Y155016I-3926J-66D01*
G01X268642Y155915D01*
X268312Y157489D01*
X267691Y160457D01*
G02X267735Y160628I196J41D01*
G02X267750Y160644I153J-129D01*
G01X268000Y160877D01*
G02X268192Y160923I137J-146D01*
G03X268602Y160866I410J1446D01*
G03X269629Y161272I0J1502D01*
G01X269630Y161273D01*
G02X269701Y161315I135J-147D01*
G02X269766Y161326I65J-189D01*
G01X270038D01*
G02X270103Y161315I0J-200D01*
G02X270174Y161273I-64J-189D01*
G01X270175Y161272D01*
G03X271202Y160866I1027J1096D01*
G03Y163870I0J1502D01*
G03X270175Y163464I0J-1502D01*
G01X270174Y163463D01*
G02X270103Y163421I-135J147D01*
G02X270038Y163410I-65J189D01*
G01X269766D01*
G02X269701Y163421I0J200D01*
G02X269630Y163463I64J189D01*
G01X269629Y163464D01*
G03X268602Y163870I-1027J-1096D01*
G03X267648Y163528I0J-1502D01*
G02X267646Y163526I-142J140D01*
G01X267645D01*
G02X267554Y163484I-127J155D01*
G01X267529Y163480D01*
X267478Y163484D01*
X267130Y163606D01*
G02X267001Y163753I67J189D01*
G01X265807Y169453D01*
X265177Y172464D01*
X263298Y181439D01*
X260946Y192670D01*
G02X260942Y192709I196J40D01*
G01X260870Y199825D01*
X260795Y207271D01*
G03X260802Y207284I-1328J724D01*
G01X260821Y207302D01*
G02X260872Y207337I137J-145D01*
G01X260881Y207341D01*
X260950Y207357D01*
G03X261053Y207418I-46J195D01*
G03X261102Y207586I-148J134D01*
G01Y207588D01*
G03X261099Y207600I-196J-43D01*
G01Y207601D01*
X261096Y207614D01*
X260971Y207964D01*
Y207997D01*
G03X260801Y208675I-1514J-19D01*
G01X260794Y208688D01*
G02X260779Y208751I185J77D01*
G01X260768Y209702D01*
Y209741D01*
X260779Y209762D01*
G03X260960Y210463I-1321J715D01*
G03X260959Y210535I-1503J15D01*
G01X260956Y210578D01*
G03X260777Y211196I-1499J-99D01*
G01X260776Y211198D01*
G02X260753Y211277I176J94D01*
G01X260743Y212146D01*
G02X260751Y212201I200J-1D01*
G01X260756Y212221D01*
X260769Y212245D01*
G03X260794Y212292I-1313J729D01*
G01X260828Y212359D01*
G03X260959Y212895I-1371J619D01*
G01Y212925D01*
G03X260961Y212977I-1501J84D01*
G01Y212978D01*
G03X260789Y213675I-1504J-1D01*
G01Y213677D01*
G03X260754Y213740I-1331J-698D01*
G01X260741Y213762D01*
X260727Y213812D01*
X260721Y214366D01*
X260718Y214656D01*
X260735Y214685D01*
X260737Y214688D01*
G03X260960Y215477I-1281J788D01*
G01Y215500D01*
X260958Y215531D01*
Y215539D01*
G03X260725Y216284I-1502J-61D01*
G01X260716Y216298D01*
X260709Y216324D01*
G02X260701Y216377I192J56D01*
G01X260674Y218997D01*
Y222782D01*
G02X260708Y222893I200J0D01*
G03X260959Y223689I-1251J832D01*
G01Y223780D01*
G03X260656Y224632I-1502J-54D01*
G01X260655Y224634D01*
G02X260615Y224740I160J121D01*
G01X260610Y225192D01*
G02X260621Y225258I200J1D01*
G01X260630Y225286D01*
X260651Y225313D01*
G03X260813Y225580I-1197J909D01*
G03X260909Y225840I-1356J648D01*
G01X260912Y225852D01*
X260913Y225854D01*
Y225855D01*
G03X260959Y226226I-1456J369D01*
G01Y226274D01*
G03X260656Y227132I-1502J-48D01*
G01X260629Y227168D01*
G02X260589Y227274I160J121D01*
G01X260587Y227535D01*
X260585Y227734D01*
X260589Y227739D01*
G03X260608Y227761I-1127J993D01*
G03X260623Y227779I-1146J970D01*
G01X260635Y227792D01*
X260638Y227797D01*
G03X260645Y227806I-1183J927D01*
G03X260813Y228080I-1190J918D01*
G03X260909Y228340I-1356J648D01*
G01X260912Y228352D01*
X260913Y228354D01*
Y228355D01*
G03X260959Y228726I-1456J369D01*
G01Y228773D01*
G03X260610Y229690I-1502J-47D01*
G01X260577Y229730D01*
G02X260570Y229741I165J113D01*
G03X260566Y229747I-168J-108D01*
G02X260564Y229750I165J112D01*
G01Y229763D01*
X260563Y229898D01*
X260560Y230193D01*
G02X260579Y230224I179J-89D01*
G01X260590Y230238D01*
X260608Y230259D01*
G03X260885Y231696I-1151J967D01*
G03X260587Y232217I-1427J-471D01*
G02X260537Y232338I150J133D01*
G01X260314Y254265D01*
Y269027D01*
X260315Y269042D01*
Y269062D01*
G03X260317Y269164I-3891J127D01*
G01Y269166D01*
G03X260311Y269367I-3894J-16D01*
G01X258387Y306399D01*
G02X258418Y306505I200J-1D01*
G02X258450Y306544I169J-106D01*
G01X258451Y306545D01*
X258468Y306558D01*
X258477Y306564D01*
G02X258492Y306574I118J-160D01*
G01X258516Y306586D01*
X258525Y306589D01*
G03X259495Y307994I-533J1405D01*
G03X258386Y309444I-1502J0D01*
G01X258364Y309450D01*
X258325Y309470D01*
G02X258322Y309472I108J165D01*
G01X258317Y309474D01*
X258310Y309478D01*
G02X258216Y309625I105J170D01*
G01X258156Y310786D01*
X258165Y310832D01*
X258175Y310855D01*
X258204Y310926D01*
X258218Y310945D01*
X258230Y310962D01*
X258246Y310977D01*
X258257Y310988D01*
G03X258729Y312081I-1030J1093D01*
G03X258723Y312212I-1503J-3D01*
G01X258718Y312258D01*
G03X258118Y313289I-1491J-178D01*
G01X258115Y313292D01*
G03X258109Y313296I-836J-1248D01*
G01X258094Y313308D01*
G02X258017Y313447I122J158D01*
G01X257223Y328697D01*
Y328699D01*
G03X257215Y328847I-3892J-136D01*
G01X257213Y328855D01*
X255403Y363637D01*
X251362Y441283D01*
G02X251386Y441381I200J3D01*
G02X251456Y441456I176J-94D01*
G01X251745Y441636D01*
X251753Y441640D01*
X251779Y441655D01*
X251838Y441669D01*
X251891Y441665D01*
X251934Y441653D01*
X251970Y441639D01*
X251994Y441627D01*
G03X252693Y441454I700J1329D01*
G01X252711D01*
G03X252753Y444457I-16J1502D01*
G01X252752D01*
X252708Y444459D01*
X252695D01*
G03X251835Y444188I1J-1502D01*
G01X251833Y444187D01*
X251821Y444179D01*
X251795Y444166D01*
G02X251695Y444147I-86J180D01*
G01X251687Y444148D01*
X251644Y444157D01*
G02X251625Y444165I68J188D01*
G01X251624D01*
X251547Y444202D01*
X251545D01*
X251274Y444335D01*
X251272Y444338D01*
X251270Y444340D01*
X251241Y444374D01*
G02X251217Y444410I153J128D01*
G01X251208Y444429D01*
X251201Y444459D01*
X251200Y444464D01*
G02X251197Y444486I196J38D01*
G01X250988Y448475D01*
X250939Y449419D01*
X250769Y452681D01*
X250654Y454889D01*
X250678Y454899D01*
X250680Y454917D01*
X250802Y454958D01*
X250803D01*
G03X251838Y456386I-468J1428D01*
G03X251299Y457539I-1503J0D01*
G03X251268Y457564I-959J-1157D01*
G01X251267Y457565D01*
G03X251254Y457576I-976J-1141D01*
G03X251248Y457580I-114J-164D01*
G03X251243Y457584I-940J-1170D01*
G01X251207Y457609D01*
G02X251203Y457611I86J178D01*
G03X251077Y457692I-874J-1221D01*
G03X250815Y457810I-745J-1304D01*
G01X250813D01*
G03X250786Y457819I-488J-1420D01*
G03X250650Y457855I-452J-1432D01*
G01X250648D01*
X250647Y457856D01*
G02X250537Y457921I41J196D01*
G01X250516Y457946D01*
X250504Y457975D01*
G02X250490Y458032I186J76D01*
G01X250147Y464642D01*
X250144Y464688D01*
X250201Y464825D01*
X250226Y464851D01*
G03X250369Y465031I-1102J1022D01*
G01X250376Y465043D01*
G03X250451Y465168I-1249J834D01*
G01Y465169D01*
G03X250502Y465273I-1322J713D01*
G01X250508Y465288D01*
X250509Y465289D01*
X250512Y465297D01*
X250518Y465310D01*
X250558Y465349D01*
G03X250585Y465380I-136J146D01*
G01X250592Y465391D01*
G03X250627Y465504I-165J113D01*
G01Y465876D01*
G03X250099Y467019I-1503J-1D01*
G01X250093Y467024D01*
X250092Y467025D01*
X250088Y467028D01*
X250073Y467041D01*
X250054Y467057D01*
X250036Y467092D01*
G02X250016Y467162I179J89D01*
G01X249989Y467673D01*
X249961Y468211D01*
X249928Y468844D01*
X249464Y477762D01*
X249204Y482755D01*
X249048Y485742D01*
X246423Y536175D01*
X246303Y538492D01*
X246211Y540259D01*
X246162Y541203D01*
X246159Y541260D01*
X246158Y541272D01*
Y541299D01*
G02X246179Y541376I200J-13D01*
G01X246213Y541442D01*
G02X246249Y541491I177J-93D01*
G01X246270Y541512D01*
G03X246864Y542675I-910J1198D01*
G01Y542710D01*
G03X246110Y544016I-1503J3D01*
G01X246108Y544017D01*
X246085Y544031D01*
X246055Y544059D01*
X246046Y544072D01*
X246034Y544092D01*
G02X246008Y544172I173J100D01*
G01X245989Y544528D01*
X245973Y544830D01*
X245954Y545192D01*
Y545201D01*
G02X245982Y545303I200J0D01*
G01X245998Y545330D01*
X246037Y545367D01*
X246062Y545381D01*
X246064Y545382D01*
G03X246866Y546712I-702J1330D01*
G03X245943Y548098I-1502J0D01*
G01X245941Y548099D01*
X245916Y548110D01*
X245866Y548149D01*
G02X245794Y548283I127J155D01*
G01X244747Y568387D01*
X244109Y580641D01*
X244067Y581451D01*
X243253Y597096D01*
X242508Y611415D01*
X242483Y611896D01*
X242350Y614449D01*
Y614463D01*
G02X242385Y614576I200J0D01*
G01X242403Y614602D01*
X242449Y614637D01*
X242481Y614649D01*
G03X243470Y616059I-514J1413D01*
G01X243469Y616111D01*
G03X243453Y616284I-1502J-52D01*
G01Y616286D01*
G03X243445Y616331I-1483J-240D01*
G01Y616333D01*
G03X243443Y616343I-1474J-290D01*
G01X243442Y616354D01*
X243439Y616365D01*
G02X243438Y616367I176J89D01*
G01Y616370D01*
X243437Y616372D01*
G03X243433Y616392I-1475J-285D01*
G01X243431Y616424D01*
G02X243450Y616507I200J-2D01*
G01X243463Y616532D01*
X243588Y616745D01*
X243589Y616746D01*
X243610Y616782D01*
X243639Y616810D01*
G02X243696Y616843I128J-155D01*
G01X243702Y616846D01*
X243716Y616850D01*
G03X244774Y618141I-438J1438D01*
G03X244781Y618281I-1496J145D01*
G01Y618288D01*
G03X243278Y619791I-1503J0D01*
G01X243277D01*
G03X242645Y619652I-1J-1503D01*
G01X242643Y619651D01*
X242621Y619641D01*
X242581Y619633D01*
X242580D01*
G02X242443Y619657I-36J197D01*
G01X242442D01*
X242264Y619761D01*
X242159Y619823D01*
G02X242154Y619826I100J173D01*
G02X242075Y619921I107J169D01*
G01X242063Y619952D01*
X241655Y627798D01*
X241668Y627835D01*
G03X241728Y628065I-1419J493D01*
G01X241732Y628088D01*
X241743Y628150D01*
X241744Y628157D01*
G03X241745Y628166I-198J27D01*
G01X241749Y628226D01*
X241750Y628234D01*
G03X241751Y628254I-199J20D01*
G01Y628329D01*
G03X241610Y628964I-1502J0D01*
G01X241593Y629000D01*
X241206Y636496D01*
Y636505D01*
G02X241234Y636606I200J-1D01*
G01X241248Y636629D01*
X241308Y636702D01*
X241313Y636707D01*
X241337Y636737D01*
X241398Y636769D01*
X241425Y636780D01*
X241440Y636784D01*
G03X242576Y638066I-356J1459D01*
G01Y638067D01*
X242578Y638085D01*
X242580Y638102D01*
X242585Y638142D01*
G03X242586Y638150I-198J29D01*
G01Y638159D01*
G03Y638166I-200J4D01*
G01Y638275D01*
G03X241278Y639733I-1502J-32D01*
G01X241276D01*
X241242Y639738D01*
X241215Y639751D01*
G02X241160Y639790I87J180D01*
G01X241129Y639821D01*
G02X241127Y639823I140J142D01*
G01X241067Y639885D01*
G02X241031Y639952I155J126D01*
G01X241029Y639959D01*
G02X241022Y639995I192J56D01*
G01X240977Y640861D01*
X240934Y641675D01*
Y641687D01*
G02X240979Y641813I200J0D01*
G01X240987Y641823D01*
X241012Y641852D01*
X241035Y641867D01*
G03X241184Y644244I-843J1246D01*
G03X241067Y644337I-993J-1129D01*
G03X240891Y644445I-872J-1224D01*
G01X240888Y644447D01*
X240865Y644461D01*
G02X240782Y644598I115J164D01*
G01X240530Y649420D01*
X240523Y649553D01*
X240268Y654453D01*
X240118Y657334D01*
X239864Y662209D01*
X239851Y662467D01*
X239742Y664557D01*
X239669Y665955D01*
X239668Y665976D01*
X239660Y666122D01*
X239641Y666480D01*
X239571Y667846D01*
X239570Y667856D01*
Y667857D01*
X239567Y667921D01*
Y667923D01*
X239374Y671614D01*
X239337Y672335D01*
X239319Y672678D01*
X239304Y672966D01*
X238882Y681075D01*
X238522Y687993D01*
X237457Y708454D01*
X235169Y752416D01*
Y752437D01*
G02X235229Y752576I200J-4D01*
G01X235355Y752694D01*
X235441Y752774D01*
X235451Y752782D01*
G02X235453Y752784I142J-140D01*
G01X235464Y752794D01*
G02X235591Y752840I128J-154D01*
G01X235617D01*
X235627Y752839D01*
G03X235795Y752830I164J1493D01*
G01X235798D01*
G03X237292Y754332I-8J1502D01*
G03X235803Y755834I-1502J0D01*
G01X235787D01*
G03X235462Y755798I2J-1502D01*
G01X235420Y755789D01*
X235351Y755803D01*
X235313Y755820D01*
X235068Y756006D01*
G02X235047Y756024I119J160D01*
G01X235019Y756052D01*
G02X234979Y756150I159J122D01*
G01X234829Y758957D01*
X234577Y763793D01*
X232827Y797404D01*
X230684Y838584D01*
X229973Y852245D01*
G02X230372Y852666I399J21D01*
G01X248971D01*
X248972D01*
G02X249158Y852537I-1J-200D01*
G01X249161Y852529D01*
G02X249167Y852504I-191J-59D01*
G01X250001Y847719D01*
X251624Y838396D01*
G02X251603Y838267I-197J-34D01*
G01X251588Y838239D01*
X251539Y838194D01*
X251506Y838180D01*
G03X250598Y836800I595J-1380D01*
G03X252007Y835301I1502J0D01*
G01X252013D01*
G02X252192Y835136I-18J-199D01*
G01X252535Y833172D01*
X252619Y832688D01*
G02X252614Y832597I-197J-35D01*
G01X252604Y832565D01*
G02X252574Y832543I-133J150D01*
G01X252423Y832517D01*
X252400Y832518D01*
G03X252353Y832520I-87J-1500D01*
G01X252304D01*
G03X250803Y831018I1J-1502D01*
G03X252305Y829516I1502J0D01*
G01X252308D01*
G03X252715Y829572I1J1502D01*
G02X252870Y829552I54J-193D01*
G01X253000Y829470D01*
X253126Y829391D01*
G02X253216Y829256I-107J-169D01*
G01X253561Y827279D01*
X253942Y825091D01*
G02X253943Y825027I-197J-35D01*
G01X253939Y825000D01*
X253926Y824972D01*
G03X253787Y824341I1365J-631D01*
G01Y824340D01*
G03X254220Y823285I1502J0D01*
G01X254223Y823282D01*
G02X254273Y823190I-145J-138D01*
G01X254514Y821806D01*
G02X254475Y821666I-199J-20D01*
G02X254466Y821655I-159J121D01*
G01X254262Y821421D01*
G02X254105Y821352I-151J131D01*
G03X254065Y821353I-58J-1501D01*
G01X254057D01*
G03X253301Y821149I0J-1501D01*
G01X253278Y821137D01*
G03X253112Y821055I581J-1385D01*
G03X252763Y820779I747J-1303D01*
G03X252650Y820644I1093J-1030D01*
G01X252641Y820631D01*
G02X252570Y820580I-149J133D01*
G02X252481Y820563I-81J183D01*
G01X252147Y820579D01*
G02X252052Y820608I9J200D01*
G01X252034Y820619D01*
X252001Y820651D01*
X251987Y820675D01*
G03X250700Y821402I-1287J-776D01*
G03Y818398I0J-1502D01*
G01Y818397D01*
G03X251908Y819007I-1J1503D01*
G01X251917Y819020D01*
G02X251987Y819071I150J-133D01*
G02X252077Y819088I81J-183D01*
G01X252409Y819072D01*
G02X252505Y819043I-8J-200D01*
G01X252545Y819018D01*
X252563Y818989D01*
G03X253858Y818249I1295J763D01*
G01X253859D01*
G03X254619Y818455I1J1502D01*
G01X254642Y818467D01*
G03X254808Y818550I-587J1382D01*
G01X254839Y818568D01*
X254977Y818592D01*
G02X254983Y818590I-60J-191D01*
G01X255025Y818574D01*
X255058Y818533D01*
G02X255100Y818442I-155J-127D01*
G01X255153Y818140D01*
X255897Y813867D01*
G02X255770Y813658I-199J-22D01*
G01X255769D01*
G03X254811Y812430I534J-1404D01*
G01X254807Y812396D01*
G03X254801Y812254I1496J-134D01*
G03X256295Y810752I1502J0D01*
G01X256298D01*
X256348Y810751D01*
X256456Y810658D01*
X291329Y610415D01*
X291323Y610405D01*
X291256Y610338D01*
G03X290981Y609962I1062J-1065D01*
G03X290813Y609272I1335J-690D01*
G03X291679Y607910I1504J0D01*
G01X291745Y607879D01*
G02X291774Y607860I-95J-176D01*
G01X291785Y607800D01*
Y607798D01*
X291894Y607169D01*
X291895Y607167D01*
X291896Y607160D01*
G02X291897Y607156I-193J-50D01*
G01X294415Y587580D01*
X296623Y570416D01*
X296933Y568008D01*
G02X296935Y567984I-198J-29D01*
G01X296982Y563030D01*
X296999Y561260D01*
X297016Y559448D01*
X297238Y535936D01*
X297713Y485599D01*
G03X297712Y485543I3891J-97D01*
G01Y485537D01*
G03X297713Y485508I3890J120D01*
G01Y485506D01*
X297951Y460244D01*
G03X298036Y459473I3892J39D01*
G01Y459472D01*
X299299Y453157D01*
X299623Y451540D01*
X305872Y420306D01*
Y420305D01*
X305873Y420302D01*
X305876Y420289D01*
G03X305877Y420285I194J46D01*
G01X305881Y420270D01*
X305882Y420263D01*
X305889Y420215D01*
X305877Y420173D01*
G02X305826Y420086I-192J54D01*
G01X305801Y420061D01*
X305788Y420052D01*
G03X305171Y418838I886J-1214D01*
G03X306324Y417376I1503J0D01*
G03X306333Y417374I48J194D01*
G02X306491Y417221I-37J-197D01*
G01X306492Y417217D01*
X306560Y416880D01*
X306676Y416296D01*
X307014Y414611D01*
X307833Y410515D01*
G02X307837Y410478I-196J-40D01*
G01Y410420D01*
G02X307835Y410411I-196J39D01*
G01X307830Y410391D01*
X307822Y410366D01*
G03X307756Y409939I1436J-441D01*
G01Y409924D01*
G03X308119Y408944I1502J-1D01*
G01X308121Y408942D01*
X308133Y408927D01*
G02X308163Y408864I-163J-116D01*
G01X308175Y408808D01*
Y408806D01*
X308465Y407347D01*
G02X308438Y407209I-197J-33D01*
G01X308412Y407174D01*
X308385Y407147D01*
X308372Y407138D01*
G03X307756Y405924I888J-1214D01*
G03X308895Y404466I1503J0D01*
G01X308917Y404461D01*
X308924Y404459D01*
X308950Y404454D01*
X309000Y404427D01*
X309021Y404406D01*
G02X309066Y404338I-141J-142D01*
G02X309076Y404303I-186J-72D01*
G01X309386Y402756D01*
X309424Y402564D01*
X309966Y399853D01*
Y399824D01*
G02X309917Y399693I-200J0D01*
G01X309728Y399498D01*
X309679Y399447D01*
G02X309541Y399392I-138J145D01*
G01X309511D01*
X309495Y399395D01*
G03X309258Y399414I-238J-1483D01*
G03Y396410I0J-1502D01*
G03X310047Y396634I0J1503D01*
G01X310075Y396656D01*
X310160Y396676D01*
X310208Y396666D01*
G02X310248Y396653I-41J-196D01*
G01X310543Y396523D01*
G02X310603Y396482I-81J-183D01*
G01X310610Y396475D01*
X310613Y396471D01*
G02X310662Y396375I-147J-135D01*
G01X312000Y389693D01*
X315953Y369942D01*
X318304Y358186D01*
G02X318167Y357984I-200J-12D01*
G01X318150Y357980D01*
G03X317288Y357407I350J-1461D01*
G02X317194Y357347I-150J132D01*
G02X317166Y357341I-56J192D01*
G01X317105Y357332D01*
X317084Y357329D01*
X316893Y357340D01*
X316881Y357341D01*
G02X316879Y357342I86J175D01*
G01X316864Y357343D01*
X316861Y357344D01*
X316846Y357345D01*
X316839D01*
X316824Y357346D01*
X316817Y357347D01*
X316759Y357352D01*
X316741Y357353D01*
X316722Y357355D01*
X316681Y357383D01*
G02X316618Y357452I112J166D01*
G01X316616Y357456D01*
X316613Y357461D01*
X316612Y357463D01*
G03X316605Y357475I-1303J-752D01*
G03X316483Y357652I-1296J-763D01*
G03X315310Y358215I-1173J-940D01*
G03X314568Y358019I0J-1503D01*
G03X314143Y357660I742J-1310D01*
G01X314141Y357657D01*
X314134Y357649D01*
X314120Y357635D01*
G02X313979Y357577I-141J142D01*
G01X313948D01*
G02X313796Y357647I0J200D01*
G01X313785Y357661D01*
X313783Y357664D01*
X313778Y357672D01*
G03X312316Y358477I-1462J-925D01*
G03X310796Y357571I0J-1728D01*
G01X310782Y357545D01*
X310767Y357517D01*
X310716Y357466D01*
G02X310677Y357436I-140J142D01*
G01X310651Y357423D01*
G02X310569Y357408I-76J185D01*
G01X310539Y357409D01*
X310482Y357411D01*
G02X310385Y357444I14J200D01*
G01X310362Y357459D01*
X310328Y357498D01*
X310315Y357525D01*
G03X308952Y358384I-1363J-652D01*
G03Y355366I0J-1509D01*
G03X310249Y356104I0J1509D01*
G01X310262Y356126D01*
X310304Y356168D01*
G02X310443Y356226I141J-142D01*
G01X310496Y356224D01*
X310537Y356222D01*
X310539D01*
X310553Y356221D01*
G02X310680Y356151I-27J-198D01*
G01X310702Y356124D01*
X310714Y356096D01*
X310715Y356094D01*
G03X312316Y355017I1601J651D01*
G03X313721Y355736I0J1732D01*
G01X313722Y355738D01*
X313734Y355754D01*
X313735Y355755D01*
X313737Y355758D01*
X313743Y355766D01*
G02X313799Y355812I153J-129D01*
G01X313872Y355851D01*
G02X314004Y355868I90J-178D01*
G01X314037Y355861D01*
X314096Y355824D01*
X314119Y355794D01*
G03X314193Y355706I1187J923D01*
G01X314196Y355703D01*
G03X315310Y355209I1114J1009D01*
G03X316510Y355806I0J1505D01*
G01X316516Y355814D01*
X316524Y355824D01*
X316566Y355859D01*
X316598Y355886D01*
X316618Y355896D01*
X316668Y355905D01*
X316918Y355890D01*
X316919D01*
X316932Y355889D01*
X317033Y355881D01*
G02X317125Y355850I-16J-199D01*
G01X317145Y355837D01*
X317177Y355803D01*
X317190Y355780D01*
G03X317253Y355678I1310J739D01*
G03X317316Y355591I1249J838D01*
G01X317330Y355573D01*
X317334Y355568D01*
X317355Y355520D01*
X317359Y355478D01*
G02X317348Y355402I-199J-10D01*
G01X317309Y355298D01*
Y355296D01*
X317224Y355074D01*
G02X317219Y355062I-187J71D01*
G02X317164Y354991I-182J84D01*
G01X317145Y354975D01*
X317099Y354954D01*
X317072Y354949D01*
G03X315831Y353470I261J-1479D01*
G03X317333Y351968I1502J0D01*
G03X318642Y352733I0J1502D01*
G01X318651Y352749D01*
X318673Y352788D01*
G02X318741Y352853I168J-108D01*
G02X318858Y352879I100J-173D01*
G01X318900Y352875D01*
X319028Y352857D01*
X319068Y352851D01*
X319112Y352825D01*
G02X319179Y352759I-103J-171D01*
G01X319194Y352735D01*
X319195Y352734D01*
G03X319267Y352624I1291J767D01*
G01X319269Y352621D01*
Y352620D01*
G03X319334Y352538I1209J892D01*
G01X319335Y352537D01*
X319337Y352534D01*
X319432Y352422D01*
X319441Y352405D01*
X319473Y352341D01*
G02X319477Y352331I-184J-79D01*
G01X319780Y350818D01*
X320027Y349583D01*
X320075Y349345D01*
Y349343D01*
X320130Y349060D01*
G02X320132Y349033I-198J-28D01*
G01Y348922D01*
G02X320103Y348819I-200J1D01*
G03X319876Y348015I1312J-804D01*
G03X320538Y346749I1542J0D01*
G01X320587Y346715D01*
X320608Y346684D01*
X320673Y346359D01*
X321167Y343890D01*
X323972Y329877D01*
X340132Y248418D01*
G02X340048Y248223I-198J-31D01*
G01X339943Y248154D01*
X339909Y248133D01*
X339901Y248128D01*
X339893Y248122D01*
X339887Y248118D01*
G02X339831Y248095I-103J172D01*
G02X339783Y248089I-49J194D01*
G01X339721D01*
G02X339684Y248093I3J200D01*
G01X339631Y248106D01*
X339611Y248119D01*
X339601Y248126D01*
G03X338770Y248377I-832J-1252D01*
G03X338768I-1J-1503D01*
G03X338711Y248376I-2J-1503D01*
G01X338657Y248372D01*
G03X337266Y246874I111J-1498D01*
G03X338768Y245372I1502J0D01*
G01X338772D01*
G03X339125Y245414I0J1502D01*
G01X339141Y245418D01*
X339169Y245421D01*
G02X339333Y245358I17J-199D01*
G02X339338Y245352I-151J-131D01*
G01X339572Y245079D01*
G02X339616Y244983I-153J-128D01*
G01X339620Y244960D01*
X339614Y244904D01*
X339613Y244901D01*
X339602Y244876D01*
G03X339486Y244297I1387J-579D01*
G03X340988Y242795I1502J0D01*
G03X341073Y242797I7J1502D01*
G01X341078D01*
G02X341278Y242646I6J-200D01*
G01X341464Y241707D01*
X341774Y240144D01*
G02X341778Y240108I-196J-40D01*
G01X341797Y238905D01*
X341795Y238891D01*
G03X341785Y238715I1492J-173D01*
G01Y238710D01*
G03X341801Y238491I1504J0D01*
G01X341803Y238478D01*
X341923Y230807D01*
X341913Y230763D01*
X341904Y230743D01*
G03X341768Y230117I1367J-625D01*
G03X341769Y230063I1503J1D01*
G01X341773Y230004D01*
G03X341925Y229451I1498J114D01*
G01X341935Y229430D01*
X341945Y229388D01*
X342277Y208112D01*
X342479Y195153D01*
G02X342478Y195138I-200J6D01*
G01X342477Y195131D01*
X337252Y156450D01*
G03X337217Y155981I3891J-526D01*
G01X337216Y155928D01*
X337214Y155787D01*
X337211Y155603D01*
G02X337209Y155577I-200J2D01*
G01X336873Y153273D01*
G03X336832Y152711I3851J-563D01*
G01Y151566D01*
X336825Y151515D01*
X336822Y151503D01*
G03X336687Y150539I3791J-1022D01*
G01X336658Y148588D01*
Y148529D01*
G03X336822Y147407I3926J1D01*
G01Y147406D01*
X336832Y147371D01*
Y147354D01*
G02X336829Y147325I-199J6D01*
G01X336821Y147285D01*
X336818Y147266D01*
X336816Y147256D01*
X336806Y147234D01*
G03X336482Y145680I3567J-1555D01*
G01Y145660D01*
G02X336452Y145555I-200J0D01*
G01X336429Y145525D01*
X336428Y145524D01*
X336242Y145324D01*
X336207Y145308D01*
X336108Y145261D01*
X336072Y145258D01*
G03X335671Y145166I132J-1496D01*
G03X335186Y144866I533J-1404D01*
G03X334713Y143938I1019J-1104D01*
G01X334709Y143905D01*
G03X334703Y143763I1496J-134D01*
G01Y143761D01*
G03X336120Y142262I1502J1D01*
G01X336164Y142259D01*
X336198Y142242D01*
G02X336251Y142203I-90J-178D01*
G01X336395Y142038D01*
X336398Y142035D01*
X336449Y141975D01*
X336453Y141970D01*
X336456Y141966D01*
X336478Y141939D01*
X336488Y141908D01*
G02X336496Y141832I-192J-59D01*
G03X336481Y141499I3878J-342D01*
G01Y141497D01*
G03X336482Y141440I3892J40D01*
G01Y140164D01*
G02X336481Y140146I-200J2D01*
G01X336480Y140137D01*
G02X336420Y140019I-198J27D01*
G01X336393Y139995D01*
X336170Y139802D01*
X336158Y139792D01*
X336142Y139786D01*
X336059Y139798D01*
X336057D01*
G03X335758Y139831I-580J-3884D01*
G03X335496Y139842I-296J-3915D01*
G01X335445D01*
G03X333370Y139230I30J-3927D01*
G01X333362Y139232D01*
X333346Y139235D01*
G03X333076Y139259I-267J-1478D01*
G01X333074D01*
G03X331572Y137772I0J-1502D01*
G01Y137756D01*
G03X331708Y137132I1502J1D01*
G01X331717Y137112D01*
X331724Y137079D01*
G03X331548Y135917I3750J-1162D01*
G01Y135915D01*
G03X331900Y134289I3928J-1D01*
G02Y134141I-186J-74D01*
G03X331548Y132515I3576J-1625D01*
G03X331617Y131777I3926J-5D01*
G03X331724Y131350I3856J739D01*
G01X331720Y131332D01*
X331706Y131290D01*
G03X331576Y130786I1367J-621D01*
G01Y130773D01*
X331575Y130771D01*
G03X331574Y130750I1500J-82D01*
G01Y130746D01*
G03X331572Y130686I1500J-80D01*
G01Y130670D01*
G03X333065Y129168I1502J0D01*
G01X333076D01*
G03X333346Y129192I3J1502D01*
G01X333373Y129197D01*
G03X335441Y128588I2101J3318D01*
G01X335489D01*
G03X337576Y129198I-15J3927D01*
G01X337612Y129191D01*
G03X337676Y129181I264J1479D01*
G03X337831Y129168I203J1488D01*
G01X337884D01*
X337888Y129167D01*
X337894D01*
G03X338063Y129179I-22J1504D01*
G01X338065D01*
G03X338345Y129241I-184J1493D01*
G01X338360Y129246D01*
X338401Y129252D01*
G02X338521Y129226I20J-199D01*
G01X338816Y129017D01*
X338827Y129005D01*
G02X338850Y128976I-145J-138D01*
G01X338848Y128902D01*
Y128828D01*
G03X339200Y127202I3928J-1D01*
G02Y127054I-186J-74D01*
G03X338848Y125430I3576J-1625D01*
G01Y125284D01*
G02X338835Y125263I-176J95D01*
G01X338819Y125240D01*
X338694Y125148D01*
X338692D01*
X338496Y125007D01*
X338448Y125000D01*
X338399Y124992D01*
G03X338316Y125020I-521J-1409D01*
G01X338279Y125031D01*
X338235Y125043D01*
G03X337875Y125087I-361J-1459D01*
G01X337871D01*
G03X337615Y125065I0J-1503D01*
G01X337577Y125058D01*
G03X335476Y125668I-2102J-3316D01*
G01X335475D01*
X335476Y125669D01*
X335474D01*
G03X333462Y125114I1J-3927D01*
G01X333448Y125105D01*
G02X333362Y125086I-85J181D01*
G01X333074D01*
G03X331572Y123593I0J-1502D01*
G01Y123582D01*
G03X331717Y122937I1503J-1D01*
G01X331724Y122908D01*
G03X331548Y121759I3751J-1162D01*
G01Y121742D01*
G03X331900Y120116I3928J-1D01*
G02Y119968I-186J-74D01*
G03X331548Y118342I3576J-1625D01*
G01Y118340D01*
G03X331725Y117176I3926J2D01*
G01X331718Y117146D01*
X331709Y117127D01*
G03X331572Y116500I1365J-627D01*
G01Y116497D01*
G03X333074Y114995I1502J0D01*
G01X333081D01*
G03X333349Y115019I1J1502D01*
G02X333356Y115020I32J-197D01*
G01X333374Y115022D01*
X333377D01*
G03X335474Y114416I2096J3320D01*
G03X335562Y114417I-1J3926D01*
G03X337572Y115023I-87J3925D01*
G01X337585D01*
G03X337873Y114995I289J1474D01*
G01X337874D01*
G03X337878I2J1502D01*
G01X337884D01*
G03X338347Y115070I-6J1502D01*
G01X338362Y115075D01*
X338399Y115081D01*
G02X338525Y115053I22J-199D01*
G01X338776Y114873D01*
X338808Y114850D01*
G02X338850Y114804I-125J-156D01*
G01X338848Y114731D01*
Y114655D01*
G03X339200Y113029I3928J-1D01*
G02Y112881I-186J-74D01*
G03X338848Y111255I3576J-1625D01*
G03X338917Y110517I3926J-5D01*
G03X338984Y110228I3856J742D01*
G03X339024Y110090I3790J1024D01*
G01Y110089D01*
X339017Y110056D01*
G03X339008Y110036I1365J-626D01*
G01X339007Y110034D01*
G03X338872Y109430I1367J-623D01*
G01Y109409D01*
G03X340374Y107908I1502J1D01*
G03X340636Y107931I0J1502D01*
G01X340674Y107937D01*
G03X340861Y107826I2097J3320D01*
G01X340929Y107788D01*
G02X340944Y107751I-177J-93D01*
G01X341022Y107462D01*
X341021Y107408D01*
X341014Y107382D01*
X340997Y107321D01*
X340985Y107300D01*
G03X340791Y106562I1308J-738D01*
G01Y106526D01*
X340792Y106510D01*
Y106507D01*
G03X340801Y106388I1501J54D01*
G03X340968Y105854I1492J173D01*
G03X341366Y105379I1325J706D01*
G01X341374Y105373D01*
X341402Y105346D01*
X341453Y105284D01*
X341463Y105263D01*
X341473Y105217D01*
X341457Y104911D01*
X341455Y104862D01*
X341383Y104738D01*
X341365Y104720D01*
X341321Y104675D01*
X341296Y104658D01*
G03X340632Y103411I839J-1247D01*
G03X343636I1502J0D01*
G03X343048Y104603I-1502J0D01*
G01X343037Y104611D01*
X343011Y104637D01*
X342993Y104660D01*
G02X342957Y104771I164J114D01*
G01X342972Y105105D01*
X342991Y105142D01*
X342995Y105151D01*
X343045Y105235D01*
X343062Y105252D01*
X343106Y105297D01*
X343131Y105314D01*
G03X343795Y106557I-838J1247D01*
G01Y106575D01*
G03X343716Y107043I-1502J-13D01*
G01X343703Y107082D01*
X343705Y107120D01*
G02X343726Y107197I200J-13D01*
G01X343778Y107301D01*
X343836Y107416D01*
G02X343838Y107419I167J-109D01*
G01X343841Y107425D01*
G02X343857Y107449I174J-99D01*
G02X343884Y107477I157J-124D01*
G01X343904Y107494D01*
X343951Y107509D01*
G03X344847Y107920I-1176J3746D01*
G01X344881D01*
G03X345074Y107907I197J1490D01*
G03X345150Y107909I-2J1503D01*
G01X345188Y107912D01*
G03X346193Y108407I-113J1498D01*
G01X346194Y108408D01*
G02X346342Y108474I148J-134D01*
G01X346500D01*
G03X349276Y109624I0J3926D01*
G01X359279Y119627D01*
G03X360121Y120879I-2776J2776D01*
G01X360617Y122054D01*
X360627Y122069D01*
G03X360977Y122728I-3247J2147D01*
G01X363647Y129171D01*
G02X363687Y129233I185J-75D01*
G01X363712Y129259D01*
X363756Y129280D01*
X363761Y129282D01*
X363763Y129283D01*
X363773Y129287D01*
G03X364655Y130364I-589J1382D01*
G03X364659Y130384I-1472J305D01*
G01Y130385D01*
X364668Y130427D01*
X364676Y130490D01*
G03X364686Y130634I-1492J176D01*
G01Y130711D01*
G03X364683Y130774I-1502J-40D01*
G01Y130776D01*
X364679Y130841D01*
G03X364676Y130863I-199J-16D01*
G01X364674Y130877D01*
Y130879D01*
G03X364583Y131219I-1488J-216D01*
G01X364570Y131250D01*
X364562Y131288D01*
Y131290D01*
G02X364557Y131341I195J45D01*
G02X364568Y131396I200J-11D01*
G01X365112Y132711D01*
X365127Y132747D01*
X365461Y133551D01*
Y133553D01*
X367265Y137834D01*
X370721Y146040D01*
G03X370958Y146820I-3618J1525D01*
G01X371392Y149068D01*
G03X371440Y149379I-3853J754D01*
G03X371464Y149812I-3903J433D01*
G03X371439Y150250I-3927J-4D01*
G01X371294Y151540D01*
X371069Y153543D01*
G02X371068Y153565I199J20D01*
G01Y154608D01*
G03X370989Y155387I-3891J-1D01*
G01X370712Y156743D01*
G02X370709Y156761I195J42D01*
G01X370614Y157607D01*
X370594Y157783D01*
G03X370535Y158150I-3902J-439D01*
G01X370029Y160568D01*
G02X370030Y160657I196J42D01*
G02X370094Y160762I195J-47D01*
G01X370161Y160819D01*
X370163D01*
X370275Y160919D01*
X370311Y160935D01*
X370353Y160951D01*
G03X370963Y160825I611J1417D01*
G01X370964D01*
G03X372100Y161324I0J1543D01*
G02X372127Y161326I28J-198D01*
G01X372404D01*
G02X372427Y161325I3J-200D01*
G03X373564Y160825I1137J1043D01*
G03Y163911I0J1543D01*
G03X372427Y163411I0J-1543D01*
G02X372404Y163410I-20J199D01*
G01X372124D01*
G02X372101Y163411I-3J200D01*
G03X370964Y163911I-1137J-1043D01*
G03X369855Y163441I0J-1543D01*
G01X369832Y163437D01*
G02X369765Y163436I-36J197D01*
G01X369719Y163445D01*
X369593Y163486D01*
X369522Y163509D01*
X369412Y163545D01*
G02X369405Y163548I75J185D01*
G01X367838Y171031D01*
X365202Y183625D01*
X363267Y193065D01*
X362953Y194603D01*
G02X362950Y194631I196J35D01*
G01Y206884D01*
G02X362962Y206951I200J-1D01*
G01X362993Y207039D01*
X363013Y207064D01*
G03X363322Y207977I-1194J913D01*
G01Y207979D01*
G03X363011Y208896I-1504J1D01*
G01X363007Y208900D01*
X362984Y208935D01*
X362970Y208963D01*
G02X362955Y209006I180J87D01*
G02X362950Y209050I195J44D01*
G01Y209371D01*
G02X362951Y209390I200J-1D01*
G01X362953Y209404D01*
X362957Y209431D01*
G02X362965Y209462I197J-34D01*
G01X362975Y209492D01*
X362989Y209532D01*
X363004Y209551D01*
Y209552D01*
X363010Y209560D01*
X363011Y209561D01*
G03X363321Y210488I-1193J914D01*
G03X363007Y211398I-1502J-9D01*
G01X362994Y211414D01*
X362970Y211462D01*
G02X362955Y211505I180J87D01*
G02X362950Y211549I195J44D01*
G01Y211871D01*
G02X362951Y211890I200J-1D01*
G01X362953Y211904D01*
X362957Y211931D01*
G02X362965Y211962I197J-34D01*
G01X362975Y211992D01*
X362989Y212032D01*
X363004Y212051D01*
Y212052D01*
X363010Y212060D01*
X363011Y212061D01*
G03X363321Y212988I-1193J914D01*
G03X363007Y213898I-1502J-9D01*
G01X362994Y213914D01*
X362970Y213962D01*
G02X362955Y214005I180J87D01*
G02X362950Y214049I195J44D01*
G01Y214429D01*
X362960Y214472D01*
X362971Y214494D01*
X362993Y214540D01*
X363006Y214557D01*
G03X363322Y215477I-1187J922D01*
G01Y215502D01*
X363319Y215560D01*
G03X363021Y216379I-1500J-82D01*
G01X363018Y216383D01*
X362996Y216415D01*
X362962Y216509D01*
G02X362950Y216577I188J68D01*
G01Y220234D01*
G03X362951Y220275I-3891J115D01*
G03Y220279I-200J2D01*
G03X362950Y220347I-3892J-23D01*
G01Y220364D01*
X362949Y220368D01*
X362930Y221180D01*
X362898Y222566D01*
X362897Y222606D01*
X362934Y222701D01*
G02X362968Y222758I186J-73D01*
G01X362980Y222772D01*
X362983Y222776D01*
G03X362987Y222781I-1171J941D01*
G01X362988Y222782D01*
G03X363318Y223624I-1169J944D01*
G03X363321Y223710I-1499J95D01*
G01Y223730D01*
G03X362922Y224746I-1503J-4D01*
G01X362898Y224772D01*
X362850Y224885D01*
X362844Y224918D01*
G02X362843Y224928I199J25D01*
G01X362841Y224983D01*
X362840Y225035D01*
X362839Y225076D01*
X362868Y225150D01*
X362896Y225179D01*
G03X363321Y226225I-1077J1047D01*
G01Y226230D01*
G03X363320Y226293I-1502J8D01*
G01X363319Y226310D01*
G03X363171Y226881I-1500J-84D01*
G03X362852Y227317I-1352J-655D01*
G01X362829Y227338D01*
X362814Y227365D01*
G02X362796Y227410I176J96D01*
G02X362794Y227420I195J44D01*
G01X362783Y227474D01*
X362782Y227478D01*
Y227485D01*
X362807Y227543D01*
X362843Y227626D01*
X362871Y227654D01*
G03X363321Y228726I-1052J1072D01*
G03X363308Y228926I-1502J3D01*
G01X363307Y228937D01*
G03X363069Y229560I-1488J-211D01*
G01X363047Y229592D01*
X363035Y229609D01*
X363011Y229642D01*
X362994Y229662D01*
G02X362976Y229691I161J120D01*
G01X362972Y229699D01*
G02X362951Y229788I179J89D01*
G01Y229871D01*
G03X362933Y229954I-200J0D01*
G01X362909Y230007D01*
G02X362934Y230215I181J84D01*
G01X362956Y230243D01*
X362970Y230261D01*
X362972Y230264D01*
X362978Y230271D01*
G03X363321Y231216I-1159J955D01*
G01Y231224D01*
G03Y231227I-1502J2D01*
G01Y231229D01*
G03X362740Y232413I-1502J-2D01*
G01X362739D01*
G02X362684Y232481I124J157D01*
G01X362674Y232501D01*
X362663Y232543D01*
X362502Y239405D01*
G03X362425Y240093I-3891J-87D01*
G01X362055Y241942D01*
X362054Y241947D01*
G03X362020Y242142I-3884J-577D01*
G01X347828Y313674D01*
G02X347893Y313861I196J37D01*
G01X347968Y313924D01*
X348039Y313983D01*
G02X348098Y314017I128J-154D01*
G01X348132Y314029D01*
X348209D01*
G02X348236Y314027I-1J-200D01*
G01X348286Y314017D01*
X348301Y314012D01*
X348303Y314011D01*
G03X348367Y313990I500J1417D01*
G02X348371Y313988I-86J-178D01*
G01X349152Y313728D01*
X349153D01*
X349380Y313780D01*
X349405Y313851D01*
G03X349416Y313918I-189J65D01*
G01Y313933D01*
G02X349521Y314106I200J-3D01*
G03X350308Y315427I-715J1321D01*
G03X348806Y316929I-1502J0D01*
G03X347761Y316506I0J-1502D01*
G01X347753Y316498D01*
G02X347682Y316458I-132J151D01*
G01X347639Y316444D01*
X347575Y316455D01*
G02X347571Y316456I46J194D01*
G01X347369Y316519D01*
G02X347279Y316577I60J191D01*
G01X347263Y316596D01*
X347240Y316642D01*
X347050Y317597D01*
X347009Y317801D01*
G02X347021Y317918I196J39D01*
G01X347032Y317944D01*
X347070Y317990D01*
X347085Y318000D01*
X347274Y318125D01*
G02X347407Y318157I111J-167D01*
G01X347417Y318155D01*
X347502Y318130D01*
X347527Y318114D01*
G03X348349Y317870I821J1260D01*
G01X348351D01*
G03Y320874I0J1502D01*
G01X348315D01*
G03X347404Y320539I35J-1502D01*
G03X347122Y320237I947J-1167D01*
G01X347108Y320216D01*
X347090Y320200D01*
X347089Y320199D01*
G02X347052Y320171I-139J145D01*
G01X347020Y320154D01*
X346992Y320140D01*
X346979Y320132D01*
G02X346971Y320129I-74J186D01*
G01Y320128D01*
G02X346903Y320110I-84J182D01*
G02X346854Y320112I-16J200D01*
G01X346793Y320124D01*
X346664Y320149D01*
G02X346512Y320306I44J195D01*
G01X322025Y443725D01*
G02X322133Y443931I198J27D01*
G01X322144Y443936D01*
G03X323051Y445315I-595J1379D01*
G03X321573Y446817I-1502J0D01*
G01X321572D01*
G02X321448Y446863I4J200D01*
G01X321421Y446885D01*
X321386Y446943D01*
X319820Y454839D01*
X318758Y460191D01*
G02X318754Y460227I196J40D01*
G01X318701Y464849D01*
Y464873D01*
G02X318743Y464998I200J2D01*
G01X318763Y465024D01*
X318819Y465060D01*
X318853Y465069D01*
G03X319699Y465627I-356J1459D01*
G02X319749Y465674I160J-120D01*
G01X319807Y465713D01*
G02X319874Y465741I109J-168D01*
G01X319967Y465762D01*
G02X320089Y465744I33J-197D01*
G03X320991Y465502I902J1561D01*
G01X320993D01*
G03X322796Y467305I0J1803D01*
G01Y470705D01*
G03X320993Y472508I-1803J0D01*
G01X320992D01*
G03X320122Y472284I1J-1804D01*
G01X320100Y472272D01*
X320003Y472246D01*
G02X319958Y472251I-1J200D01*
G01X319839Y472278D01*
G02X319724Y472351I43J195D01*
G01X319710Y472370D01*
X319707Y472374D01*
G03X318769Y472961I-1210J-890D01*
G01X318768D01*
G02X318743Y472967I34J197D01*
G02X318605Y473155I62J190D01*
G01X318537Y479024D01*
G02X318589Y479150I200J-9D01*
G01X318708Y479214D01*
X318709D01*
G03X319713Y479820I-213J1487D01*
G01X319720Y479829D01*
X319809Y479887D01*
G02X319874Y479915I110J-167D01*
G01X319956Y479934D01*
G02X320036Y479936I45J-195D01*
G02X320100Y479912I-37J-197D01*
G03X320991Y479676I892J1567D01*
G01X320993D01*
G03X322796Y481479I0J1803D01*
G01Y484879D01*
G03X319190I-1803J0D01*
G01Y482580D01*
Y482578D01*
G02X319120Y482428I-200J2D01*
G01X318890Y482231D01*
G02X318758Y482183I-130J152D01*
G01X318729Y482185D01*
G03X318674Y482193I-244J-1482D01*
G02X318549Y482258I24J198D01*
G01X318524Y482285D01*
X318499Y482351D01*
X317862Y537451D01*
G02X317923Y537597I200J2D01*
G02X317935Y537608I141J-142D01*
G01X318177Y537806D01*
G02X318254Y537845I127J-155D01*
G01X318298Y537856D01*
X318344Y537846D01*
G03X318657Y537813I313J1470D01*
G01X318687D01*
G03X320162Y539315I-27J1502D01*
G03X318660Y540817I-1502J0D01*
G01X318627D01*
G03X318201Y540746I31J-1502D01*
G01X318171Y540736D01*
X318112Y540716D01*
G03X318092Y540707I72J-187D01*
G01X318060Y540692D01*
G03X318008Y540669I582J-1385D01*
G01X317904Y540734D01*
G02X317823Y540892I119J161D01*
G01X317518Y567202D01*
G03X317476Y567731I-3927J-46D01*
G01Y567732D01*
X312016Y610114D01*
G03X311990Y610286I-3894J-501D01*
G01X275459Y820048D01*
X275466Y820105D01*
X275478Y820133D01*
G03X275599Y820703I-1382J591D01*
G01Y820725D01*
G03X275593Y820857I-1503J-2D01*
G01X275588Y820902D01*
G03X275197Y821748I-1493J-177D01*
G01X275175Y821771D01*
X275162Y821798D01*
G02X275146Y821849I181J85D01*
G01X274614Y824906D01*
X274125Y827711D01*
X273983Y828526D01*
X273877Y829133D01*
G02X273940Y829315I197J34D01*
G01X274076Y829439D01*
G02X274095Y829454I133J-149D01*
G01X274126Y829476D01*
X274127D01*
G02X274246Y829509I110J-166D01*
G01X274293Y829503D01*
X274306Y829500D01*
X274309Y829499D01*
G03X274693Y829449I384J1452D01*
G01X274697D01*
G03X276199Y830951I0J1502D01*
G03X274716Y832453I-1502J0D01*
G01X274695D01*
G03X273847Y832190I1J-1502D01*
G01X273838Y832183D01*
X273800Y832162D01*
G02X273732Y832140I-95J176D01*
G01X273723Y832139D01*
G02X273647Y832149I-12J200D01*
G01X273514Y832204D01*
X273441Y832234D01*
G02X273439Y832235I88J179D01*
G01X273427Y832240D01*
G02X273312Y832386I81J182D01*
G01X269993Y851437D01*
G02X270021Y851577I197J33D01*
G01X270040Y851608D01*
X270096Y851651D01*
X270133Y851662D01*
G03X271202Y853100I-433J1438D01*
G03X269700Y854602I-1502J0D01*
G01X269698D01*
G03X269621Y854600I0J-1502D01*
G01X269610D01*
G02X269417Y854751I1J200D01*
G01X258275Y918722D01*
X239424Y1027694D01*
X238322Y1034065D01*
X238225Y1034624D01*
G02X238222Y1034658I197J35D01*
G01Y1039368D01*
G02X238225Y1039400I200J-3D01*
G01Y1039402D01*
G02X238279Y1039508I197J-34D01*
G01X244139Y1045368D01*
G02X244245Y1045422I140J-143D01*
G01X244247D01*
G02X244279Y1045425I35J-197D01*
G01X365260D01*
X365280Y1045393D01*
G03X365307Y1045391I28J198D01*
G01X382946D01*
G02X383146Y1045191I0J-200D01*
G01Y1037590D01*
G03X383703Y1036245I1902J0D01*
G01X401909Y1018039D01*
G03X403254Y1017482I1345J1345D01*
G01X424746D01*
G02X424946Y1017282I0J-200D01*
G01Y1015436D01*
G03X424949Y1015403I200J2D01*
G01X425086Y1015266D01*
G02X425102Y1015248I-141J-142D01*
G01X425121Y1015225D01*
X425131Y1015210D01*
X425134Y1015205D01*
G03X425137Y1015200I1031J615D01*
G01X425138Y1015199D01*
X425141Y1015194D01*
X425142Y1015193D01*
G03X425168Y1015155I1004J659D01*
G01X425169Y1015154D01*
G03X425171Y1015151I1000J665D01*
G03X425174Y1015147I963J719D01*
G01X425179Y1015140D01*
G03X425185Y1015132I964J717D01*
G01X425186Y1015131D01*
G03X425299Y1015000I964J717D01*
G01X425916Y1014383D01*
G03X426046Y1014270I851J848D01*
G01X426064Y1014257D01*
G03X426078Y1014247I705J972D01*
G01X426098Y1014233D01*
G03X426101Y1014231I668J998D01*
G01X426118Y1014220D01*
X426120Y1014218D01*
X426134Y1014210D01*
X426169Y1014183D01*
X426175Y1014177D01*
G03X426235Y1014139I135J147D01*
G01X426271Y1014124D01*
X426300D01*
X426335Y1014110D01*
G03X426416Y1014082I433J1121D01*
G01X426418D01*
G03X426437Y1014076I371J1142D01*
G01X426445Y1014074D01*
X426448Y1014073D01*
G03X426457Y1014070I384J1136D01*
G01X426460D01*
X426474Y1014066D01*
G03X426482Y1014064I295J1163D01*
G01X426486Y1014063D01*
G03X426492Y1014061I382J1136D01*
G01X426499Y1014060D01*
X426508Y1014058D01*
X426509D01*
X426512Y1014057D01*
X426513D01*
G03X426766Y1014030I253J1175D01*
G01X433508D01*
G03X433863Y1014092I-27J1201D01*
G01X433865D01*
G03X433900Y1014105I-401J1132D01*
G02X433905Y1014107I77J-185D01*
G01X433907D01*
X433909Y1014108D01*
G03X433916Y1014110I-326J1154D01*
G03X434054Y1014174I-436J1120D01*
G03X434203Y1014270I-574J1055D01*
G03X434334Y1014383I-717J964D01*
G01X434583Y1014632D01*
G03X434696Y1014763I-851J848D01*
G03X434832Y1014994I-961J721D01*
G03X434874Y1015101I-1096J492D01*
G01X434875Y1015104D01*
G03X434878Y1015113I-1138J384D01*
G01X434895Y1015165D01*
G03X434903Y1015200I-190J62D01*
G01X434914Y1015253D01*
G03X434936Y1015481I-1180J229D01*
G01Y1019807D01*
G03X434874Y1020162I-1201J-27D01*
G01Y1020164D01*
G03X434861Y1020199I-1132J-401D01*
G02X434859Y1020204I185J77D01*
G01Y1020206D01*
X434858Y1020208D01*
G03X434856Y1020215I-1154J-326D01*
G03X434792Y1020353I-1120J-436D01*
G03X434696Y1020502I-1055J-574D01*
G03X434583Y1020633I-964J-717D01*
G01X434089Y1021127D01*
G03X433958Y1021240I-848J-851D01*
G01X433956Y1021242D01*
G03X433950Y1021247I-769J-917D01*
G03X433946Y1021250I-723J-960D01*
G03X433940Y1021254I-114J-164D01*
G03X433934Y1021258I-669J-997D01*
G02X433930Y1021261I118J162D01*
G03X433921Y1021268I-127J-154D01*
G02X433919Y1021270I138J140D01*
G03X433913Y1021274I-669J-997D01*
G01X433910Y1021276D01*
X433903Y1021280D01*
G03X433892Y1021288I-712J-967D01*
G01X433866Y1021304D01*
G03X433854Y1021311I-611J-1034D01*
G01X433853Y1021312D01*
G03X433848Y1021315I-620J-1028D01*
G03X433841Y1021318I-82J-182D01*
G01X433840Y1021319D01*
G03X433835Y1021322I-621J-1029D01*
G01X433815Y1021333D01*
G03X433732Y1021374I-573J-1056D01*
G01X433698Y1021389D01*
X433666Y1021421D01*
G03X433524Y1021480I-142J-141D01*
G01X426107D01*
G03X426029Y1021464I0J-200D01*
G01X425993Y1021449D01*
X425981Y1021437D01*
X425976Y1021433D01*
G03X425970Y1021427I138J-144D01*
G01X425887Y1021344D01*
G02X425820Y1021300I-141J142D01*
G01X425786Y1021286D01*
X404125D01*
G02X404004Y1021327I0J200D01*
G01X403995Y1021335D01*
X403988Y1021342D01*
G03X403973Y1021355I-138J-144D01*
G01X387008Y1038320D01*
G02X386964Y1038387I142J141D01*
G01X386950Y1038421D01*
Y1120373D01*
G03X386590Y1121486I-1902J0D01*
G01X386572Y1121511D01*
X386542Y1121599D01*
G02X386533Y1121641I190J63D01*
G02X386532Y1121661I199J20D01*
G01Y1124574D01*
G02X386535Y1124606I200J-3D01*
G01Y1124608D01*
G02X386589Y1124714I197J-34D01*
G01X389478Y1127603D01*
G02X389584Y1127657I140J-143D01*
G01X389586D01*
G02X389618Y1127660I35J-197D01*
G01X392399D01*
G03X392541Y1127719I0J200D01*
G01X392720Y1127898D01*
G02X392742Y1127917I141J-141D01*
G02X392813Y1127951I120J-160D01*
G01X392824Y1127953D01*
G03X395134Y1128610I-2469J13072D01*
G03X403656Y1140998I-4781J12414D01*
G01Y1141025D01*
G03X401844Y1147727I-13302J-1D01*
G01X401830Y1147751D01*
X401817Y1147801D01*
G02X401811Y1147849I194J49D01*
G01Y1147893D01*
G02X401826Y1147941I197J-35D01*
G01X401881Y1148033D01*
X401897Y1148060D01*
G02X402064Y1148150I167J-110D01*
G01X430768D01*
G02X430800Y1148147I-3J-200D01*
G01X430802D01*
G02X430908Y1148093I-34J-197D01*
G01X431407Y1147594D01*
G02X431461Y1147488I-143J-140D01*
G01Y1147486D01*
G02X431464Y1147454I-197J-35D01*
G01Y1131238D01*
G02X431264Y1131038I-200J0D01*
G01X429235D01*
G03X429091Y1130977I0J-200D01*
G01X429062Y1130972D01*
G03X428642Y1130858I285J-1880D01*
G03X428003Y1130437I705J-1766D01*
G01X426632Y1129066D01*
G03X426192Y1128377I1345J-1344D01*
G03X426076Y1127721I1785J-654D01*
G01Y1115321D01*
G03X426192Y1114665I1901J-2D01*
G03X426632Y1113976I1785J655D01*
G01X430073Y1110535D01*
G02X430126Y1110433I-143J-139D01*
G02X430130Y1110395I-196J-40D01*
G01Y1108856D01*
Y1108851D01*
G02X430094Y1108742I-200J6D01*
G02X430069Y1108712I-165J112D01*
G01X429858Y1108507D01*
G02X429723Y1108456I-133J149D01*
G01X429719D01*
G03X429683Y1108457I-60J-1501D01*
G01X429676D01*
G03X428175Y1106955I1J-1502D01*
G03X429677Y1105453I1502J0D01*
G03X430503Y1105701I-1J1502D01*
G01X430504D01*
Y1105702D01*
X430511Y1105707D01*
G02X430655Y1105729I100J-173D01*
G01X430936Y1105668D01*
G02X431008Y1105637I-41J-195D01*
G01X431040Y1105615D01*
X431062Y1105580D01*
G03X431326Y1105248I1611J1010D01*
G01X432986Y1103588D01*
G03X433675Y1103148I1344J1345D01*
G03X434327Y1103032I654J1785D01*
G01X443802D01*
G03X444454Y1103148I-2J1901D01*
G03X445143Y1103588I-655J1785D01*
G01X448736Y1107182D01*
G02X448878Y1107241I142J-141D01*
G01X449079D01*
G02X449130Y1107152I-142J-141D01*
G03X449103Y1106867I1493J-285D01*
G03X449123Y1106622I1520J1D01*
G02X449099Y1106569I-192J55D01*
G01X448931Y1106338D01*
G02X448822Y1106265I-160J120D01*
G01X448813Y1106263D01*
G03X447614Y1104792I303J-1471D01*
G03X450618I1502J0D01*
G03X450609Y1104961I-1502J5D01*
G02X450642Y1105093I199J20D01*
G01X450811Y1105326D01*
G02X450831Y1105348I158J-123D01*
G01X450870Y1105367D01*
G03X451008Y1105397I-254J1499D01*
G02X451015Y1105395I-51J-193D01*
G02X451092Y1105357I-48J-194D01*
G01X451145Y1105315D01*
G02X451147Y1105313I-140J-142D01*
G01X451334Y1105160D01*
G02X451408Y1105005I-126J-155D01*
G01Y1103577D01*
G02X451386Y1103486I-200J0D01*
G02X451350Y1103436I-178J90D01*
G01X448936Y1101022D01*
G03X448496Y1099960I1062J-1062D01*
G01Y1098520D01*
G02X448474Y1098429I-200J0D01*
G02X448438Y1098379I-178J90D01*
G01X447459Y1097400D01*
G02X447409Y1097364I-140J142D01*
G02X447318Y1097342I-91J178D01*
G01X446072D01*
G02X445981Y1097364I0J200D01*
G02X445931Y1097400I90J178D01*
G01X441728Y1101603D01*
G03X440668Y1102042I-1061J-1062D01*
G01X431806D01*
G03X430746Y1101603I1J-1501D01*
G01X426543Y1097400D01*
G02X426493Y1097364I-140J142D01*
G02X426402Y1097342I-91J178D01*
G01X424670D01*
G02X424642Y1097344I0J200D01*
G02X424541Y1097389I28J198D01*
G01X424307Y1097623D01*
G02X424275Y1097671I149J134D01*
G02X424256Y1097744I181J86D01*
G01Y1100058D01*
G02X424331Y1100214I200J0D01*
G01X424573Y1100409D01*
G02X424654Y1100448I125J-156D01*
G01X424697Y1100458D01*
X424741Y1100449D01*
G03X425058Y1100415I318J1468D01*
G01X425075D01*
G03X426562Y1101917I-15J1502D01*
G03X425147Y1103416I-1501J0D01*
G01X425142D01*
G02X425003Y1103490I17J199D01*
G01X424815Y1103754D01*
G02X424781Y1103838I163J115D01*
G01X424776Y1103866D01*
X424782Y1103913D01*
X424784Y1103920D01*
X424785Y1103925D01*
G03X424842Y1104335I-1446J410D01*
G03X424747Y1104860I-1501J-1D01*
G02X424736Y1104954I188J70D01*
G01X424741Y1104998D01*
X424915Y1105267D01*
G02X424982Y1105331I168J-109D01*
G01X425094Y1105397D01*
X425118Y1105400D01*
G03X426497Y1106897I-123J1497D01*
G03X423493I-1502J0D01*
G03X423588Y1106372I1502J1D01*
G01X423597Y1106349D01*
X423602Y1106303D01*
X423599Y1106280D01*
G02X423569Y1106195I-199J22D01*
G01X423420Y1105965D01*
G02X423353Y1105901I-168J109D01*
G01X423241Y1105835D01*
X423218Y1105832D01*
G03X422776Y1105728I119J-1498D01*
G02X422742Y1105717I-78J184D01*
G01X422682Y1105705D01*
G02X422604Y1105721I0J200D01*
G01X422326Y1105854D01*
G02X422260Y1105904I85J181D01*
G01X422235Y1105934D01*
X422226Y1105962D01*
X422222Y1105977D01*
G03X420782Y1107054I-1440J-424D01*
G03X420582Y1107041I-3J-1502D01*
G03X420428Y1107012I201J-1489D01*
G01X420417Y1107009D01*
X420367Y1107003D01*
G02X420284Y1107022I2J200D01*
G01X419994Y1107188D01*
X419975Y1107212D01*
G03X418495Y1108387I-1480J-345D01*
G03X416975Y1106867I0J-1520D01*
G03X416995Y1106622I1520J1D01*
G02X416971Y1106569I-192J55D01*
G01X416803Y1106338D01*
G02X416694Y1106265I-160J120D01*
G01X416685Y1106263D01*
G03X415486Y1104792I303J-1471D01*
G03X418490I1502J0D01*
G03X418481Y1104961I-1502J5D01*
G02X418514Y1105093I199J20D01*
G01X418683Y1105326D01*
G02X418703Y1105348I158J-123D01*
G01X418742Y1105367D01*
G03X418880Y1105397I-254J1499D01*
G02X418887Y1105395I-51J-193D01*
G02X418964Y1105357I-48J-194D01*
G01X419017Y1105315D01*
G02X419019Y1105313I-140J-142D01*
G01X419206Y1105160D01*
G02X419280Y1105005I-126J-155D01*
G01Y1103819D01*
G02X419222Y1103678I-200J0D01*
G01X418617Y1103073D01*
X418136Y1102591D01*
G02X418017Y1102537I-138J145D01*
G02X417998Y1102536I-20J199D01*
G01X416263D01*
G03X415203Y1102097I1J-1501D01*
G01X414008Y1100902D01*
G03X413568Y1099840I1062J-1062D01*
G01Y1097888D01*
G03X414008Y1096826I1502J0D01*
G01X421169Y1089665D01*
G02X421222Y1089563I-143J-139D01*
G02X421226Y1089525I-196J-40D01*
G01Y1057470D01*
G03X421666Y1056408I1502J0D01*
G01X429200Y1048874D01*
G03X430262Y1048434I1062J1062D01*
G01X438526D01*
G02X438564Y1048430I-2J-200D01*
G02X438666Y1048377I-37J-196D01*
G01X448225Y1038818D01*
G03X449287Y1038378I1062J1062D01*
G01X452091D01*
G03Y1041382I0J1502D01*
G01X449992D01*
G02X449901Y1041404I0J200D01*
G02X449851Y1041440I90J178D01*
G01X440293Y1050998D01*
G03X439231Y1051438I-1062J-1062D01*
G01X430967D01*
G02X430876Y1051460I0J200D01*
G02X430826Y1051496I90J178D01*
G01X424288Y1058034D01*
G02X424252Y1058084I142J140D01*
G02X424230Y1058175I178J91D01*
G01Y1090230D01*
G03X423790Y1091292I-1502J0D01*
G01X416630Y1098452D01*
G02X416594Y1098502I142J140D01*
G02X416572Y1098593I178J91D01*
G01Y1099136D01*
G02X416575Y1099173I200J2D01*
G02X416620Y1099266I197J-38D01*
G01X416833Y1099480D01*
G02X416956Y1099534I137J-146D01*
G01X418705D01*
G03X419765Y1099973I-1J1501D01*
G01X420641Y1100849D01*
G02X420911Y1100861I142J-141D01*
G01X421203Y1100569D01*
G02X421235Y1100521I-149J-134D01*
G02X421254Y1100436I-181J-85D01*
G01Y1097049D01*
G03X421693Y1095989I1501J1D01*
G01X422904Y1094778D01*
G03X423966Y1094338I1062J1062D01*
G01X427107D01*
G03X428169Y1094778I0J1502D01*
G01X432372Y1098982D01*
G02X432477Y1099037I141J-142D01*
G02X432513Y1099040I35J-197D01*
G01X439961D01*
G02X440046Y1099021I0J-200D01*
G02X440094Y1098989I-86J-181D01*
G01X444305Y1094778D01*
G03X445367Y1094338I1062J1062D01*
G01X448023D01*
G03X449085Y1094778I0J1502D01*
G01X451060Y1096753D01*
G03X451500Y1097815I-1062J1062D01*
G01Y1099255D01*
G02X451504Y1099293I200J-2D01*
G02X451557Y1099395I196J-37D01*
G01X453972Y1101810D01*
G03X454391Y1102625I-1062J1061D01*
G01X454393Y1102634D01*
G02X454486Y1102764I195J-42D01*
G01X454758Y1102920D01*
G02X454844Y1102946I99J-174D01*
G01X454887Y1102949D01*
X454929Y1102933D01*
G03X454967Y1102919I538J1402D01*
G03X455061Y1102889I503J1415D01*
G03X455380Y1102836I404J1446D01*
G01X455386D01*
G02X455525Y1102762I-17J-199D01*
G01X455713Y1102498D01*
G02X455747Y1102414I-163J-115D01*
G01X455752Y1102386D01*
X455746Y1102339D01*
X455744Y1102332D01*
X455743Y1102327D01*
G03X455686Y1101917I1446J-410D01*
G03X458690I1502J0D01*
G03X457275Y1103416I-1501J0D01*
G01X457270D01*
G02X457131Y1103490I17J199D01*
G01X456943Y1103754D01*
G02X456909Y1103838I163J115D01*
G01X456904Y1103866D01*
X456910Y1103913D01*
X456912Y1103920D01*
X456913Y1103925D01*
G03X456970Y1104335I-1446J410D01*
G03X456875Y1104860I-1501J-1D01*
G02X456864Y1104954I188J70D01*
G01X456869Y1104998D01*
X457043Y1105267D01*
G02X457110Y1105331I168J-109D01*
G01X457222Y1105397D01*
X457246Y1105400D01*
G03X458625Y1106897I-123J1497D01*
G03X457694Y1108287I-1503J0D01*
G01X457656Y1108303D01*
X457626Y1108334D01*
G02X457616Y1108345I143J140D01*
G01X457600Y1108364D01*
X457579Y1108407D01*
X457549Y1108552D01*
G02X457545Y1108598I196J40D01*
G02X457605Y1108735I200J-6D01*
G01X457606Y1108736D01*
G03X457622Y1108751I-1292J1394D01*
G01X458058Y1109187D01*
X458129Y1109259D01*
G02X458241Y1109308I132J-150D01*
G02X458277Y1109309I24J-198D01*
G01X458580Y1109286D01*
G02X458664Y1109260I-16J-199D01*
G01X458700Y1109240D01*
X458726Y1109204D01*
G03X459938Y1108590I1212J889D01*
G03X461429Y1109909I0J1502D01*
G02X461542Y1110066I199J-24D01*
G02X461563Y1110074I82J-183D01*
G01X461902Y1110191D01*
G02X462108Y1110144I65J-189D01*
G01X463472Y1108780D01*
G02X463508Y1108730I-142J-140D01*
G02X463530Y1108639I-178J-91D01*
G01Y1108254D01*
G02X463529Y1108234I-200J0D01*
G02X463463Y1108105I-199J20D01*
G01X463240Y1107906D01*
G02X463231Y1107899I-127J154D01*
G02X463092Y1107856I-125J157D01*
G01X463085Y1107857D01*
G03X462913Y1107867I-173J-1492D01*
G03Y1104863I0J-1502D01*
G03X463901Y1105234I0J1501D01*
G01X463905Y1105237D01*
G02X464040Y1105283I128J-154D01*
G01X464311Y1105274D01*
G02X464398Y1105251I-6J-200D01*
G02X464436Y1105225I-93J-177D01*
G01X464441Y1105221D01*
G02X464446Y1105216I-139J-144D01*
G01X465886Y1103776D01*
G03X466575Y1103336I1344J1345D01*
G03X467227Y1103220I654J1785D01*
G01X475886D01*
G03X476538Y1103336I-2J1901D01*
G03X477227Y1103776I-655J1785D01*
G01X482422Y1108972D01*
G02X482524Y1109026I141J-142D01*
G02X482563Y1109030I40J-196D01*
G01X490182D01*
G03X490834Y1109146I-2J1901D01*
G03X491523Y1109586I-655J1785D01*
G01X491638Y1109702D01*
X491639Y1109703D01*
G02X491921I141J-142D01*
G01X491938Y1109686D01*
X491962Y1109646D01*
X491970Y1109623D01*
Y1109622D01*
G03X493397Y1108590I1427J471D01*
G03X494899Y1110092I0J1502D01*
G03X493976Y1111478I-1502J0D01*
G01X493939Y1111493D01*
X493910Y1111522D01*
G02X493867Y1111588I143J140D01*
G01X493760Y1111854D01*
G02X493746Y1111933I186J74D01*
G01X493747Y1111972D01*
X493761Y1112003D01*
X493764Y1112010D01*
G03X493926Y1112770I-1740J768D01*
G01Y1118387D01*
G02X493983Y1118527I200J0D01*
G01X496365Y1120909D01*
X496716Y1121261D01*
G02X496928Y1121299I136J-147D01*
G01X496950Y1121290D01*
X496985Y1121276D01*
X497019Y1121225D01*
G02X497052Y1121115I-167J-110D01*
G01Y1120944D01*
G02X497011Y1120823I-200J0D01*
G01X497003Y1120814D01*
X496996Y1120807D01*
G03X496983Y1120792I144J-138D01*
G01X495825Y1119634D01*
G03X495312Y1118396I1237J-1238D01*
G01Y1118393D01*
G03X495328Y1118157I1751J0D01*
G03X495334Y1118116I1736J233D01*
G01Y1118114D01*
G03X495336Y1118101I1732J260D01*
G01X495339Y1118085D01*
Y1118083D01*
G03X495345Y1118052I1723J317D01*
G01Y1118050D01*
G03X495346Y1118046I194J46D01*
G01X495347Y1118041D01*
X495348Y1118037D01*
X495349Y1118034D01*
G03X495358Y1117996I1708J385D01*
G01X495361Y1117984D01*
G03X495363Y1117975I1709J375D01*
G01Y1117973D01*
G03X495364Y1117968I197J37D01*
G01X495365Y1117965D01*
Y1117964D01*
G03X495388Y1117883I1696J438D01*
G01X495397Y1117854D01*
X495402Y1117838D01*
X495421Y1117781D01*
G03X495427Y1117765I190J62D01*
G01X495440Y1117734D01*
X495444Y1117727D01*
G03X495802Y1117180I1619J669D01*
G01X495803Y1117179D01*
X495822Y1117159D01*
X495832Y1117149D01*
X495848Y1117132D01*
X495861Y1117103D01*
G02X495878Y1117044I-182J-84D01*
G01X495887Y1116915D01*
Y1116913D01*
X495890Y1116880D01*
X495871Y1116813D01*
X495849Y1116781D01*
X495838Y1116766D01*
X495830Y1116755D01*
X495804Y1116717D01*
G03X495560Y1115896I1259J-821D01*
G01Y1115872D01*
X495563Y1115818D01*
G03X497063Y1114394I1500J78D01*
G03X498565Y1115883I0J1502D01*
G01Y1115898D01*
G03X498286Y1116771I-1503J1D01*
G01X498285Y1116772D01*
X498276Y1116785D01*
X498258Y1116819D01*
G02X498239Y1116897I181J85D01*
G01Y1116922D01*
X498250Y1117049D01*
G02X498306Y1117162I198J-28D01*
G01X498332Y1117188D01*
X500041Y1118898D01*
G03X500554Y1120136I-1237J1238D01*
G01Y1125407D01*
X500561Y1125458D01*
X500563Y1125465D01*
G03X500628Y1125958I-1836J493D01*
G01Y1128762D01*
G03X500561Y1129261I-1901J-1D01*
G01X500554Y1129287D01*
Y1147669D01*
G02X500557Y1147701I200J-3D01*
G01Y1147703D01*
G02X500611Y1147809I197J-34D01*
G01X501101Y1148299D01*
G02X501207Y1148353I140J-143D01*
G01X501209D01*
G02X501241Y1148356I35J-197D01*
G01X528492D01*
G02X528524Y1148353I-3J-200D01*
G01X528526D01*
G02X528632Y1148299I-34J-197D01*
G01X529123Y1147808D01*
G02X529177Y1147702I-143J-140D01*
G01Y1147700D01*
G02X529180Y1147668I-197J-35D01*
G01Y1120944D01*
G02X529139Y1120823I-200J0D01*
G01X529131Y1120814D01*
X529124Y1120807D01*
G03X529111Y1120792I145J-138D01*
G01X527953Y1119634D01*
G03X527440Y1118396I1237J-1238D01*
G01Y1118393D01*
G03X527456Y1118157I1751J0D01*
G03X527467Y1118085I1736J228D01*
G01Y1118082D01*
G03X527469Y1118074I1700J421D01*
G01Y1118072D01*
X527470Y1118066D01*
X527471Y1118062D01*
Y1118061D01*
X527474Y1118046D01*
Y1118044D01*
G03X527481Y1118015I1706J396D01*
G01Y1118014D01*
G03X527486Y1117994I1702J415D01*
G01Y1117993D01*
G03X527516Y1117883I1704J406D01*
G01X527525Y1117854D01*
X527530Y1117838D01*
X527549Y1117781D01*
G03X527555Y1117765I190J62D01*
G01X527568Y1117734D01*
X527572Y1117727D01*
G03X527909Y1117202I1619J669D01*
G03X527929Y1117181I1278J1198D01*
G01X527950Y1117159D01*
X527975Y1117134D01*
X527990Y1117101D01*
G02X528007Y1117038I-182J-83D01*
G01X528015Y1116915D01*
Y1116913D01*
X528018Y1116880D01*
X527999Y1116813D01*
X527977Y1116781D01*
X527966Y1116766D01*
X527958Y1116755D01*
X527932Y1116717D01*
G03X527688Y1115896I1259J-821D01*
G01Y1115872D01*
X527691Y1115818D01*
G03X529191Y1114394I1500J78D01*
G03X530693Y1115883I0J1502D01*
G01Y1115898D01*
G03X530414Y1116771I-1503J1D01*
G01X530413Y1116772D01*
X530404Y1116785D01*
X530386Y1116819D01*
G02X530367Y1116897I181J85D01*
G01Y1116922D01*
X530378Y1117049D01*
G02X530434Y1117162I198J-28D01*
G01X530460Y1117188D01*
X532169Y1118898D01*
G03X532682Y1120136I-1237J1238D01*
G01Y1148477D01*
G03X532169Y1149715I-1750J0D01*
G01X530539Y1151345D01*
G03X529301Y1151858I-1238J-1237D01*
G01X500433D01*
G03X499195Y1151345I0J-1750D01*
G01X498948Y1151099D01*
X498944Y1151095D01*
G02X498662I-141J142D01*
G01X498634Y1151123D01*
X498454Y1151302D01*
G03X498440Y1151316I-1245J-1231D01*
G01X498411Y1151345D01*
G03X497173Y1151858I-1238J-1237D01*
G01X466970D01*
G03X466565Y1151810I2J-1751D01*
G01X466542Y1151804D01*
X434791D01*
G03X433553Y1151290I1J-1751D01*
G01X433465Y1151202D01*
G02X433183I-141J142D01*
G01X432987Y1151398D01*
G03X432208Y1151869I-1346J-1346D01*
G03X431644Y1151955I-566J-1817D01*
G01X431641D01*
G03X431582Y1151954I3J-1903D01*
G01X402969D01*
G02X402828Y1152012I0J200D01*
G01X400255Y1154584D01*
G02Y1154866I142J141D01*
G01X401276Y1155887D01*
G02X401382Y1155941I140J-143D01*
G01X401384D01*
G02X401416Y1155944I35J-197D01*
G01X530601D01*
G02X530633Y1155941I-3J-200D01*
G01X530635D01*
G02X530741Y1155887I-34J-197D01*
G01X533759Y1152869D01*
G02X533813Y1152763I-143J-140D01*
G01Y1152761D01*
G02X533816Y1152729I-197J-35D01*
G01Y1099862D01*
G02X533679Y1099673I-200J1D01*
G01X533644Y1099664D01*
G03X532523Y1099373I2779J-13009D01*
G03X528385Y1097257I3894J-12719D01*
G03Y1076051I8032J-10603D01*
G03X529427Y1075337I8031J10604D01*
G03X533642Y1073645I6990J11317D01*
G01X533649Y1073644D01*
X533654Y1073642D01*
X533670Y1073637D01*
X533679Y1073634D01*
G02X533816Y1073444I-63J-190D01*
G01Y1007127D01*
G02X533775Y1007006I-200J0D01*
G01X533767Y1006997D01*
X533760Y1006990D01*
G03X533747Y1006975I143J-137D01*
G01X533637Y1006865D01*
G03X533578Y1006723I141J-142D01*
G01Y1001580D01*
G02X533537Y1001459I-200J0D01*
G01X533529Y1001450D01*
X533522Y1001443D01*
G03X533509Y1001428I143J-137D01*
G01X524727Y992646D01*
G02X524513Y992602I-141J142D01*
G01X524172Y992735D01*
G02X524160Y992740I71J187D01*
G02X524045Y992914I85J181D01*
G03X522544Y994356I-1501J-60D01*
G03X521042Y992854I0J-1502D01*
G03X522484Y991353I1502J0D01*
G02X522659Y991235I-7J-200D01*
G01X522735Y991041D01*
X522796Y990885D01*
G02X522752Y990671I-186J-73D01*
G01X517917Y985836D01*
G02X517850Y985792I-141J142D01*
G01X517816Y985778D01*
X513786D01*
G02X513684Y985806I0J200D01*
G01X513602Y985855D01*
G02X513531Y985927I102J172D01*
G03X512232Y986674I-1299J-756D01*
G03X510817Y985675I0J-1502D01*
G01X510813Y985663D01*
G02X510633Y985542I-184J79D01*
G01X508492D01*
G02X508376Y985579I0J200D01*
G02X508324Y985632I114J164D01*
G01X508305Y985670D01*
X508303Y985679D01*
G03X508023Y986156I-1414J-509D01*
G03X508021Y986160I-174J-84D01*
G03X507996Y986186I-1096J-1029D01*
G01X507984Y986198D01*
G03X507910Y986272I-1098J-1024D01*
G01X507908Y986274D01*
G03X507880Y986300I-1036J-1088D01*
G03X507878Y986302I-142J-140D01*
G03X507847Y986329I-1002J-1119D01*
G01X507830Y986343D01*
X507821Y986351D01*
X507805Y986376D01*
G02X507783Y986425I170J106D01*
G01X507768Y986481D01*
X507758Y986521D01*
Y986522D01*
G03X507718Y986601I-194J-49D01*
G03X507565Y986673I-154J-128D01*
G01X506885D01*
G03X506060Y986425I2J-1502D01*
G03X505810Y986217I831J-1253D01*
G01X505782Y986188D01*
X505671Y986138D01*
G02X505597Y986123I-76J185D01*
G01X505348D01*
G02X505227Y986164I0J200D01*
G01X505215Y986175D01*
G03X505209Y986180I-131J-151D01*
G01X505205Y986183D01*
X505204Y986184D01*
X505201Y986186D01*
X505200Y986187D01*
X505188Y986196D01*
X505157Y986227D01*
G03X504109Y986673I-1068J-1056D01*
G01X504056D01*
G03X502787Y985923I32J-1502D01*
G01X502776Y985903D01*
X502772Y985895D01*
X502768Y985888D01*
G03X502697Y985739I1319J-720D01*
G01Y985738D01*
X502683Y985702D01*
G03X502675Y985683I1380J-592D01*
G01X502659Y985641D01*
X502629Y985611D01*
G02X502609Y985593I-144J139D01*
G01X502607D01*
G02X502563Y985567I-123J158D01*
G01X502497Y985544D01*
X502443Y985542D01*
X413799D01*
G02X413658Y985600I0J200D01*
G01X413539Y985719D01*
G03X413397Y985778I-142J-141D01*
G01X402830D01*
G03X402688Y985719I0J-200D01*
G01X400822Y983853D01*
G03X400763Y983711I141J-142D01*
G01Y961581D01*
G03X400822Y961439I200J0D01*
G01X401250Y961011D01*
G02X401307Y960852I-142J-141D01*
G01X401299Y960778D01*
Y960776D01*
X401271Y960538D01*
X401266Y960513D01*
G02X401195Y960402I-194J46D01*
G01X401190Y960398D01*
X401177Y960390D01*
G03X400993Y960255I795J-1276D01*
G01X400960Y960227D01*
X400917Y960214D01*
G02X400838Y960208I-54J193D01*
G01X400588Y960239D01*
X400550Y960244D01*
X400478Y960283D01*
X400472Y960287D01*
X400445Y960304D01*
X400390Y960354D01*
X400378Y960369D01*
X400376Y960371D01*
G03X399177Y960970I-1201J-904D01*
G01X399173D01*
G03Y957966I0J-1502D01*
G01X399234D01*
G03X400121Y958302I-62J1502D01*
G01X400147Y958323D01*
X400280Y958375D01*
X400331Y958369D01*
X400411Y958359D01*
X400413D01*
X400566Y958338D01*
G02X400613Y958324I-33J-197D01*
G03X400617Y958322I91J178D01*
G02X400622Y958320I-72J-187D01*
G01X400734Y958251D01*
X400757Y958219D01*
G03X401051Y957921I1207J896D01*
G01X401062Y957913D01*
X401086Y957889D01*
X401096Y957877D01*
G02X401126Y957830I-152J-130D01*
G01X401137Y957805D01*
X401141Y957777D01*
X401182Y957494D01*
X401184Y957453D01*
X401177Y957424D01*
G02X401151Y957365I-194J50D01*
G01X401144Y957355D01*
G03X401135Y957343I1197J-907D01*
G01X401134Y957341D01*
X401118Y957320D01*
X401112Y957311D01*
X401111Y957309D01*
X401109Y957306D01*
X401108Y957305D01*
G03X400852Y956465I1246J-839D01*
G01Y956436D01*
X400853Y956416D01*
G03X401392Y955311I1502J49D01*
G03X402177Y954973I962J1154D01*
G01X402181D01*
X402191Y954972D01*
X402198Y954971D01*
G03X402216Y954969I175J1492D01*
G01X402231Y954968D01*
X402235Y954967D01*
G03X402738Y955012I120J1498D01*
G01X402875Y955049D01*
G03X402914Y955064I-52J193D01*
G01X403034Y955125D01*
G03X403189Y955217I-688J1335D01*
G01X403191D01*
G03X403273Y955276I-836J1248D01*
G01X403279Y955281D01*
X403299Y955294D01*
X403311Y955302D01*
X403354Y955324D01*
G02X403436Y955342I83J-182D01*
G01X403454D01*
X403680Y955323D01*
G02X403752Y955303I-17J-199D01*
G01X403848Y955256D01*
X403874Y955229D01*
X403881Y955222D01*
G03X404398Y954867I1090J1034D01*
G03X404942Y954754I572J1389D01*
G01X404976D01*
G03X405046Y954755I14J1502D01*
G01X405083Y954758D01*
X405084D01*
G03X406179Y955363I-113J1498D01*
G01X406204Y955397D01*
X406349Y955480D01*
X406393Y955484D01*
X406652Y955507D01*
X406691D01*
G02X406812Y955449I-21J-199D01*
G01X409053Y953208D01*
G03X409195Y953149I142J141D01*
G01X470417D01*
G02X470449Y953146I-3J-200D01*
G01X470451D01*
G02X470557Y953092I-34J-197D01*
G01X473090Y950559D01*
G03X473232Y950500I142J141D01*
G01X482013D01*
G02X482045Y950497I-3J-200D01*
G01X482047D01*
G02X482153Y950443I-34J-197D01*
G01X491656Y940940D01*
G02X491707Y940744I-141J-141D01*
G01X491606Y940448D01*
G02X491556Y940369I-189J65D01*
G01X491548Y940361D01*
X491472Y940300D01*
X491446Y940279D01*
X491402Y940259D01*
X491384Y940256D01*
X491380Y940255D01*
X491373Y940254D01*
G03X490114Y938771I244J-1483D01*
G03X491616Y937269I1502J0D01*
G03X493099Y938526I0J1503D01*
G01Y938528D01*
X493104Y938554D01*
X493113Y938575D01*
G02X493141Y938621I183J-80D01*
G01X493202Y938697D01*
X493204Y938699D01*
X493219Y938718D01*
X493267Y938752D01*
X493295Y938762D01*
X493557Y938851D01*
G02X493621Y938862I65J-189D01*
G01X493698D01*
G02X493784Y938812I-54J-192D01*
G01X498926Y933670D01*
G02X498980Y933564I-143J-140D01*
G01Y933562D01*
G02X498983Y933530I-197J-35D01*
G01Y867298D01*
X498977Y867263D01*
X498969Y867220D01*
X498940Y867165D01*
X498916Y867142D01*
X498714Y866949D01*
X498685Y866921D01*
X498615Y866893D01*
X498558D01*
G03X498531Y866894I-69J-1500D01*
G01X498506D01*
G03Y863890I1J-1502D01*
G01X498531D01*
G03X498558Y863891I-42J1501D01*
G01X498615D01*
X498685Y863863D01*
X498714Y863835D01*
X498921Y863637D01*
X498926Y863632D01*
G02X498980Y863526I-143J-140D01*
G01Y863524D01*
G02X498983Y863492I-197J-35D01*
G01Y863013D01*
G02X498969Y862947I-200J8D01*
G02X498935Y862890I-186J72D01*
G01X498895Y862843D01*
X498866Y862826D01*
G03X498137Y861547I774J-1288D01*
G01X498138Y861520D01*
Y861508D01*
G03X498141Y861443I1501J37D01*
G01Y861441D01*
G03X498148Y861361I1499J91D01*
G01X498149Y861353D01*
Y861351D01*
G03X498153Y861319I1492J170D01*
G01Y861315D01*
G03X498155Y861304I1479J263D01*
G01X498156Y861300D01*
G03X498163Y861263I1479J261D01*
G01Y861257D01*
G03X498166Y861239I1484J238D01*
G03X498168Y861233I189J60D01*
G03X498516Y860541I1471J306D01*
G01X498560Y860492D01*
G03X498570Y860482I147J137D01*
G01X498609Y860445D01*
G03X498842Y860265I1031J1093D01*
G01X498843Y860264D01*
X498863Y860251D01*
X498878Y860236D01*
G02X498909Y860196I-141J-142D01*
G01X498953Y860122D01*
G02X498963Y860103I-172J-103D01*
G01X498965Y860099D01*
G02X498983Y860020I-182J-83D01*
G01Y782808D01*
G03X499042Y782666I200J0D01*
G01X502699Y779009D01*
G03X502841Y778950I142J141D01*
G01X565443D01*
G02X565613Y778854I-1J-200D01*
G01X565646Y778801D01*
X565652Y778773D01*
X565654Y778765D01*
Y778764D01*
G03X567126Y777564I1472J303D01*
G03X568599Y778771I0J1502D01*
G01X568601Y778781D01*
X568611Y778816D01*
G02X568775Y778949I189J-66D01*
G02X568791Y778950I20J-199D01*
G01X584012D01*
G02X584156Y778888I-1J-200D01*
G01X584361Y778676D01*
G02X584411Y778544I-150J-132D01*
G01Y778521D01*
G03X584410Y778499I1500J-79D01*
G01Y778440D01*
G03X585093Y777211I1502J30D01*
G01X585110Y777200D01*
X585140Y777170D01*
G02X585197Y777030I-143J-140D01*
G01Y776991D01*
X583683Y769000D01*
Y768998D01*
X583633Y768750D01*
G02X583593Y768678I-191J59D01*
G01X583575Y768657D01*
X583531Y768627D01*
X583485Y768614D01*
G02X583443Y768608I-49J193D01*
G01X583427Y768609D01*
X583408Y768610D01*
G02X583400Y768611I21J199D01*
G01X583399D01*
X583397Y768612D01*
X583395D01*
X583390Y768613D01*
G03X583111Y768639I-278J-1477D01*
G01X583102D01*
G03X581600Y767137I0J-1502D01*
G03X582844Y765657I1502J0D01*
G01X582845D01*
X582860Y765654D01*
G02X583010Y765446I-50J-194D01*
G01X578360Y740890D01*
X577092Y734194D01*
G02X577040Y734103I-194J50D01*
G01X577013Y734076D01*
X576940Y734036D01*
X576938D01*
X576719Y733915D01*
G02X576637Y733893I-92J178D01*
G01X576595Y733890D01*
X576551Y733908D01*
G03X575988Y734019I-567J-1392D01*
G01X575964D01*
G03X574477Y732517I15J-1502D01*
G03X575979Y731015I1502J0D01*
G01X576002D01*
X576043Y731008D01*
X576078Y731002D01*
X576108Y730985D01*
G02X576160Y730942I-99J-173D01*
G01X576285Y730794D01*
X576347Y730720D01*
X576368Y730690D01*
X576375Y730679D01*
G02X576395Y730635I-171J-104D01*
G02X576404Y730559I-191J-61D01*
G01X576309Y730057D01*
X576271Y729857D01*
G02X576241Y729790I-195J47D01*
G01X576212Y729756D01*
G02X576174Y729724I-147J136D01*
G01X576172Y729723D01*
X576107Y729681D01*
X576092Y729676D01*
X576082Y729673D01*
G03X575027Y728219I474J-1454D01*
G03X575612Y727016I1529J0D01*
G01X575621Y727009D01*
X575656Y726974D01*
G02X575697Y726827I-157J-123D01*
G01X575386Y725186D01*
X564333Y666820D01*
G03X564328Y666791I3833J-676D01*
G01X564324Y666771D01*
X564323Y666760D01*
X554540Y615103D01*
X546482Y572557D01*
G03X546446Y572331I3824J-725D01*
G01X546172Y570208D01*
Y570207D01*
X546127Y569862D01*
X543978Y553521D01*
X536889Y499628D01*
G02X536840Y499521I-198J26D01*
G01X536801Y499478D01*
X536790Y499475D01*
X536788Y499474D01*
X536787D01*
X536676Y499445D01*
G02X536637Y499441I-40J196D01*
G01X536501D01*
G02X536422Y499458I2J200D01*
G01X536404Y499466D01*
X536389Y499474D01*
G02X536349Y499505I102J172D01*
G01X536324Y499530D01*
X536315Y499542D01*
G03X535119Y500135I-1196J-910D01*
G03X533617Y498652I0J-1502D01*
G01Y498633D01*
G03X533621Y498517I1502J-6D01*
G01X533624Y498474D01*
X533609Y498433D01*
G02X533563Y498361I-188J69D01*
G01X533554Y498352D01*
X533550Y498277D01*
G03X533593Y498143I200J-10D01*
G01X533926Y497720D01*
X533927Y497718D01*
X533928Y497717D01*
G02X533934Y497710I-149J-134D01*
G01X533939Y497703D01*
X533940Y497702D01*
G03X533944Y497697I158J122D01*
G01X533946Y497694D01*
X533959Y497676D01*
X533973Y497645D01*
G02X533987Y497572I-186J-73D01*
G01Y497488D01*
G03X534005Y497405I200J0D01*
G01X534029Y497352D01*
G02X534004Y497144I-181J-84D01*
G01X533982Y497116D01*
X533968Y497098D01*
X533966Y497095D01*
X533964Y497093D01*
X533961Y497089D01*
G03X533617Y496149I1158J-957D01*
G01Y496137D01*
G03X533733Y495553I1502J-5D01*
G03X533943Y495197I1387J578D01*
G01X533958Y495178D01*
X533968Y495157D01*
G02X533987Y495072I-181J-85D01*
G01Y494988D01*
G03X534005Y494905I200J0D01*
G01X534029Y494852D01*
G02X534004Y494644I-181J-84D01*
G01X533982Y494616D01*
X533968Y494598D01*
X533966Y494595D01*
X533964Y494593D01*
X533961Y494589D01*
G03X533617Y493649I1158J-957D01*
G01Y493637D01*
G03X533733Y493053I1502J-5D01*
G03X533943Y492697I1387J578D01*
G01X533958Y492678D01*
X533968Y492657D01*
G02X533987Y492572I-181J-85D01*
G01Y492488D01*
G03X534005Y492405I200J0D01*
G01X534029Y492352D01*
G02X534004Y492144I-181J-84D01*
G01X533982Y492116D01*
X533968Y492098D01*
X533966Y492095D01*
X533960Y492088D01*
G03X533619Y491210I1159J-955D01*
G03X533617Y491137I1500J-78D01*
G01Y491133D01*
G03X535119Y489631I1502J0D01*
G03X535279Y489640I-4J1502D01*
G01X535292Y489641D01*
G02X535368Y489629I7J-200D01*
G01X535411Y489613D01*
X535484Y489539D01*
G02X535540Y489372I-142J-141D01*
G01X535416Y488426D01*
X535143Y486352D01*
X535036Y485537D01*
G02X534981Y485424I-198J27D01*
G01X534937Y485378D01*
X534901Y485372D01*
X534894Y485371D01*
G03X533617Y483886I225J-1485D01*
G03X534060Y482821I1502J0D01*
G01X534074Y482807D01*
X534110Y482753D01*
X534121Y482737D01*
X534151Y482667D01*
G02X534160Y482640I-185J-77D01*
G01Y482638D01*
G02X534167Y482589I-193J-53D01*
G01Y482346D01*
G02X534126Y482225I-200J0D01*
G01X534118Y482216D01*
X534111Y482209D01*
G03X534098Y482194I144J-138D01*
G01X534086Y482182D01*
X534074Y482165D01*
X534062Y482153D01*
G03X533617Y481086I1057J-1067D01*
G03X533630Y480886I1502J-3D01*
G03X533942Y480152I1489J200D01*
G01X533958Y480132D01*
X533972Y480101D01*
G02X533987Y480025I-185J-76D01*
G01Y479941D01*
G03X533995Y479886I200J1D01*
G01X533998Y479871D01*
Y479661D01*
G02X533986Y479593I-200J0D01*
G01X533975Y479562D01*
X533961Y479544D01*
G03X533616Y478594I1158J-958D01*
G01X533617Y478556D01*
Y478555D01*
G03X533618Y478522I1501J29D01*
G01X533621Y478412D01*
G03X533632Y478351I200J5D01*
G01X533635Y478341D01*
G03X533644Y478296I1478J272D01*
G01X533649Y478275D01*
Y478274D01*
G03X533651Y478265I1467J321D01*
G01X533656Y478243D01*
G03X533959Y477631I1463J343D01*
G02X533961Y477629I-140J-142D01*
G01X533964Y477625D01*
X533985Y477547D01*
X533911Y476980D01*
X533894Y476956D01*
G03X533789Y476784I1227J-867D01*
G03X533644Y476372I1329J-699D01*
G01X533643Y476366D01*
G03X533617Y476120I1476J-280D01*
G01Y476046D01*
G03X533704Y475579I1502J38D01*
G01X533709Y475567D01*
G03X533715Y475550I1420J492D01*
G01X533721Y475535D01*
X533411Y473183D01*
G02X533404Y473151I-198J27D01*
G01X531496Y466856D01*
X530227Y462669D01*
G02X530127Y462549I-192J58D01*
G02X529995Y462531I-92J178D01*
G01X529978Y462536D01*
G02X529922Y462562I55J193D01*
G01X529901Y462577D01*
X529882Y462600D01*
G03X529852Y462635I-1154J-959D01*
G01X529850Y462637D01*
X529846Y462642D01*
G03X529770Y462723I-1133J-987D01*
G03X529739Y462753I-1060J-1064D01*
G01X529738Y462754D01*
X529727Y462764D01*
G03X528739Y463154I-1009J-1110D01*
G01X528714D01*
G03X527833Y462868I1J-1502D01*
G01X527800Y462843D01*
X527781Y462828D01*
G02X527747Y462807I-122J159D01*
G01X527743Y462805D01*
G02X527654Y462784I-89J179D01*
G01X527571D01*
G03X527488Y462766I0J-200D01*
G01X527435Y462742D01*
G02X527227Y462767I-84J181D01*
G01X527199Y462789D01*
X527181Y462803D01*
X527178Y462805D01*
G03X526217Y463154I-962J-1152D01*
G01X526216D01*
G03X526161Y463153I0J-1502D01*
G01X526148D01*
G03X524714Y461671I68J-1501D01*
G01Y461652D01*
G03X524718Y461536I1502J-6D01*
G01Y461535D01*
X524721Y461493D01*
X524706Y461452D01*
G02X524660Y461380I-188J69D01*
G01X524651Y461371D01*
X524647Y461296D01*
G03X524690Y461162I200J-10D01*
G01X525023Y460739D01*
X525024Y460737D01*
X525025Y460736D01*
G02X525031Y460729I-149J-134D01*
G01X525036Y460722D01*
X525037Y460721D01*
G03X525041Y460716I158J122D01*
G01X525043Y460713D01*
X525056Y460695D01*
X525070Y460664D01*
G02X525084Y460591I-186J-73D01*
G01Y460507D01*
G03X525102Y460424I200J0D01*
G01X525126Y460371D01*
G02X525101Y460163I-181J-84D01*
G01X525079Y460135D01*
X525065Y460117D01*
X525063Y460114D01*
X525061Y460112D01*
X525058Y460108D01*
G03X524714Y459168I1158J-957D01*
G01Y459156D01*
G03X524830Y458572I1502J-5D01*
G03X525040Y458216I1387J578D01*
G01X525055Y458197D01*
X525065Y458176D01*
G02X525084Y458091I-181J-85D01*
G01Y458007D01*
G03X525102Y457924I200J0D01*
G01X525126Y457871D01*
G02X525101Y457663I-181J-84D01*
G01X525079Y457635D01*
X525065Y457617D01*
X525063Y457614D01*
X525057Y457607D01*
G03X524716Y456729I1159J-955D01*
G03X524714Y456656I1500J-78D01*
G01Y456652D01*
G03X526216Y455150I1502J0D01*
G01X526217D01*
G03X527151Y455476I0J1502D01*
G01X527170Y455491D01*
X527199Y455504D01*
G02X527277Y455520I78J-184D01*
G01X527361D01*
G03X527420Y455529I0J200D01*
G01X527436Y455534D01*
X527504Y455565D01*
G02X527712Y455534I79J-184D01*
G01X527722Y455525D01*
X527723Y455524D01*
X527733Y455516D01*
G03X527777Y455479I989J1131D01*
G03X527831Y455437I949J1165D01*
G01X527833D01*
G03X527839Y455432I958J1144D01*
G01X527843Y455430D01*
X527860Y455417D01*
X527888Y455385D01*
X527966Y455239D01*
G02X527961Y455196I-200J1D01*
G01X513047Y405991D01*
X513044Y405981D01*
G03X513043Y405978I3723J-1243D01*
G03X513039Y405966I3722J-1247D01*
G01X505376Y380684D01*
X505350Y380653D01*
G03X504998Y379687I1150J-966D01*
G01Y379685D01*
G03X505007Y379521I1502J0D01*
G01Y379517D01*
X505011Y379481D01*
X492500Y338206D01*
G03X492395Y337771I3758J-1137D01*
G03X492332Y337067I3863J-701D01*
G01Y337035D01*
X493080Y246470D01*
Y240221D01*
G02X493075Y240218I-105J170D01*
G01X493048Y240203D01*
X492928Y240173D01*
G03X491796Y238890I360J-1459D01*
G01X491790Y238835D01*
G03X491785Y238714I1498J-123D01*
G03X492783Y237297I1505J0D01*
G01X492808Y237288D01*
X492811Y237287D01*
X492832Y237272D01*
G02X492871Y237235I-117J-162D01*
G01X492887Y237215D01*
X492939Y237148D01*
G02X492978Y237034I-161J-119D01*
G01Y237018D01*
X492869Y235085D01*
Y235081D01*
X492547Y231521D01*
G02X492458Y231380I-198J27D01*
G01X492457D01*
G03X491770Y230117I817J-1263D01*
G01Y230116D01*
G03X492246Y229020I1502J1D01*
G01X492261Y229006D01*
X492286Y228968D01*
X492294Y228947D01*
G02X492306Y228859I-187J-70D01*
G01X492294Y228729D01*
X492259Y228347D01*
X492025Y225762D01*
G03X492010Y225408I3911J-343D01*
G01Y225347D01*
Y225343D01*
X492078Y220984D01*
Y220970D01*
X491281Y206773D01*
X491104Y203609D01*
G02X491086Y203546I-199J23D01*
G01X491070Y203513D01*
X491039Y203485D01*
X491038Y203484D01*
X491017Y203465D01*
X490744Y203329D01*
G02X490655Y203308I-89J179D01*
G01X490545D01*
G02X490493Y203315I0J200D01*
G01X490468Y203322D01*
X490444Y203336D01*
G03X489673Y203550I-773J-1288D01*
G01X489672D01*
G03X489265Y203495I-4J-1502D01*
G03X488628Y203130I406J-1447D01*
G03X488393Y202841I1040J-1086D01*
G01X488383Y202825D01*
G02X488329Y202776I-159J121D01*
G01X488311Y202764D01*
X488269Y202750D01*
X488058Y202728D01*
X488056D01*
X487945Y202718D01*
G02X487888Y202721I-18J199D01*
G01X487864Y202726D01*
G02X487820Y202741I42J195D01*
G01X487784Y202760D01*
X487761Y202784D01*
G03X486673Y203250I-1088J-1036D01*
G01X486672D01*
G03X486613Y203249I-4J-1502D01*
G03X485254Y202244I59J-1501D01*
G01X485253Y202242D01*
X485243Y202212D01*
G03X485188Y201985I1428J-466D01*
G01Y201983D01*
G03X485178Y201906I1484J-232D01*
G01Y201903D01*
X485171Y201841D01*
G03X485170Y201819I199J-20D01*
G01Y201747D01*
G03X485174Y201632I1502J-5D01*
G01X485177Y201589D01*
X485162Y201548D01*
G02X485116Y201476I-188J69D01*
G01X485107Y201467D01*
X485103Y201392D01*
G03X485146Y201258I200J-10D01*
G01X485479Y200835D01*
X485480Y200833D01*
X485481Y200832D01*
G02X485487Y200825I-149J-134D01*
G01X485492Y200818D01*
X485493Y200817D01*
G03X485497Y200812I158J122D01*
G01X485499Y200809D01*
X485512Y200791D01*
X485526Y200760D01*
G02X485540Y200687I-186J-73D01*
G01Y200603D01*
G03X485558Y200520I200J0D01*
G01X485582Y200467D01*
G02X485557Y200259I-181J-84D01*
G01X485535Y200231D01*
X485521Y200213D01*
X485519Y200210D01*
X485517Y200208D01*
X485514Y200204D01*
G03X485170Y199264I1158J-957D01*
G01Y199252D01*
G03X485200Y198949I1502J-4D01*
G03X486610Y197747I1472J299D01*
G01X486624D01*
G03X486641Y197746I97J1498D01*
G01X486679D01*
X486684Y197745D01*
X486696D01*
G03X487824Y198282I-23J1502D01*
G01X487827Y198286D01*
X487851Y198315D01*
X487890Y198341D01*
X487904Y198348D01*
X487978Y198383D01*
G02X488027Y198399I86J-181D01*
G02X488060Y198402I35J-197D01*
G01X488263D01*
G02X488311Y198396I-1J-200D01*
G01X488375Y198380D01*
X488394Y198371D01*
X488438Y198350D01*
X488457Y198341D01*
X488494Y198313D01*
X488510Y198294D01*
X488511Y198293D01*
X488523Y198279D01*
G03X488656Y198141I1146J972D01*
G03X489672Y197745I1016J1105D01*
G03X489794Y197750I0J1503D01*
G01X489811Y197752D01*
X489816Y197753D01*
G03X490184Y197836I-144J1495D01*
G01X490217Y197848D01*
X490323D01*
G02X490355Y197845I-3J-200D01*
G01X490357D01*
G02X490463Y197791I-34J-197D01*
G01X490492Y197762D01*
G03X490516Y197742I140J143D01*
G01X490688Y197618D01*
G02X490741Y197550I-128J-154D01*
G01X490749Y197529D01*
G02X490759Y197467I-190J-62D01*
G01Y197454D01*
X490751Y197326D01*
Y197323D01*
X490742Y197169D01*
X490734Y197032D01*
G02X490714Y196965I-199J23D01*
G01X490697Y196931D01*
X490677Y196914D01*
X490665Y196904D01*
X490577Y196829D01*
G03X490532Y196775I129J-153D01*
G01Y196774D01*
X490524Y196760D01*
G02X490457Y196697I-167J110D01*
G01X490434Y196684D01*
X490382Y196670D01*
X490334Y196671D01*
X490324D01*
G03X490195Y196678I-146J-1496D01*
G01X490128D01*
G03X489998Y196670I27J-1502D01*
G03X489809Y196638I156J-1494D01*
G03X489563Y196557I345J-1462D01*
G03X489223Y196355I590J-1381D01*
G01X489211Y196346D01*
X489205Y196341D01*
X489159Y196318D01*
X489116Y196308D01*
X489009D01*
G03X488926Y196290I0J-200D01*
G01X488873Y196266D01*
G02X488665Y196291I-84J181D01*
G01X488637Y196313D01*
X488619Y196327D01*
X488616Y196329D01*
G03X487655Y196678I-962J-1152D01*
G01X487616D01*
G03X486772Y196392I38J-1502D01*
G01X486738Y196368D01*
X486718Y196351D01*
G02X486689Y196333I-120J161D01*
G01X486681Y196329D01*
G02X486592Y196308I-89J179D01*
G01X486509D01*
G03X486426Y196290I0J-200D01*
G01X486373Y196266D01*
G02X486165Y196291I-84J181D01*
G01X486137Y196313D01*
X486119Y196327D01*
X486116Y196329D01*
G03X485155Y196678I-962J-1152D01*
G01X485116D01*
G03X484272Y196392I38J-1502D01*
G01X484238Y196368D01*
X484218Y196351D01*
G02X484189Y196333I-120J161D01*
G01X484181Y196329D01*
G02X484092Y196308I-89J179D01*
G01X484009D01*
G03X483926Y196290I0J-200D01*
G01X483873Y196266D01*
G02X483665Y196291I-84J181D01*
G01X483637Y196313D01*
X483619Y196327D01*
X483616Y196329D01*
G03X482655Y196678I-962J-1152D01*
G01X482654D01*
G03Y193674I0J-1502D01*
G01X482655D01*
G03X483589Y194000I0J1502D01*
G01X483608Y194015D01*
X483637Y194028D01*
G02X483715Y194044I78J-184D01*
G01X483799D01*
G03X483882Y194062I0J200D01*
G01X483935Y194086D01*
G02X484143Y194061I84J-181D01*
G01X484171Y194039D01*
X484189Y194025D01*
X484192Y194023D01*
G03X485153Y193674I962J1152D01*
G01X485192D01*
G03X486088Y193999I-38J1502D01*
G01X486108Y194015D01*
X486139Y194029D01*
G02X486215Y194044I76J-185D01*
G01X486299D01*
G03X486382Y194062I0J200D01*
G01X486435Y194086D01*
G02X486643Y194061I84J-181D01*
G01X486671Y194039D01*
X486689Y194025D01*
X486692Y194023D01*
G03X487653Y193674I962J1152D01*
G01X487692D01*
G03X488588Y193999I-38J1502D01*
G01X488608Y194015D01*
X488635Y194027D01*
G02X488664Y194037I79J-183D01*
G01X488666D01*
G02X488716Y194044I52J-193D01*
G01X488799D01*
G03X488882Y194062I0J200D01*
G01X488927Y194083D01*
X488929D01*
X488965Y194101D01*
X489010Y194102D01*
G02X489094Y194084I1J-200D01*
G01X489114Y194075D01*
X489149Y194057D01*
X489167Y194041D01*
G03X489777Y193722I983J1137D01*
G03X490088Y193675I379J1454D01*
G01X490101D01*
G03X490130Y193674I66J1500D01*
G01X490131D01*
X490172Y193673D01*
X490208Y193658D01*
G02X490270Y193615I-81J-183D01*
G01X490345Y193535D01*
X490470Y193400D01*
G02X490523Y193253I-147J-136D01*
G01X490040Y184653D01*
X489466Y174432D01*
G02X489465Y174416I-200J4D01*
G01X487377Y158959D01*
G03X487342Y158493I3891J-527D01*
G01X487318Y156950D01*
X487310Y156399D01*
G02X487289Y156324I-199J15D01*
G01Y156323D01*
G03X486882Y154641I3519J-1742D01*
G01X486852Y152695D01*
Y152624D01*
G03X487055Y151382I3927J4D01*
G02X487058Y151263I-190J-64D01*
G02X487053Y151249I-191J60D01*
G03X486808Y149942I3681J-1366D01*
G01X486778Y147995D01*
Y147931D01*
G03X486885Y147018I3926J-3D01*
G01X486893Y146986D01*
X486864Y146694D01*
X486843Y146657D01*
G03X486425Y145562I3385J-1919D01*
G01X486416Y145520D01*
X486412Y145500D01*
X486409Y145483D01*
G02X486346Y145384I-193J53D01*
G01X486345Y145383D01*
X486336Y145375D01*
X486243Y145300D01*
G02X486200Y145276I-118J161D01*
G01X486170Y145265D01*
X486140Y145263D01*
X486136D01*
G03X485533Y145105I71J-1501D01*
G03X485370Y145010I673J-1342D01*
G03X485241Y144913I837J-1247D01*
G03X484714Y143938I965J-1151D01*
G01X484707Y143879D01*
G03X484703Y143762I1499J-110D01*
G03X485801Y142314I1504J0D01*
G01X485809Y142313D01*
X485819Y142310D01*
G03X485827Y142308I368J1454D01*
G01X485830Y142307D01*
X485833D01*
X485842Y142304D01*
X485855Y142301D01*
G02X485915Y142268I-65J-189D01*
G02X485955Y142224I-126J-155D01*
G01X485984Y142174D01*
G02X485986Y142170I-178J-91D01*
G01X486095Y141971D01*
X486101Y141960D01*
G02X486120Y141875I-181J-85D01*
G01Y141796D01*
X486115Y141779D01*
X486114Y141776D01*
Y141775D01*
X486110Y141763D01*
G03X486108Y141757I3691J-1234D01*
G03X486096Y141720I3695J-1219D01*
G01Y141717D01*
X486088Y141688D01*
G03X486085Y141679I3686J-1234D01*
G01X486082Y141672D01*
G03X486076Y141650I3748J-1034D01*
G01X486073Y141638D01*
G03X486071Y141632I3689J-1233D01*
G01Y141631D01*
G03X486066Y141614I3730J-1106D01*
G01X486063Y141603D01*
G03X486054Y141569I3757J-1013D01*
G01Y141568D01*
X486048Y141547D01*
Y141545D01*
X486042Y141522D01*
G03X486031Y141477I3775J-947D01*
G03X485947Y140982I3787J-897D01*
G01X485940Y140912D01*
X485925Y140758D01*
X485847Y139975D01*
G02X485812Y139890I-197J32D01*
G02X485792Y139866I-163J116D01*
G01X485787Y139861D01*
G02X485753Y139833I-144J140D01*
G01X485654Y139838D01*
X485644D01*
G03X485595Y139840I-185J-3923D01*
G03X485495Y139842I-129J-3925D01*
G01X485446D01*
G03X483371Y139230I30J-3927D01*
G01X483363Y139232D01*
X483347Y139235D01*
G03X483077Y139259I-267J-1478D01*
G01X483075D01*
G03X481573Y137757I0J-1502D01*
G01Y137746D01*
G03X481685Y137189I1502J12D01*
G01X481687Y137183D01*
X481694Y137166D01*
X481720Y137103D01*
X481725Y137081D01*
X481707Y137019D01*
G03X481548Y135923I3768J-1106D01*
G01Y135888D01*
G03X481652Y135017I3927J27D01*
G03X481890Y134312I3823J898D01*
G01X481897Y134296D01*
X481915Y134217D01*
G02Y134213I-200J-2D01*
G01X481897Y134134D01*
X481890Y134118D01*
G03X481548Y132515I3585J-1603D01*
G03X481556Y132261I3927J-3D01*
G03X481630Y131720I3918J260D01*
G03X481725Y131351I3846J793D01*
G01X481718Y131320D01*
X481709Y131298D01*
G03X481575Y130760I1366J-626D01*
G01Y130743D01*
G03X481573Y130670I1500J-78D01*
G01Y130640D01*
G03X483075Y129168I1502J30D01*
G01X483076D01*
G03X483303Y129185I2J1502D01*
G02X483437Y129159I31J-197D01*
G03X485475Y128588I2039J3356D01*
G01X485476D01*
G03X487513Y129158I-1J3927D01*
G02X487646Y129185I104J-171D01*
G03X487879Y129168I225J1485D01*
G01X487882D01*
G03X488342Y129242I-6J1501D01*
G01X488396Y129260D01*
X488441Y129256D01*
G02X488554Y129208I-18J-200D01*
G01X488631Y129152D01*
X488799Y129029D01*
G02X488841Y128984I-123J-157D01*
G01X488843Y128982D01*
G02X488851Y128970I-163J-117D01*
G01X488849Y128888D01*
Y128886D01*
G03X488848Y128829I3925J-97D01*
G01Y128822D01*
G03X488849Y128728I3927J-5D01*
G03X489190Y127225I3926J100D01*
G01X489197Y127209D01*
X489215Y127130D01*
G02Y127126I-200J-2D01*
G01X489197Y127047D01*
X489190Y127031D01*
G03X488849Y125528I3585J-1603D01*
G03X488848Y125434I3926J-89D01*
G01Y125427D01*
G03X488849Y125367I3926J35D01*
G01Y125356D01*
X488851Y125282D01*
G02X488803Y125227I-172J102D01*
G01X488625Y125097D01*
X488623D01*
X488547Y125042D01*
G02X488452Y125008I-113J165D01*
G01X488450D01*
G02X488434Y125007I-20J199D01*
G01X488357D01*
X488327Y125016D01*
G03X487881Y125086I-453J-1432D01*
G01X487853D01*
G03X487752Y125081I24J-1502D01*
G03X487606Y125062I121J-1497D01*
G01X487588Y125059D01*
X487580Y125057D01*
G03X485475Y125668I-2104J-3315D01*
G03X483458Y125111I-1J-3926D01*
G01X483435Y125097D01*
X483331Y125068D01*
X483310D01*
X483282Y125072D01*
G03X483266Y125074I-194J-1489D01*
G01X483260D01*
G03X483108Y125086I-194J-1489D01*
G01X483075D01*
G03X481573Y123584I0J-1502D01*
G01Y123573D01*
G03X481685Y123016I1502J12D01*
G01X481687Y123010D01*
X481694Y122993D01*
X481720Y122930D01*
X481725Y122908D01*
X481707Y122846D01*
G03X481548Y121773I3768J-1107D01*
G01Y121729D01*
G03X481889Y120142I3927J14D01*
G02X481901Y120104I-184J-79D01*
G01X481915Y120044D01*
G02Y120040I-200J-2D01*
G01X481901Y119980D01*
G02X481889Y119942I-196J41D01*
G03X481548Y118342I3586J-1601D01*
G01Y118340D01*
G03X481574Y117890I3927J1D01*
G03X481687Y117307I3901J454D01*
G03X481726Y117175I3785J1046D01*
G01X481719Y117146D01*
G03X481573Y116499I1357J-646D01*
G01Y116497D01*
G03X483075Y114995I1502J0D01*
G01X483078D01*
G03X483355Y115021I-1J1502D01*
G01X483371Y115024D01*
X483374Y115025D01*
G03X485475Y114416I2100J3317D01*
G03X487575Y115024I1J3926D01*
G01X487579Y115023D01*
X487593Y115021D01*
G03X487874Y114995I278J1476D01*
G01X487878D01*
G03X488273Y115048I0J1502D01*
G01X488280Y115050D01*
X488285Y115051D01*
X488300Y115055D01*
X488341Y115069D01*
X488349Y115071D01*
X488390Y115087D01*
X488452Y115082D01*
G02X488493Y115071I-31J-198D01*
G01X488516Y115062D01*
X488539Y115046D01*
X488581Y115016D01*
X488584Y115014D01*
X488732Y114905D01*
X488735Y114903D01*
X488799Y114857D01*
G02X488832Y114825I-122J-159D01*
G01X488846Y114808D01*
X488851Y114798D01*
X488849Y114715D01*
Y114714D01*
G03X488848Y114656I3925J-97D01*
G01Y114649D01*
G03X488849Y114555I3927J-5D01*
G03X489190Y113052I3926J100D01*
G01X489197Y113036D01*
X489215Y112957D01*
G02Y112953I-200J-2D01*
G01X489201Y112893D01*
G02X489189Y112855I-196J41D01*
G03X488848Y111255I3586J-1601D01*
G01Y111253D01*
G03X488874Y110803I3927J1D01*
G03X488987Y110221I3900J455D01*
G01Y110219D01*
G03X489015Y110126I3773J1085D01*
G01Y110124D01*
G03X489026Y110088I3761J1129D01*
G01X489019Y110059D01*
X489010Y110040D01*
G03X488875Y109500I1365J-628D01*
G01Y109483D01*
G03X488873Y109410I1500J-78D01*
G01Y109380D01*
G03X490375Y107908I1502J30D01*
G03X490637Y107931I0J1502D01*
G01X490675Y107937D01*
G03X490862Y107826I2097J3320D01*
G01X490930Y107788D01*
G02X490945Y107751I-177J-93D01*
G01X491023Y107462D01*
X491022Y107408D01*
X491015Y107382D01*
X490998Y107321D01*
X490986Y107300D01*
G03X490792Y106562I1308J-738D01*
G01Y106526D01*
X490793Y106510D01*
Y106507D01*
G03X490802Y106388I1501J54D01*
G03X490969Y105854I1492J173D01*
G03X491367Y105379I1325J706D01*
G01X491375Y105373D01*
X491403Y105346D01*
X491454Y105284D01*
X491464Y105263D01*
X491474Y105217D01*
X491458Y104911D01*
X491456Y104862D01*
X491384Y104738D01*
X491366Y104720D01*
X491322Y104675D01*
X491297Y104658D01*
G03X490633Y103411I839J-1247D01*
G03X493637I1502J0D01*
G03X493049Y104603I-1502J0D01*
G01X493038Y104611D01*
X493012Y104637D01*
X492994Y104660D01*
G02X492958Y104771I164J114D01*
G01X492973Y105105D01*
X492992Y105142D01*
X492996Y105151D01*
X493046Y105235D01*
X493063Y105252D01*
X493107Y105297D01*
X493132Y105314D01*
G03X493796Y106557I-838J1247D01*
G01Y106575D01*
G03X493717Y107043I-1502J-13D01*
G01X493704Y107082D01*
X493706Y107120D01*
G02X493727Y107197I200J-13D01*
G01X493779Y107300D01*
Y107302D01*
X493843Y107427D01*
G02X493876Y107469I172J-102D01*
G01X493905Y107494D01*
X493952Y107509D01*
G03X494848Y107920I-1176J3746D01*
G01X494882D01*
G03X495075Y107907I197J1490D01*
G03X495151Y107909I-2J1503D01*
G01X495189Y107912D01*
G03X496278Y108510I-114J1498D01*
G01X496286Y108520D01*
G03X498461Y109624I-602J3880D01*
G01X502048Y113211D01*
G03X502537Y113805I-2772J2781D01*
G01X502655Y113982D01*
G02X502678Y114010I165J-112D01*
G01X503675Y115007D01*
G02X503736Y115049I142J-141D01*
G01X503755Y115056D01*
X503763Y115058D01*
G03X503826Y115079I-443J1435D01*
G01X503827D01*
X503838Y115083D01*
G03X503923Y115117I-515J1411D01*
G01X503936Y115123D01*
X503975Y115140D01*
X504000Y115153D01*
X504002Y115154D01*
G03X504063Y115186I-667J1346D01*
G01X504086Y115199D01*
X504087D01*
G03X504104Y115209I-753J1300D01*
G01X504112Y115214D01*
G03X504828Y116441I-785J1281D01*
G01X504831Y116497D01*
X505926Y118138D01*
X506411Y118865D01*
X506423Y118883D01*
X506821Y119281D01*
X510819Y123280D01*
G03X511661Y124532I-2776J2776D01*
G01X512860Y127376D01*
X513163Y128096D01*
X513611Y129159D01*
G02X513656Y129224I184J-79D01*
G01X513684Y129252D01*
X513724Y129267D01*
G03X514677Y130494I-540J1403D01*
G01X514683Y130552D01*
G03X514688Y130670I-1498J123D01*
G01Y130672D01*
G03X514566Y131267I-1504J2D01*
G01Y131268D01*
G02X514565Y131424I183J79D01*
G01X521065Y146854D01*
G03X521312Y147684I-3617J1528D01*
G03X521374Y148377I-3865J695D01*
G01Y148379D01*
G03X521373Y148442I-3927J-31D01*
G01Y148443D01*
X521276Y154275D01*
G03X521193Y155015I-3926J-66D01*
G01X520488Y158385D01*
X520054Y160457D01*
G02X520057Y160533I198J30D01*
G01X520058Y160537D01*
G02X520115Y160635I194J-47D01*
G01X520363Y160867D01*
G02X520401Y160895I137J-146D01*
G02X520554Y160914I99J-174D01*
G01X520579Y160907D01*
G03X520963Y160858I382J1463D01*
G01X520965D01*
G03X521987Y161256I0J1511D01*
G01X521991Y161260D01*
X522000Y161267D01*
X522037Y161287D01*
X522093Y161317D01*
X522132Y161326D01*
X522405D01*
G02X522428Y161325I3J-200D01*
G03X523565Y160825I1137J1043D01*
G03Y163911I0J1543D01*
G03X522428Y163411I0J-1543D01*
G02X522405Y163410I-20J199D01*
G01X522155D01*
G02X522108Y163416I2J200D01*
G01X522084Y163422D01*
G02X522036Y163442I52J193D01*
G01X522017Y163453D01*
X522000Y163468D01*
X521997Y163471D01*
G03X520965Y163878I-1032J-1105D01*
G01X520964D01*
G03X520007Y163536I0J-1511D01*
G01X520005Y163534D01*
G02X519912Y163492I-126J155D01*
G01X519864Y163484D01*
X519491Y163615D01*
G02X519362Y163762I67J189D01*
G01X519034Y165329D01*
X518857Y166173D01*
X517895Y170765D01*
G02X517893Y170775I195J44D01*
G01X513904Y196999D01*
Y197001D01*
X513889Y197095D01*
X513888Y197102D01*
X513885Y197122D01*
X513472Y199837D01*
X513284Y201072D01*
X513157Y201904D01*
Y201907D01*
X513156Y201914D01*
X512665Y205146D01*
G02X512663Y205172I198J28D01*
G01X512644Y206356D01*
X512641Y206564D01*
G02X512662Y206657I200J4D01*
G01X512709Y206751D01*
X512737Y206786D01*
X512754Y206799D01*
G03X513323Y207978I-937J1179D01*
G03X513319Y208094I-1503J6D01*
G01X513312Y208154D01*
Y208155D01*
G03X513266Y208385I-1491J-179D01*
G03X512999Y208909I-1446J-407D01*
G01X512988Y208923D01*
X512962Y208972D01*
X512952Y209016D01*
Y209123D01*
G03X512934Y209206I-200J0D01*
G01X512910Y209259D01*
G02X512935Y209467I181J84D01*
G01X512957Y209495D01*
X512971Y209513D01*
X512973Y209516D01*
X512975Y209518D01*
X512978Y209522D01*
G03X513322Y210462I-1158J957D01*
G01Y210474D01*
G03X513206Y211058I-1502J5D01*
G01Y211059D01*
X513205Y211061D01*
G03X513200Y211072I-1369J-616D01*
G01X513198Y211076D01*
X513190Y211095D01*
G03X513127Y211218I-1367J-623D01*
G03X513036Y211360I-1308J-738D01*
G01X513012Y211393D01*
X512994Y211416D01*
G02X512977Y211443I160J120D01*
G01X512973Y211451D01*
G02X512952Y211540I179J89D01*
G01Y211623D01*
G03X512934Y211706I-200J0D01*
G01X512910Y211759D01*
G02X512935Y211967I181J84D01*
G01X512957Y211995D01*
X512971Y212013D01*
X512973Y212016D01*
X512975Y212018D01*
X512978Y212022D01*
G03X513322Y212962I-1158J957D01*
G01Y212974D01*
G03X513206Y213558I-1502J5D01*
G01Y213559D01*
X513205Y213561D01*
G03X513200Y213572I-1369J-616D01*
G01X513198Y213576D01*
X513190Y213595D01*
G03X513127Y213718I-1367J-623D01*
G03X513036Y213860I-1308J-738D01*
G01X513012Y213893D01*
X512994Y213916D01*
G02X512977Y213943I160J120D01*
G01X512973Y213951D01*
G02X512952Y214040I179J89D01*
G01Y214123D01*
G03X512934Y214206I-200J0D01*
G01X512910Y214259D01*
G02X512935Y214467I181J84D01*
G01X512957Y214495D01*
X512971Y214513D01*
X512973Y214516D01*
X512979Y214523D01*
G03X513320Y215401I-1159J955D01*
G03X513322Y215474I-1500J78D01*
G01Y215478D01*
G03X512578Y216775I-1503J0D01*
G01X512577Y216776D01*
G02X512478Y216935I101J173D01*
G01X512397Y222153D01*
G02X512426Y222261I200J4D01*
G01X512477Y222343D01*
G02X512549Y222412I170J-105D01*
G01X512550Y222413D01*
G03X513312Y223550I-730J1313D01*
G01X513316Y223587D01*
G03X513322Y223726I-1496J134D01*
G03X512998Y224658I-1502J0D01*
G01X512983Y224677D01*
X512973Y224699D01*
X512962Y224720D01*
X512952Y224764D01*
Y224874D01*
G03X512936Y224952I-200J0D01*
G01X512909Y225014D01*
X512908Y225017D01*
X512898Y225039D01*
X512894Y225069D01*
Y225117D01*
X512899Y225156D01*
X512923Y225204D01*
X512941Y225226D01*
X512944Y225229D01*
G03X512950Y225236I-1137J981D01*
G01X512955Y225242D01*
X512961Y225248D01*
X512970Y225259D01*
X512995Y225290D01*
G03X513012Y225312I-1180J929D01*
G03X513027Y225332I-1194J911D01*
G03X513322Y226226I-1207J894D01*
G01Y226227D01*
G03X513007Y227147I-1502J0D01*
G01X513005Y227149D01*
X512978Y227190D01*
G02X512952Y227287I174J99D01*
G01Y227374D01*
G03X512936Y227452I-200J0D01*
G01X512909Y227514D01*
X512908Y227517D01*
X512898Y227539D01*
X512894Y227569D01*
Y227617D01*
X512899Y227656D01*
X512923Y227704D01*
X512941Y227726D01*
X512944Y227729D01*
G03X512950Y227736I-1137J981D01*
G01X512955Y227742D01*
X512961Y227748D01*
X512970Y227759D01*
X512995Y227790D01*
G03X513012Y227812I-1180J929D01*
G03X513027Y227832I-1194J911D01*
G03X513322Y228726I-1207J894D01*
G01Y228727D01*
G03X513007Y229647I-1502J0D01*
G01X513005Y229649D01*
X512978Y229690D01*
G02X512952Y229787I174J99D01*
G01Y229871D01*
G03X512934Y229954I-200J0D01*
G01X512910Y230007D01*
G02X512935Y230215I181J84D01*
G01X512957Y230243D01*
X512971Y230261D01*
X512973Y230264D01*
G03X513203Y230640I-1152J963D01*
G03X513292Y230926I-1382J587D01*
G03X513311Y231043I-1472J299D01*
G03X513322Y231201I-1491J183D01*
G01Y231261D01*
G03X513321Y231277I-1499J-86D01*
G01Y231292D01*
X513318Y231350D01*
Y231354D01*
G03X513316Y231379I-200J-3D01*
G01X513305Y231454D01*
G03X513265Y231635I-1484J-233D01*
G01Y231639D01*
G03X513259Y231659I-1442J-422D01*
G01X513244Y231709D01*
X513232Y231738D01*
G03X513014Y232139I-1413J-509D01*
G01X512998Y232161D01*
X513192Y234124D01*
X513384Y236071D01*
G03X513397Y236246I-3908J378D01*
G03X513402Y236456I-3921J198D01*
G01Y243540D01*
Y243542D01*
X513378Y246525D01*
X513354Y249509D01*
Y257742D01*
Y257744D01*
X513351Y257968D01*
X513350Y258087D01*
G02X513441Y258254I200J-1D01*
G01X513469Y258269D01*
G02X513650Y258259I81J-182D01*
G01X513683Y258239D01*
X513748Y258169D01*
X513760Y258148D01*
X513761Y258146D01*
G03X515074Y257378I1313J738D01*
G03Y260382I0J1502D01*
G03X514034Y259964I0J-1503D01*
G01X514005Y259936D01*
X513943Y259912D01*
G02X513920Y259905I-70J188D01*
G01X513868Y259892D01*
G02X513779Y259899I-29J198D01*
G01X513575Y259979D01*
X513573D01*
X513451Y260027D01*
G02X513323Y260213I72J186D01*
G01Y260214D01*
X513301Y261980D01*
X513296Y262389D01*
X513290Y262859D01*
Y262951D01*
X513292Y262969D01*
X513293Y262977D01*
X513295Y262994D01*
G02X513397Y263135I197J-35D01*
G01X513429Y263151D01*
X513460Y263162D01*
X513757Y263270D01*
G02X513821Y263281I65J-189D01*
G01X513849D01*
G02X513938Y263260I0J-200D01*
G01X513957Y263251D01*
X513984Y263229D01*
X513997Y263215D01*
X513999Y263211D01*
G03X514003Y263207I1058J1054D01*
G01X514006Y263204D01*
G03X514143Y263064I1141J979D01*
G03X515149Y262677I1006J1114D01*
G03X516083Y263003I-1J1503D01*
G02X516087Y263005I90J-174D01*
G03X516098Y263014I-946J1167D01*
G01X516100Y263016D01*
G02X516167Y263044I109J-168D01*
G02X516205Y263048I40J-196D01*
G01X516294D01*
G03X516377Y263066I0J200D01*
G01X516430Y263090D01*
G02X516638Y263065I84J-181D01*
G01X516666Y263043D01*
X516684Y263029D01*
X516687Y263027D01*
G03X517648Y262678I962J1152D01*
G01X517649D01*
G03X519151Y264180I0J1502D01*
G03X517664Y265682I-1502J0D01*
G01X517647D01*
G03X516766Y265396I1J-1502D01*
G01X516733Y265371D01*
X516714Y265356D01*
G02X516680Y265335I-122J159D01*
G01X516676Y265333D01*
G02X516587Y265312I-89J179D01*
G01X516504D01*
G03X516421Y265294I0J-200D01*
G01X516368Y265270D01*
G02X516160Y265295I-84J181D01*
G01X516142Y265309D01*
X516138Y265313D01*
G03X515149Y265683I-989J-1136D01*
G01X515147D01*
G03X514581Y265572I1J-1503D01*
G03X514445Y265508I571J-1390D01*
G03X514250Y265384I706J-1326D01*
G03X514060Y265215I900J-1203D01*
G01X514058Y265213D01*
G03X513995Y265144I1078J-1047D01*
G01X513981Y265127D01*
X513965Y265114D01*
G02X513934Y265094I-123J157D01*
G01X513897Y265076D01*
G02X513813Y265057I-85J181D01*
G01X513758D01*
G02X513698Y265067I2J200D01*
G01X513592Y265102D01*
X513590D01*
X513388Y265172D01*
G02X513261Y265323I70J187D01*
G01X513259Y265335D01*
X513178Y271763D01*
X513165Y272845D01*
X512948Y299623D01*
X512843Y312612D01*
G02X512895Y312749I200J2D01*
G01X512898Y312752D01*
G03X512925Y312781I-1105J1055D01*
G01X512926D01*
X512963Y312822D01*
X513001Y312839D01*
X513028Y312846D01*
G02X513198Y312805I43J-195D01*
G01X513232Y312774D01*
X513233Y312773D01*
X513257Y312751D01*
X513287Y312699D01*
X513294Y312664D01*
G03X514769Y311451I1475J290D01*
G03X516271Y312953I0J1502D01*
G03X514945Y314445I-1502J0D01*
G01X514888Y314451D01*
G03X514769Y314456I-123J-1498D01*
G01X514767D01*
G03X513830Y314128I0J-1503D01*
G01X513820Y314120D01*
G02X513649Y314092I-115J164D01*
G01X513421Y314158D01*
X513419D01*
X513328Y314186D01*
G02X513267Y314221I67J188D01*
G01X513261Y314226D01*
X513245Y314271D01*
X513235Y314300D01*
Y314301D01*
G03X513151Y314499I-1445J-496D01*
G03X512881Y314875I-1362J-693D01*
G01X512870Y314886D01*
G02X512823Y315002I153J129D01*
G01X512718Y328027D01*
X512669Y334064D01*
Y334066D01*
G02X512671Y334092I200J-2D01*
G01X512722Y334449D01*
X512858Y335398D01*
X512859Y335406D01*
G02X512861Y335414I195J-44D01*
G01X531189Y395885D01*
G02X531285Y395999I190J-63D01*
G01X531444Y396085D01*
X531472Y396100D01*
X531532Y396112D01*
X531585Y396106D01*
X531603Y396101D01*
G03X531964Y396050I389J1451D01*
G01X531992D01*
G03X533484Y397376I0J1502D01*
G01X533490Y397430D01*
G03X532503Y398966I-1498J123D01*
G01X532468Y398979D01*
X532353Y399078D01*
X532335Y399114D01*
X532298Y399187D01*
X532264Y399254D01*
G02X532252Y399389I182J84D01*
G02X532254Y399396I193J-51D01*
G01X540584Y426878D01*
X552798Y466883D01*
G03X552935Y467521I-3723J1133D01*
G01X552957Y467690D01*
G02X552964Y467722I198J-27D01*
G01X553273Y468741D01*
G03X553408Y469368I-3758J1137D01*
G01X566343Y567700D01*
X566344Y567706D01*
X606266Y778823D01*
G02X606444Y778950I186J-73D01*
G01X623496D01*
G02X623894Y778518I-1J-400D01*
G01X623604Y774928D01*
X623393Y772313D01*
X622714Y763904D01*
X621993Y754982D01*
X616525Y687284D01*
Y687279D01*
X616523Y687263D01*
X616522Y687254D01*
X616521Y687242D01*
Y687239D01*
X616520Y687230D01*
G03X616518Y687205I3878J-323D01*
G01X616260Y684013D01*
X615598Y675813D01*
X615041Y668919D01*
X614840Y666426D01*
X613960Y655526D01*
X613071Y644510D01*
G03X613066Y644436I3880J-299D01*
G01X611620Y620901D01*
X610743Y606632D01*
Y606629D01*
X610404Y602321D01*
X607602Y566699D01*
Y566693D01*
X606468Y555919D01*
X606467Y555913D01*
G03X606437Y555434I3862J-482D01*
G01X606414Y545370D01*
X606413Y545361D01*
G03X606448Y544845I3893J5D01*
G01X606449Y544840D01*
X606924Y541353D01*
X607072Y540271D01*
G02X607000Y540090I-198J-26D01*
G01X606913Y540023D01*
X606911D01*
X606737Y539892D01*
G02X606617Y539852I-120J160D01*
G01X606558D01*
X606484Y539867D01*
X606467Y539874D01*
G03X605948Y540001I-683J-1669D01*
G03X605793Y540008I-159J-1795D01*
G03X605779I-7J-1802D01*
G01X605737Y540009D01*
G03X603976Y538207I42J-1803D01*
G01Y534806D01*
G03X604877Y533245I1803J0D01*
G03X604922Y533220I898J1563D01*
G03X605016Y533173I853J1588D01*
G03X605242Y533085I766J1632D01*
G03X605454Y533033I535J1721D01*
G03X605775Y533004I322J1773D01*
G03X605778I2J1802D01*
G01X605780D01*
G03X605879Y533006I13J1802D01*
G03X605941Y533010I-85J1801D01*
G01X605948Y533011D01*
X605951D01*
G03X605970Y533013I-179J1794D01*
G01X605979Y533014D01*
G03X606002Y533017I-222J1788D01*
G01X606007Y533018D01*
X606017Y533019D01*
G03X606039Y533022I-232J1787D01*
G01X606063Y533025D01*
X606098Y533031D01*
X606113Y533033D01*
X606114D01*
X606119Y533034D01*
X606120D01*
G03X606141Y533038I-27J198D01*
G01X606210Y533055D01*
G03X606650Y533227I-431J1751D01*
G01X606672Y533239D01*
X606732Y533255D01*
X606733D01*
X606778Y533268D01*
X606845Y533253D01*
X606846D01*
X606935Y533235D01*
G02X606985Y533215I-49J-194D01*
G01X607007Y533199D01*
X607030Y533182D01*
X607050Y533156D01*
G03X607052Y533153I1251J832D01*
G03X607202Y532975I1221J877D01*
G01X607205Y532972D01*
X607206Y532970D01*
G03X607214Y532963I136J147D01*
G02X607216Y532961I-140J-142D01*
G01X607218Y532960D01*
G02X607227Y532951I-137J-146D01*
G03X607229Y532949I142J140D01*
G01X607230Y532948D01*
G03X607239Y532939I1067J1058D01*
G02X607241Y532937I-140J-142D01*
G03X607244Y532934I143J140D01*
G03X607257Y532922I1025J1098D01*
G01X607282Y532899D01*
X607288Y532889D01*
X607356Y532838D01*
X607361Y532834D01*
G03X607437Y532780I908J1197D01*
G03X607596Y532687I837J1248D01*
G01X607617Y532677D01*
X607619Y532676D01*
G03X607986Y532553I657J1351D01*
G01X607987D01*
X607996Y532551D01*
G02X608143Y532404I-47J-194D01*
G02X608147Y532384I-194J-49D01*
G01X609448Y522836D01*
Y522830D01*
X609716Y520354D01*
X609826Y519336D01*
G02X609827Y519320I-199J-20D01*
G01X610200Y484727D01*
X610349Y470890D01*
Y470882D01*
X610133Y463736D01*
X608830Y420713D01*
X608737Y417892D01*
X608688Y416395D01*
X608603Y413836D01*
Y413826D01*
X608379Y411036D01*
G02X608319Y410909I-199J16D01*
G01X608292Y410882D01*
X608227Y410854D01*
X608191Y410852D01*
G03X607662Y410724I83J-1500D01*
G03X607052Y410226I612J-1373D01*
G01X607044Y410214D01*
G02X606933Y410147I-153J129D01*
G01X606814Y410120D01*
G02X606769Y410115I-44J195D01*
G01X606672Y410141D01*
X606650Y410153D01*
G03X605780Y410377I-871J-1580D01*
G01X605779D01*
G03X603976Y408574I0J-1803D01*
G01Y405174D01*
G03X605779Y403371I1803J0D01*
G01X605780D01*
G03X606637Y403588I-1J1804D01*
G01X606648Y403594D01*
X606697Y403613D01*
X606736Y403623D01*
X606836D01*
X606881Y403613D01*
X606934Y403600D01*
G02X606998Y403572I-47J-194D01*
G01X607030Y403551D01*
X607052Y403521D01*
X607053Y403520D01*
G03X607263Y403284I1221J875D01*
G03X607577Y403064I1012J1111D01*
G01X607611Y403045D01*
X607722Y402868D01*
G02X607721Y402861I-197J25D01*
G01X607316Y397803D01*
X607195Y396286D01*
G02X607178Y396221I-199J17D01*
G01X607167Y396195D01*
X607145Y396170D01*
G03X607136Y396160I1112J-1010D01*
G02X607132Y396154I-168J108D01*
G03X607127Y396149I1058J-1063D01*
G03X607123Y396144I154J-127D01*
G03X607052Y396053I1148J-969D01*
G01X607029Y396022D01*
X607001Y396003D01*
G02X606944Y395977I-110J167D01*
G01X606804Y395945D01*
X606756Y395946D01*
X606732Y395952D01*
X606672Y395968D01*
X606650Y395980D01*
G03X605780Y396204I-871J-1580D01*
G01X605779D01*
G03X603976Y394401I0J-1803D01*
G01Y391001D01*
G03X605779Y389198I1803J0D01*
G03X605993Y389211I-2J1803D01*
G03X606064Y389221I-216J1789D01*
G03X606275Y389268I-286J1780D01*
G01X606289Y389272D01*
X606315Y389276D01*
G02X606433Y389256I27J-198D01*
G01X606448Y389247D01*
X606466Y389232D01*
G03X606497Y389211I123J148D01*
G01X606593Y389133D01*
X606618Y389112D01*
X606275Y384830D01*
X606218Y384121D01*
G02X606122Y383976I-199J27D01*
G02X606116Y383973I-92J177D01*
G01X606063Y383944D01*
X606031Y383936D01*
G02X605988Y383931I-44J195D01*
G01X605893D01*
G02X605832Y383941I1J200D01*
G01X605830D01*
G02X605819Y383945I63J190D01*
G01X605806Y383951D01*
X605799Y383954D01*
X605795Y383956D01*
G03X605149Y384102I-646J-1356D01*
G01X605147D01*
G03Y381098I0J-1502D01*
G01X605148D01*
G03X605617Y381173I0J1502D01*
G01X605631Y381178D01*
X605657Y381183D01*
G02X605811Y381151I40J-196D01*
G01X605896Y381083D01*
G02X605961Y380930I-135J-148D01*
G01X605905Y380223D01*
G02X605816Y380081I-198J25D01*
G01X605784Y380060D01*
X605783Y380059D01*
G03X605147Y380192I-637J-1459D01*
G03Y377008I0J-1592D01*
G01X605148D01*
G03X605547Y377059I-1J1592D01*
G03X605549Y377057I142J140D01*
G01X605551Y377055D01*
X605601Y377009D01*
X605607Y377003D01*
X605623Y376962D01*
G02X605636Y376873I-186J-73D01*
G01X604402Y361505D01*
X596034Y257272D01*
G03X596032Y257245I3915J-304D01*
G03X596025Y257115I3917J-276D01*
G01X595352Y240321D01*
G02X595232Y240157I-199J20D01*
G01X595211Y240151D01*
G03X594148Y238714I440J-1437D01*
G03X595098Y237317I1502J0D01*
G01X595100Y237316D01*
G02X595194Y237240I-73J-186D01*
G01X595209Y237216D01*
X595226Y237157D01*
X595056Y232912D01*
X595003Y231594D01*
G02X594975Y231499I-200J7D01*
G01X594963Y231479D01*
X594925Y231443D01*
X594901Y231430D01*
G03X594131Y230117I734J-1313D01*
G03X594160Y229824I1503J1D01*
G03X594370Y229303I1474J291D01*
G01X594371Y229302D01*
X594386Y229278D01*
X594398Y229239D01*
G02X594402Y229215I-195J-45D01*
G01X594404Y229151D01*
X594401Y229111D01*
G03X594416Y229019I200J-15D01*
G03X594422Y229006I185J77D01*
G01X594429Y228993D01*
X594444Y228973D01*
G03X594537Y228905I159J120D01*
G01X594757Y228829D01*
G02X594863Y228733I-72J-187D01*
G01X594866Y228727D01*
G02X594884Y228635I-182J-83D01*
G01X594880Y228540D01*
X594641Y222554D01*
X594483Y218595D01*
G03X594480Y218438I3923J-153D01*
G01Y218377D01*
Y218373D01*
X594501Y217028D01*
X594649Y207593D01*
Y207583D01*
X594262Y196491D01*
G02X594125Y196321I-199J20D01*
G01X593920Y196239D01*
X593918D01*
X593831Y196204D01*
G02X593813Y196200I-52J193D01*
G01X593784Y196195D01*
G02X593623Y196252I-20J199D01*
G01X593616Y196259D01*
G03X592516Y196720I-1100J-1082D01*
G03X591520Y196356I0J-1545D01*
G01X591519Y196355D01*
X591508Y196346D01*
G02X591391Y196308I-117J162D01*
G01X591371D01*
G03X591288Y196290I0J-200D01*
G01X591235Y196266D01*
G02X591027Y196291I-84J181D01*
G01X590999Y196313D01*
X590981Y196327D01*
X590978Y196329D01*
G03X590017Y196678I-962J-1152D01*
G01X589978D01*
G03X589134Y196392I38J-1502D01*
G01X589100Y196368D01*
X589080Y196351D01*
G02X589051Y196333I-120J161D01*
G01X589043Y196329D01*
G02X588954Y196308I-89J179D01*
G01X588871D01*
G03X588788Y196290I0J-200D01*
G01X588735Y196266D01*
G02X588527Y196291I-84J181D01*
G01X588499Y196313D01*
X588481Y196327D01*
X588478Y196329D01*
G03X587517Y196678I-962J-1152D01*
G01X587478D01*
G03X586634Y196392I38J-1502D01*
G01X586600Y196368D01*
X586580Y196351D01*
G02X586551Y196333I-120J161D01*
G01X586543Y196329D01*
G02X586454Y196308I-89J179D01*
G01X586371D01*
G03X586288Y196290I0J-200D01*
G01X586235Y196266D01*
G02X586027Y196291I-84J181D01*
G01X585999Y196313D01*
X585981Y196327D01*
X585978Y196329D01*
G03X585017Y196678I-962J-1152D01*
G01X585016D01*
G03Y193674I0J-1502D01*
G01X585017D01*
G03X585951Y194000I0J1502D01*
G01X585970Y194015D01*
X585999Y194028D01*
G02X586077Y194044I78J-184D01*
G01X586161D01*
G03X586244Y194062I0J200D01*
G01X586297Y194086D01*
G02X586505Y194061I84J-181D01*
G01X586533Y194039D01*
X586551Y194025D01*
X586554Y194023D01*
G03X587515Y193674I962J1152D01*
G01X587554D01*
G03X588450Y193999I-38J1502D01*
G01X588470Y194015D01*
X588501Y194029D01*
G02X588577Y194044I76J-185D01*
G01X588661D01*
G03X588744Y194062I0J200D01*
G01X588797Y194086D01*
G02X589005Y194061I84J-181D01*
G01X589033Y194039D01*
X589051Y194025D01*
X589054Y194023D01*
G03X590015Y193674I962J1152D01*
G01X590054D01*
G03X590950Y193999I-38J1502D01*
G01X590970Y194015D01*
X591001Y194029D01*
G02X591077Y194044I76J-185D01*
G01X591457D01*
G02X591572Y194007I-1J-200D01*
G01X591585Y193997D01*
X591597Y193988D01*
X591616Y193969D01*
G02X591648Y193926I-143J-140D01*
G01X591670Y193884D01*
G03X592516Y193632I846J1294D01*
G01X592518D01*
G03X593520Y194004I-2J1541D01*
G01X593542Y194022D01*
X593605Y194051D01*
G02X593778Y194048I83J-182D01*
G01X593804Y194035D01*
X593806D01*
X594077Y193905D01*
G02X594168Y193800I-97J-176D01*
G01X594163Y193646D01*
X594162Y193633D01*
G02X594160Y193617I-199J17D01*
G01X594147Y193558D01*
G03X594142Y193525I195J-46D01*
G01Y193051D01*
Y193043D01*
X593996Y188889D01*
G02X593995Y188874I-199J6D01*
G01X589711Y157164D01*
G03X589676Y156699I3891J-527D01*
G01X589634Y153984D01*
X589624Y153941D01*
X589614Y153921D01*
X589613Y153920D01*
Y153919D01*
G03X589404Y153410I3519J-1742D01*
G03X589206Y152236I3728J-1232D01*
G01X589176Y150290D01*
Y150226D01*
G03X589205Y149745I3926J-5D01*
G01X589206Y149740D01*
X589207Y149722D01*
G03X589206Y149667I3891J-98D01*
G01Y149658D01*
G03X589207Y149578I3892J9D01*
G01X589232Y148356D01*
X589227Y148332D01*
G03X589133Y147537I3832J-856D01*
G01X589103Y145583D01*
X589092Y145550D01*
X589076Y145507D01*
X589066Y145480D01*
G03X589055Y145451I3633J-1395D01*
G01Y145449D01*
X589042Y145416D01*
G03X589027Y145375I3647J-1358D01*
G01X589017Y145352D01*
G02X588939Y145270I-178J91D01*
G03X588570Y145315I-371J-1508D01*
G01X588568D01*
G03Y142209I0J-1553D01*
G03X588709Y142216I-6J1553D01*
G02X588720Y142207I-121J-159D01*
G01X588778Y142157D01*
X588808Y142131D01*
X588850Y142048D01*
X588858Y142032D01*
X588879Y141964D01*
X588881Y141945D01*
G03X589306Y140563I3868J433D01*
G01X589315Y140546D01*
X589336Y140481D01*
X589337Y140425D01*
X589330Y140398D01*
X589324Y140373D01*
X589314Y140334D01*
X589284Y140225D01*
Y140223D01*
X589213Y139966D01*
G02X589144Y139874I-187J69D01*
G01X588947Y139756D01*
X588945D01*
X588899Y139729D01*
G02X588869Y139714I-104J171D01*
G01X588867D01*
G02X588854Y139709I-78J184D01*
G01X588783Y139726D01*
X588759Y139732D01*
G03X588426Y139797I-918J-3818D01*
G01X588424D01*
G03X588290Y139816I-618J-3878D01*
G01X588288D01*
G03X587858Y139842I-452J-3901D01*
G01X587808D01*
G03X585733Y139230I30J-3927D01*
G01X585725Y139232D01*
X585709Y139235D01*
G03X585439Y139259I-267J-1478D01*
G01X585437D01*
G03X583935Y137757I0J-1502D01*
G01Y137746D01*
G03X584047Y137189I1502J12D01*
G01X584049Y137183D01*
X584056Y137166D01*
X584082Y137103D01*
X584087Y137081D01*
X584069Y137019D01*
G03X583910Y135946I3768J-1107D01*
G01Y135902D01*
G03X584251Y134315I3927J14D01*
G02X584263Y134277I-184J-79D01*
G01X584277Y134217D01*
G02Y134213I-200J-2D01*
G01X584263Y134153D01*
G02X584251Y134115I-196J41D01*
G03X583910Y132515I3586J-1601D01*
G01Y132513D01*
G03X583943Y132006I3927J1D01*
G03X584016Y131609I3894J511D01*
G03X584087Y131351I3819J912D01*
G01X584080Y131320D01*
X584071Y131298D01*
G03X583937Y130760I1366J-626D01*
G01Y130743D01*
G03X583935Y130670I1500J-78D01*
G01Y130640D01*
G03X585437Y129168I1502J30D01*
G01X585438D01*
G03X585665Y129185I2J1502D01*
G02X585799Y129159I31J-197D01*
G03X587837Y128588I2039J3356D01*
G01X587838D01*
G03X589875Y129158I-1J3927D01*
G02X590008Y129185I104J-171D01*
G03X590241Y129168I225J1485D01*
G01X590244D01*
G03X590704Y129242I-6J1501D01*
G01X590758Y129260D01*
X590803Y129256D01*
G02X590916Y129208I-18J-200D01*
G01X590993Y129152D01*
X591161Y129029D01*
G02X591203Y128984I-123J-157D01*
G01X591205Y128982D01*
G02X591213Y128970I-163J-117D01*
G01X591211Y128888D01*
Y128886D01*
G03X591210Y128829I3925J-97D01*
G01Y128822D01*
G03X591211Y128728I3927J-5D01*
G03X591552Y127225I3926J100D01*
G01X591559Y127209D01*
X591577Y127130D01*
G02Y127126I-200J-2D01*
G01X591563Y127066D01*
G02X591551Y127028I-196J41D01*
G03X591210Y125428I3586J-1601D01*
G01Y125426D01*
G03X591220Y125147I3927J1D01*
G01X591221Y125140D01*
Y125138D01*
X591226Y125065D01*
G02X591209Y125040I-173J100D01*
G01X591190Y125014D01*
X591160Y124978D01*
G02X591006Y124909I-151J131D01*
G02X590965Y124914I4J200D01*
G01X590939Y124920D01*
X590917Y124925D01*
G03X590908Y124930I-734J-1310D01*
G01X590897Y124935D01*
G03X590241Y125086I-656J-1352D01*
G01X590202D01*
G03X589944Y125059I27J-1503D01*
G01X589943D01*
X589940Y125058D01*
G03X587837Y125668I-2102J-3316D01*
G03X585733Y125057I-1J-3926D01*
G01X585729Y125058D01*
X585702Y125063D01*
G03X585474Y125086I-264J-1479D01*
G01X585431D01*
G03X583935Y123588I6J-1502D01*
G01Y123586D01*
G03Y123584I1502J-1D01*
G01Y123573D01*
G03X584047Y123016I1502J12D01*
G01X584049Y123010D01*
X584056Y122993D01*
X584082Y122930D01*
X584087Y122908D01*
X584069Y122846D01*
G03X583910Y121750I3768J-1106D01*
G01Y121715D01*
G03X584014Y120844I3927J27D01*
G03X584252Y120139I3823J898D01*
G01X584259Y120123D01*
X584277Y120044D01*
G02Y120040I-200J-2D01*
G01X584259Y119961D01*
X584252Y119945D01*
G03X583910Y118342I3585J-1603D01*
G03X583969Y117663I3927J-1D01*
G03X584049Y117307I3867J682D01*
G03X584088Y117175I3785J1046D01*
G01X584081Y117146D01*
G03X583935Y116499I1357J-646D01*
G01Y116497D01*
G03X585437Y114995I1502J0D01*
G01X585440D01*
G03X585717Y115021I-1J1502D01*
G01X585733Y115024D01*
X585736Y115025D01*
G03X587837Y114416I2100J3317D01*
G03X589937Y115024I1J3926D01*
G01X589941Y115023D01*
X589955Y115021D01*
G03X590236Y114995I278J1476D01*
G01X590240D01*
G03X590635Y115048I0J1502D01*
G01X590642Y115050D01*
X590647Y115051D01*
X590662Y115055D01*
X590717Y115073D01*
X590719D01*
X590740Y115081D01*
X590790Y115086D01*
X590813Y115083D01*
G02X590855Y115072I-29J-198D01*
G02X590903Y115046I-70J-187D01*
G01X591151Y114865D01*
G02X591154Y114863I-110J-168D01*
G01X591173Y114849D01*
G02X591199Y114824I-125J-156D01*
G02X591213Y114805I-154J-128D01*
G01X591211Y114716D01*
Y114715D01*
G03X591210Y114656I3925J-96D01*
G01Y114649D01*
G03X591211Y114555I3927J-5D01*
G03X591552Y113052I3926J100D01*
G01X591559Y113036D01*
X591577Y112957D01*
G02Y112953I-200J-2D01*
G01X591559Y112874D01*
X591552Y112858D01*
G03X591210Y111255I3585J-1603D01*
G03X591269Y110576I3927J-1D01*
G03X591349Y110221I3867J685D01*
G01Y110219D01*
G03X591377Y110126I3773J1085D01*
G01Y110124D01*
G03X591388Y110088I3761J1129D01*
G01X591381Y110059D01*
X591372Y110040D01*
G03X591237Y109500I1365J-628D01*
G01Y109483D01*
G03X591235Y109410I1500J-78D01*
G01Y109380D01*
G03X592737Y107908I1502J30D01*
G03X593013Y107932I8J1503D01*
G01X593021Y107934D01*
G03X593038Y107937I-253J1481D01*
G03X593207Y107835I2113J3310D01*
G03X593211Y107833I91J178D01*
G03X593224Y107826I1868J3454D01*
G01X593293Y107787D01*
G02X593298Y107776I-179J-88D01*
G03X593300Y107770I190J60D01*
G02X593302Y107766I-177J-91D01*
G01X593385Y107462D01*
X593384Y107408D01*
X593377Y107382D01*
X593360Y107321D01*
X593348Y107300D01*
G03X593154Y106562I1308J-738D01*
G01Y106526D01*
X593155Y106510D01*
Y106507D01*
G03X593164Y106388I1501J54D01*
G03X593331Y105854I1492J173D01*
G03X593729Y105379I1325J706D01*
G01X593737Y105373D01*
X593765Y105346D01*
X593816Y105284D01*
X593826Y105263D01*
X593836Y105217D01*
X593820Y104911D01*
X593818Y104862D01*
X593759Y104761D01*
G02X593728Y104720I-174J99D01*
G01X593699Y104691D01*
X593667Y104664D01*
X593658Y104658D01*
G03X592994Y103411I839J-1247D01*
G03X596000I1503J0D01*
G03X595405Y104609I-1504J0D01*
G01X595392Y104619D01*
X595377Y104634D01*
X595353Y104665D01*
G02X595320Y104771I167J110D01*
G01X595335Y105105D01*
X595354Y105142D01*
X595358Y105151D01*
X595408Y105235D01*
X595425Y105252D01*
X595469Y105297D01*
X595494Y105314D01*
G03X596158Y106557I-838J1247D01*
G01Y106575D01*
G03X596079Y107043I-1502J-13D01*
G01X596076Y107052D01*
X596066Y107084D01*
X596070Y107128D01*
G02X596079Y107172I199J-18D01*
G02X596082Y107179I185J-75D01*
G01X596141Y107301D01*
G02X596143Y107303I135J-133D01*
G01X596174Y107365D01*
X596231Y107476D01*
G02X596238Y107485I161J-118D01*
G01X596289Y107501D01*
X596315Y107509D01*
G03X596685Y107646I-1177J3746D01*
G03X597158Y107888I-1548J3609D01*
G02X597279Y107916I103J-171D01*
G03X597294Y107914I206J1487D01*
G01X597300D01*
X597312Y107912D01*
X597316D01*
X597319Y107911D01*
G03X597358Y107909I96J1500D01*
G01X597364D01*
G03X597397Y107907I107J1499D01*
G01X597421D01*
G03X597437I8J1503D01*
G03X597513Y107909I-2J1503D01*
G01X597551Y107912D01*
G03X598640Y108510I-114J1498D01*
G01X598648Y108520D01*
G03X600823Y109624I-602J3880D01*
G01X606343Y115143D01*
X606355Y115149D01*
G03X606367Y115155I-666J1347D01*
G01X606371Y115157D01*
G03X607028Y115814I-682J1339D01*
G01X607030Y115818D01*
G03X607036Y115830I-1341J678D01*
G01X607042Y115842D01*
X607512Y116312D01*
X612236Y121037D01*
G03X612599Y121454I-2773J2780D01*
G03X612823Y121785I-3136J2363D01*
G01X612827Y121792D01*
X612851Y121825D01*
G03X613060Y122072I-2864J2635D01*
G03X613256Y122346I-3064J2399D01*
G03X613321Y122450I-3267J2114D01*
G01X613325Y122458D01*
X613331Y122467D01*
G03X613355Y122507I-3325J2022D01*
G03X613387Y122562I-3348J1984D01*
G01Y122563D01*
X613411Y122607D01*
X613415Y122615D01*
G03X613587Y122977I-3424J1849D01*
G01X615911Y128586D01*
X616192Y129263D01*
G02X616225Y129316I184J-78D01*
G01X616244Y129339D01*
X616259Y129347D01*
X616262Y129349D01*
X616278Y129358D01*
G03X617049Y130655I-731J1312D01*
G01Y130672D01*
G03X616998Y131062I-1502J2D01*
G01X616996Y131071D01*
X616983Y131113D01*
X616987Y131176D01*
X617000Y131210D01*
X619954Y138346D01*
X620092Y138679D01*
X623135Y146026D01*
G03X623322Y146596I-3593J1495D01*
G01X623324Y146606D01*
X623325Y146610D01*
X623427Y146854D01*
G03X623674Y147684I-3617J1528D01*
G03X623736Y148377I-3865J695D01*
G01Y148379D01*
G03X623735Y148442I-3927J-31D01*
G01Y148443D01*
X623727Y148939D01*
X623696Y150807D01*
X623677Y151942D01*
G03X623594Y152682I-3926J-66D01*
G01X621832Y161099D01*
G02X621842Y161194I198J27D01*
G02X621876Y161254I188J-67D01*
G01X621889Y161270D01*
X621923Y161297D01*
X621943Y161306D01*
G02X622030Y161326I87J-180D01*
G01X622167D01*
G02X622190Y161325I3J-200D01*
G03X624464I1137J1043D01*
G02X624487Y161326I20J-199D01*
G01X624767D01*
G02X624790Y161325I3J-200D01*
G03X625927Y160825I1137J1043D01*
G03Y163911I0J1543D01*
G03X624790Y163411I0J-1543D01*
G02X624767Y163410I-20J199D01*
G01X624487D01*
G02X624464Y163411I-3J200D01*
G03X622190I-1137J-1043D01*
G02X622167Y163410I-20J199D01*
G01X621890D01*
G02X621817Y163424I0J200D01*
G01X621783Y163437D01*
X621754Y163464D01*
G03X621742Y163475I-1021J-1102D01*
G03X621716Y163498I-1008J-1113D01*
G01X621710Y163503D01*
X621692Y163521D01*
G03X621344Y163738I-962J-1155D01*
G02X621340Y163740I87J180D01*
G01X621319Y163750D01*
X621291Y163785D01*
G02X621251Y163869I156J126D01*
G01X619206Y173639D01*
Y173643D01*
X616860Y186051D01*
X615448Y193521D01*
X615187Y194902D01*
G02X615184Y194936I197J35D01*
G01X615002Y206610D01*
G02X615022Y206701I200J4D01*
G01X615032Y206722D01*
X615062Y206758D01*
X615082Y206773D01*
G03X615398Y208860I-902J1204D01*
G01X615373Y208894D01*
X615358Y208913D01*
G02X615337Y208947I159J122D01*
G01X615335Y208951D01*
G02X615314Y209040I179J89D01*
G01Y209123D01*
G03X615296Y209206I-200J0D01*
G01X615272Y209259D01*
G02X615297Y209467I181J84D01*
G01X615319Y209495D01*
X615333Y209513D01*
X615335Y209516D01*
X615337Y209518D01*
X615340Y209522D01*
G03X615684Y210462I-1158J957D01*
G01Y210474D01*
G03X615568Y211058I-1502J5D01*
G01Y211059D01*
X615563Y211069D01*
G03X615398Y211360I-1381J-591D01*
G01X615374Y211393D01*
X615356Y211416D01*
G02X615339Y211443I160J120D01*
G01X615335Y211451D01*
G02X615314Y211540I179J89D01*
G01Y211623D01*
G03X615296Y211706I-200J0D01*
G01X615272Y211759D01*
G02X615297Y211967I181J84D01*
G01X615319Y211995D01*
X615333Y212013D01*
X615335Y212016D01*
X615337Y212018D01*
X615340Y212022D01*
G03X615684Y212962I-1158J957D01*
G01Y212974D01*
G03X615568Y213558I-1502J5D01*
G01Y213559D01*
X615563Y213569D01*
G03X615398Y213860I-1381J-591D01*
G01X615374Y213893D01*
X615356Y213916D01*
G02X615339Y213943I160J120D01*
G01X615335Y213951D01*
G02X615314Y214040I179J89D01*
G01Y214123D01*
G03X615296Y214206I-200J0D01*
G01X615272Y214259D01*
G02X615297Y214467I181J84D01*
G01X615319Y214495D01*
X615340Y214521D01*
X615341Y214522D01*
G03X615435Y214649I-1159J956D01*
G03X615632Y215082I-1252J831D01*
G01Y215084D01*
X615641Y215120D01*
G03X615681Y215379I-1459J358D01*
G03X615684Y215460I-1499J96D01*
G01Y215475D01*
G03Y215481I-1502J3D01*
G01Y215540D01*
G03X615282Y216501I-1501J-64D01*
G01X615281Y216502D01*
X615236Y216551D01*
G03X615221Y216565I-144J-139D01*
G01X615071Y216697D01*
X615053Y216732D01*
X614998Y216842D01*
X615000Y216893D01*
X615068Y218860D01*
X615102Y219838D01*
X615125Y220501D01*
X615127Y220548D01*
X615129Y220612D01*
X615179Y222038D01*
X615190Y222340D01*
X615197Y222548D01*
G02X615205Y222583I198J-27D01*
G01X615216Y222616D01*
G02X615253Y222673I184J-79D01*
G01X615258Y222678D01*
G03X615684Y223726I-1076J1048D01*
G01Y223730D01*
G03X615346Y224677I-1502J-2D01*
G01X615325Y224703D01*
X615276Y224833D01*
X615278Y224874D01*
X615288Y225138D01*
G02X615299Y225196I200J-8D01*
G01X615313Y225236D01*
X615336Y225264D01*
X615337Y225265D01*
G03X615355Y225287I-1154J962D01*
G01X615711Y225720D01*
G03X615698Y225988I-155J127D01*
G01X615672Y226014D01*
X615676Y226069D01*
Y226075D01*
G03X615684Y226229I-1494J155D01*
G01Y226262D01*
G03X615414Y227086I-1502J-36D01*
G01X615408Y227094D01*
X615398Y227111D01*
X615379Y227137D01*
X615369Y227171D01*
X615359Y227204D01*
X615364Y227333D01*
Y227335D01*
X615375Y227641D01*
X615379Y227757D01*
G02X615389Y227813I200J-7D01*
G01X615400Y227845D01*
X615416Y227868D01*
G03X615433Y227893I-1234J857D01*
G01X615434Y227895D01*
X615459Y227933D01*
G03X615684Y228712I-1278J791D01*
G01Y228727D01*
G03X615484Y229476I-1502J0D01*
G01X615471Y229498D01*
X615443Y229598D01*
X615444Y229630D01*
X615457Y230002D01*
X615471Y230405D01*
G02X615480Y230456I200J-9D01*
G01X615486Y230477D01*
X615496Y230497D01*
X615498Y230500D01*
X615499Y230502D01*
X615501Y230505D01*
G03X615684Y231200I-1321J719D01*
G01Y231231D01*
G03X615549Y231850I-1502J-3D01*
G01X615548Y231852D01*
X615543Y231863D01*
X615536Y231885D01*
X615524Y231920D01*
X615626Y234847D01*
X615885Y242259D01*
X616070Y247561D01*
X616217Y251757D01*
X616357Y255266D01*
X616394Y256183D01*
Y256187D01*
X616482Y257287D01*
X616503Y257301D01*
X616517Y257309D01*
X616556Y257334D01*
X616598Y257361D01*
X616693Y257422D01*
X616710Y257432D01*
G02X616810Y257460I102J-172D01*
G01X616892D01*
G02X616916Y257458I-5J-200D01*
G01X616967Y257450D01*
X616977Y257447D01*
X616983Y257445D01*
G03X617430Y257378I444J1436D01*
G01X617447D01*
G03X618938Y258880I-11J1502D01*
G03X617436Y260382I-1502J0D01*
G03X617144Y260354I-3J-1502D01*
G01X617097Y260345D01*
X617053Y260357D01*
G02X616971Y260401I51J193D01*
G01X616855Y260506D01*
X616822Y260536D01*
G02X616757Y260700I134J148D01*
G01X616905Y262551D01*
G02X616929Y262561I89J-179D01*
G01X617011Y262590D01*
X617013Y262592D01*
X617095Y262656D01*
G02X617219Y262699I124J-157D01*
G01X617259D01*
X617275Y262697D01*
G03X617432Y262680I240J1483D01*
G03X617497Y262678I79J1500D01*
G01X617540D01*
G03X618445Y263003I-29J1502D01*
G01X618465Y263019D01*
X618496Y263033D01*
G02X618572Y263048I76J-185D01*
G01X618656D01*
G03X618739Y263066I0J200D01*
G01X618792Y263090D01*
G02X619000Y263065I84J-181D01*
G01X619028Y263043D01*
X619046Y263029D01*
X619049Y263027D01*
G03X620010Y262678I962J1152D01*
G01X620011D01*
G03X621513Y264180I0J1502D01*
G03X620026Y265682I-1502J0D01*
G01X620009D01*
G03X619128Y265396I1J-1502D01*
G01X619095Y265371D01*
X619076Y265356D01*
G02X619042Y265335I-122J159D01*
G01X619038Y265333D01*
G02X618949Y265312I-89J179D01*
G01X618866D01*
G03X618783Y265294I0J-200D01*
G01X618730Y265270D01*
G02X618522Y265295I-84J181D01*
G01X618494Y265317D01*
X618476Y265331D01*
X618473Y265333D01*
G03X617512Y265682I-962J-1152D01*
G01X617485D01*
G02X617454Y265685I4J200D01*
G02X617354Y265736I37J197D01*
G01X617285Y265809D01*
G02X617283Y265811I140J142D01*
G01X617235Y265863D01*
G02X617183Y266014I147J135D01*
G01X628765Y410316D01*
G03X628776Y410511I-3914J319D01*
G01X630598Y470607D01*
G03X630600Y470724I-3925J126D01*
G01Y470728D01*
G03X630599Y470766I-3925J-84D01*
G01Y470768D01*
X630384Y490786D01*
X630100Y517117D01*
X629848Y540536D01*
G02X629877Y540643I200J3D01*
G02X629984Y540728I170J-105D01*
G01X630350Y540851D01*
G02X630407Y540860I59J-191D01*
G01X630566Y540780D01*
X630592Y540748D01*
G03X631881Y540064I1417J1114D01*
G01X631883D01*
X631947Y540059D01*
X632006D01*
G03X633812Y541861I3J1803D01*
G01Y545262D01*
G03X630206I-1803J0D01*
G01Y544520D01*
Y544519D01*
G02X630007Y544320I-200J1D01*
G01X630004D01*
G02X629805Y544518I1J200D01*
G01X629791Y545837D01*
X629772Y547542D01*
X629755Y549072D01*
X629754Y549164D01*
G02X629820Y549314I200J2D01*
G01X629873Y549362D01*
G02X629937Y549402I136J-147D01*
G01X629946Y549405D01*
G02X629966Y549410I59J-192D01*
G01X629968D01*
G02X630008Y549415I45J-195D01*
G03X630136Y549406I169J1493D01*
G01X630138D01*
G03X630166Y549405I68J1501D01*
G01X630184D01*
G03X630201I9J1502D01*
G01X630202D01*
G03X631136Y549731I0J1502D01*
G01X631155Y549746D01*
X631184Y549759D01*
G02X631262Y549775I78J-184D01*
G01X631346D01*
G03X631429Y549793I0J200D01*
G01X631482Y549817D01*
G02X631690Y549792I84J-181D01*
G01X631718Y549770D01*
X631736Y549756D01*
X631739Y549754D01*
G03X632700Y549405I962J1152D01*
G01X632701D01*
G03X632703I1J1502D01*
G03X633963Y550091I-1J1502D01*
G01X633967Y550097D01*
G03X634201Y550825I-1266J809D01*
G03X634203Y550890I-1500J79D01*
G01Y550943D01*
X634202Y550954D01*
G03X633917Y551790I-1502J-45D01*
G01X633892Y551823D01*
X633877Y551842D01*
G02X633856Y551876I159J122D01*
G01X633854Y551880D01*
G02X633833Y551969I179J89D01*
G01Y552052D01*
G03X633815Y552135I-200J0D01*
G01X633791Y552188D01*
G02X633816Y552396I181J84D01*
G01X633838Y552424D01*
X633852Y552442D01*
X633854Y552445D01*
G03X634202Y553350I-1153J963D01*
G03X634203Y553402I-1501J55D01*
G01Y553412D01*
G03X633668Y554556I-1502J-5D01*
G03X632713Y554909I-967J-1149D01*
G01X632699D01*
G03X631818Y554623I1J-1502D01*
G01X631785Y554598D01*
X631766Y554583D01*
G02X631732Y554562I-122J159D01*
G01X631728Y554560D01*
G02X631639Y554539I-89J179D01*
G01X631556D01*
G03X631473Y554521I0J-200D01*
G01X631420Y554497D01*
G02X631212Y554522I-84J181D01*
G01X631184Y554544D01*
X631166Y554558D01*
X631163Y554560D01*
G03X630202Y554909I-962J-1152D01*
G01X630200D01*
G03X630197I-2J-1502D01*
G03X629980Y554893I2J-1502D01*
G01X629969Y554891D01*
X629949Y554890D01*
G02X629810Y554937I-10J200D01*
G01X629761Y554979D01*
G02X629690Y555126I129J153D01*
G01X629595Y563969D01*
X629567Y566546D01*
X629551Y568030D01*
G02X629579Y568135I200J3D01*
G02X629602Y568166I171J-103D01*
G01X629656Y568226D01*
X629786Y568369D01*
G02X629845Y568414I149J-134D01*
G01X629875Y568429D01*
X629911Y568433D01*
X629915D01*
G03X629960Y568438I-143J1495D01*
G01X629961D01*
G02X630092Y568408I23J-199D01*
G01X630325Y568245D01*
G02X630397Y568145I-118J-161D01*
G01X630400Y568131D01*
G03X631862Y566973I1462J344D01*
G01X631863D01*
G03X632430Y567084I0J1502D01*
G01X632474Y567102D01*
X632567Y567095D01*
X632882Y566908D01*
G02X632979Y566760I-101J-172D01*
G01Y566759D01*
G03X634471Y565427I1492J170D01*
G01X634483D01*
G03X635985Y566928I0J1502D01*
G01Y566930D01*
G03X635979Y567058I-1502J-6D01*
G01X635978Y567072D01*
G02Y567080I200J4D01*
G01X635979Y567094D01*
G03X635985Y567227I-1496J134D01*
G01Y567229D01*
G03X635486Y568348I-1504J0D01*
G01X635454Y568377D01*
X635437Y568415D01*
X635424Y568443D01*
X635411Y568548D01*
X635410Y568554D01*
X635449Y568615D01*
G03X635687Y569426I-1263J811D01*
G03X635685Y569512I-1502J8D01*
G02X635686Y569540I200J7D01*
G03X635697Y569723I-1502J182D01*
G01Y569726D01*
G03X634186Y571238I-1512J0D01*
G01X634185D01*
G03X634022Y571228I11J-1511D01*
G01X633983Y571224D01*
X633948Y571233D01*
G02X633892Y571258I52J193D01*
G01X633744Y571367D01*
X633741Y571370D01*
X633716Y571390D01*
G02X633686Y571423I132J150D01*
G01X633678Y571436D01*
G02X633654Y571491I169J107D01*
G03X632119Y572813I-1535J-230D01*
G03X630682Y571846I0J-1551D01*
G01X630679Y571838D01*
X630672Y571824D01*
G02X630587Y571742I-175J97D01*
G01X630500Y571704D01*
X630498D01*
X630444Y571681D01*
G02X630347Y571671I-68J188D01*
G01X630306Y571679D01*
X630291Y571684D01*
X630289Y571685D01*
G03X630222Y571707I-516J-1457D01*
G03X630161Y571724I-445J-1480D01*
G01X630144Y571728D01*
X630124Y571733D01*
X630094Y571755D01*
G02X630042Y571810I117J163D01*
G01X630027Y571835D01*
G03X629981Y571887I-171J-105D01*
G01X629980Y571888D01*
G03X629977Y571890I-113J-166D01*
G01X629935Y571932D01*
G02X629925Y571947I161J118D01*
G01X629923Y571951D01*
G03X629927Y572070I-1498J110D01*
G03X629921Y572199I-1502J-5D01*
G01Y572200D01*
X629920Y572220D01*
X629923Y572249D01*
G03X629919Y572533I-1498J121D01*
G03X629544Y573375I-1494J-161D01*
G01X629518Y573404D01*
X629506Y573437D01*
G02X629493Y573505I187J71D01*
G01X629450Y577342D01*
X629447Y577660D01*
Y577674D01*
X629603Y580200D01*
X630980Y602590D01*
Y602594D01*
X639753Y715065D01*
X641412Y736329D01*
X644722Y778766D01*
G02X644921Y778950I199J-16D01*
G01X669286D01*
G02X669313Y778948I-1J-200D01*
G02X669463Y778844I-26J-198D01*
G02X669485Y778774I-177J-94D01*
G01X669511Y778291D01*
X669591Y776733D01*
X672083Y728858D01*
X676168Y650376D01*
X678321Y609006D01*
X680369Y569661D01*
G02X680233Y569461I-200J-10D01*
G01X680221Y569457D01*
X680214Y569455D01*
G03X679084Y568000I372J-1455D01*
G03X680295Y566525I1504J0D01*
G01X680296D01*
X680310Y566522D01*
X680342Y566511D01*
G02X680409Y566472I-65J-189D01*
G02X680423Y566458I-134J-148D01*
G01X680494Y566381D01*
G02X680505Y566368I-147J-136D01*
G02X680546Y566265I-158J-123D01*
G01X680549Y566202D01*
X680558Y566030D01*
Y566022D01*
X680567Y565865D01*
Y565863D01*
X680616Y564916D01*
X680631Y564634D01*
X680643Y564394D01*
Y564393D01*
X680645Y564363D01*
X680638Y564335D01*
G02X680631Y564312I-195J47D01*
G02X680617Y564282I-188J69D01*
G01X680563Y564199D01*
X680548Y564176D01*
X680508Y564140D01*
X680486Y564128D01*
G03X679687Y562800I704J-1328D01*
G01Y562797D01*
G03X679698Y562617I1503J2D01*
G01X679700Y562605D01*
Y562604D01*
X679703Y562577D01*
X679707Y562557D01*
G03X679790Y562254I1483J243D01*
G03X680379Y561535I1400J546D01*
G01X680418Y561510D01*
G03X680670Y561389I774J1289D01*
G01X680688Y561382D01*
X680724Y561360D01*
G02X680808Y561217I-115J-164D01*
G01X680816Y561074D01*
X680817Y561064D01*
Y561063D01*
X680822Y560967D01*
X680824Y560921D01*
Y560903D01*
G02X680814Y560841I-200J0D01*
G02X680788Y560791I-188J66D01*
G01X680722Y560704D01*
X680697Y560679D01*
G02X680645Y560642I-141J142D01*
G01X680615Y560628D01*
X680597Y560623D01*
G03X679229Y558800I531J-1823D01*
G03X680802Y556930I1898J0D01*
G01X680803D01*
X680818Y556927D01*
X680820D01*
X680836Y556924D01*
X680864Y556909D01*
G02X680912Y556872I-97J-175D01*
G01X680945Y556837D01*
X680947Y556835D01*
X680994Y556783D01*
G02X681031Y556724I-148J-134D01*
G01X681044Y556693D01*
X681046Y556657D01*
X681049Y556599D01*
Y556594D01*
X681051Y556562D01*
X681052Y556550D01*
G02X680991Y556393I-200J-13D01*
G01X680968Y556371D01*
X680930Y556352D01*
X680929D01*
G03X680084Y555005I658J-1352D01*
G01Y555000D01*
G03X680090Y554861I1503J-5D01*
G01X680091Y554848D01*
X680094Y554823D01*
G03X680122Y554663I1492J179D01*
G03X680163Y554517I1465J333D01*
G01X680166Y554508D01*
G03X680174Y554486I1416J502D01*
G01Y554484D01*
X680212Y554376D01*
Y554375D01*
G03X680230Y554336I190J64D01*
G01X680307Y554212D01*
G03X680663Y553814I1281J787D01*
G03X681068Y553589I924J1186D01*
G01X681069D01*
X681089Y553581D01*
G02X681212Y553426I-74J-185D01*
G01X681214Y553415D01*
X681250Y552741D01*
X681310Y551585D01*
X681312Y551549D01*
X681292Y551483D01*
X681270Y551454D01*
X681265Y551447D01*
X681205Y551377D01*
X681202Y551374D01*
X681179Y551347D01*
X681066Y551287D01*
X681034Y551281D01*
G03X679794Y549976I252J-1481D01*
G01X679789Y549927D01*
G03X679783Y549801I1497J-134D01*
G01Y549799D01*
G03X680164Y548800I1503J1D01*
G01X680165Y548799D01*
X680192Y548768D01*
X680201Y548743D01*
X680208Y548720D01*
G02X680216Y548660I-192J-56D01*
G01X680211Y548604D01*
Y548602D01*
X680194Y548369D01*
X680191Y548329D01*
X680153Y548253D01*
X680121Y548226D01*
G03X679584Y547075I965J-1151D01*
G03X681086Y545573I1502J0D01*
G01X681095D01*
G03X681218Y545577I13J1503D01*
G01X681241Y545579D01*
X681253Y545580D01*
X681290Y545568D01*
G02X681358Y545529I-64J-190D01*
G01X681574Y545341D01*
G02X681640Y545223I-131J-151D01*
G02X681642Y545201I-198J-29D01*
G01X681716Y543789D01*
X681768Y542787D01*
X681801Y542141D01*
G02X681764Y542014I-200J-11D01*
G01X681745Y541988D01*
X681692Y541951D01*
X681658Y541941D01*
G03X680586Y540594I427J-1440D01*
G01Y540587D01*
G03Y540408I1500J-89D01*
G03X680685Y539955I1500J91D01*
G01X680700Y539916D01*
X680697Y539832D01*
Y539823D01*
G03X680704Y539769I200J-2D01*
G01X680707Y539760D01*
X680709Y539751D01*
G03X680795Y539632I194J50D01*
G01X680797Y539631D01*
G02X680799Y539629I-137J-139D01*
G03X680806Y539625I103J172D01*
G01X680809Y539623D01*
X680810D01*
X680827Y539613D01*
X680901Y539565D01*
G02X680917Y539552I-118J-162D01*
G02X680919Y539550I-140J-142D01*
G01X680955Y539509D01*
G03X680959Y539505I1064J1060D01*
G02X680961Y539503I-140J-142D01*
G03X680963Y539501I142J140D01*
G02X680970Y539494I-138J-145D01*
G03X681067Y539395I1121J1001D01*
G01X681076Y539387D01*
X681091Y539374D01*
X681092Y539373D01*
G03X681406Y539160I994J1127D01*
G03X681516Y539110I676J1342D01*
G03X681670Y539056I573J1389D01*
G03X681751Y539035I417J1443D01*
G01X681755Y539034D01*
X681773Y539030D01*
X681805Y539013D01*
X681838Y538995D01*
X681884Y538941D01*
X681921Y538897D01*
X681923Y538895D01*
X681934Y538881D01*
X681947Y538864D01*
G02X681972Y538803I-170J-105D01*
G01X681975Y538787D01*
G02X681976Y538781I-197J-36D01*
G01Y538780D01*
X681977Y538776D01*
X681993Y538466D01*
X682041Y537539D01*
X682064Y537096D01*
X682133Y535772D01*
X682236Y533797D01*
X682263Y533273D01*
X682345Y531658D01*
G02X682235Y531469I-200J-10D01*
G01X682202Y531453D01*
X682183Y531447D01*
X682179Y531446D01*
X682178D01*
G03X681084Y530000I409J-1446D01*
G03X681097Y529800I1502J-3D01*
G03X682322Y528521I1489J200D01*
G01X682355Y528515D01*
X682415Y528482D01*
G02X682518Y528317I-97J-175D01*
G01X689834Y387822D01*
X696804Y253880D01*
Y253868D01*
X696778Y246600D01*
X696775Y245756D01*
G02X696574Y245566I-200J10D01*
G01X696520D01*
X696474Y245593D01*
G03X696389Y245639I-757J-1298D01*
G01X696383Y245642D01*
G03X696375Y245646I-676J-1342D01*
G03X696317Y245673I-663J-1348D01*
G01X696316D01*
X696280Y245688D01*
G03X696089Y245752I-572J-1389D01*
G01X696073Y245756D01*
G03X695724Y245799I-357J-1459D01*
G01X695708D01*
G03X695354Y245756I3J-1502D01*
G01X695342Y245753D01*
X695317Y245750D01*
G02X695155Y245806I-22J199D01*
G01X695015Y245969D01*
X695014Y245971D01*
X694913Y246086D01*
G02X694896Y246110I154J127D01*
G02X694870Y246255I170J105D01*
G01X694881Y246293D01*
X694885Y246304D01*
G03X694996Y246871I-1392J567D01*
G01Y246874D01*
G03X694991Y246993I-1503J-4D01*
G01X694989Y247009D01*
Y247013D01*
G03X693493Y248376I-1496J-139D01*
G03X691991Y246874I0J-1502D01*
G03X693486Y245372I1502J0D01*
G01X693496D01*
G03X693825Y245409I-2J1502D01*
G01X693827D01*
X693857Y245416D01*
X693870Y245419D01*
X693890Y245421D01*
X693892D01*
G02X694024Y245388I20J-199D01*
G02X694050Y245367I-112J-166D01*
G01X694300Y245076D01*
G02X694336Y244919I-160J-119D01*
G01X694325Y244878D01*
X694321Y244867D01*
G03X694210Y244300I1392J-567D01*
G01Y244297D01*
G03X694215Y244175I1503J0D01*
G01X694219Y244143D01*
X694221Y244122D01*
G03X694770Y243127I1492J174D01*
G03X695550Y242803I943J1170D01*
G01X695555D01*
X695576Y242800D01*
X695579D01*
X695587Y242799D01*
X695593D01*
X695608Y242798D01*
X695616D01*
X695625Y242797D01*
X695640D01*
G03X695660Y242796I85J1499D01*
G01X695664D01*
G03X695679Y242795I107J1497D01*
G01X695715D01*
G03X696226Y242885I-1J1502D01*
G02X696273Y242896I69J-188D01*
G02X696410Y242861I22J-199D01*
G01X696684Y242667D01*
G02X696710Y242644I-119J-161D01*
G01X696722Y242630D01*
G02X696763Y242516I-159J-122D01*
G01X696762Y242317D01*
X696755Y240152D01*
Y240146D01*
G03X696754Y240130I199J-20D01*
G03X696755Y240077I3926J48D01*
G01X696763Y239551D01*
X696744Y239520D01*
G03X696706Y237972I1269J-806D01*
G03X696761Y237882I1309J738D01*
G01X696774Y237862D01*
X696782Y237836D01*
G02X696790Y237781I-192J-56D01*
G01X696892Y231214D01*
G02X696881Y231146I-200J-3D01*
G01X696870Y231113D01*
X696846Y231084D01*
G03X696493Y230121I1150J-968D01*
G01X696494Y230096D01*
G03X696753Y229273I1503J21D01*
G03X696855Y229139I1245J842D01*
G01X696877Y229113D01*
X696915Y229017D01*
G02X696929Y228947I-186J-74D01*
G01X697092Y218486D01*
Y218476D01*
X696902Y213631D01*
X696243Y196799D01*
G02X696190Y196671I-200J8D01*
G01X696163Y196644D01*
X695868Y196484D01*
X695850Y196476D01*
X695835Y196468D01*
G02X695696Y196454I-88J179D01*
G01X695643Y196469D01*
X695620Y196482D01*
G03X694879Y196678I-742J-1306D01*
G01X694864D01*
G03X694713Y196669I14J-1502D01*
G03X693946Y196354I165J-1493D01*
G01X693927Y196339D01*
X693905Y196329D01*
X693884Y196318D01*
X693840Y196308D01*
X693733D01*
G03X693650Y196290I0J-200D01*
G01X693597Y196266D01*
G02X693389Y196291I-84J181D01*
G01X693361Y196313D01*
X693343Y196327D01*
X693340Y196329D01*
G03X692379Y196678I-962J-1152D01*
G01X692340D01*
G03X691496Y196392I38J-1502D01*
G01X691462Y196368D01*
X691442Y196351D01*
G02X691413Y196333I-120J161D01*
G01X691405Y196329D01*
G02X691316Y196308I-89J179D01*
G01X691233D01*
G03X691150Y196290I0J-200D01*
G01X691097Y196266D01*
G02X690889Y196291I-84J181D01*
G01X690861Y196313D01*
X690843Y196327D01*
X690840Y196329D01*
G03X689879Y196678I-962J-1152D01*
G01X689840D01*
G03X688996Y196392I38J-1502D01*
G01X688962Y196368D01*
X688942Y196351D01*
G02X688913Y196333I-120J161D01*
G01X688905Y196329D01*
G02X688816Y196308I-89J179D01*
G01X688733D01*
G03X688650Y196290I0J-200D01*
G01X688597Y196266D01*
G02X688389Y196291I-84J181D01*
G01X688361Y196313D01*
X688343Y196327D01*
X688340Y196329D01*
G03X687379Y196678I-962J-1152D01*
G01X687378D01*
G03Y193674I0J-1502D01*
G01X687379D01*
G03X688313Y194000I0J1502D01*
G01X688332Y194015D01*
X688361Y194028D01*
G02X688439Y194044I78J-184D01*
G01X688523D01*
G03X688606Y194062I0J200D01*
G01X688659Y194086D01*
G02X688867Y194061I84J-181D01*
G01X688895Y194039D01*
X688913Y194025D01*
X688916Y194023D01*
G03X689877Y193674I962J1152D01*
G01X689916D01*
G03X690812Y193999I-38J1502D01*
G01X690832Y194015D01*
X690863Y194029D01*
G02X690939Y194044I76J-185D01*
G01X691023D01*
G03X691106Y194062I0J200D01*
G01X691159Y194086D01*
G02X691367Y194061I84J-181D01*
G01X691395Y194039D01*
X691413Y194025D01*
X691416Y194023D01*
G03X692377Y193674I962J1152D01*
G01X692416D01*
G03X693312Y193999I-38J1502D01*
G01X693332Y194015D01*
X693363Y194029D01*
G02X693439Y194044I76J-185D01*
G01X693523D01*
G03X693606Y194062I0J200D01*
G01X693659Y194086D01*
G02X693867Y194061I84J-181D01*
G01X693895Y194039D01*
X693913Y194025D01*
X693916Y194023D01*
G03X694877Y193674I962J1152D01*
G01X694914D01*
G03X695205Y193710I-38J1502D01*
G03X695310Y193737I-321J1467D01*
G01X695342Y193747D01*
X695346Y193748D01*
X695348Y193749D01*
X695364Y193754D01*
G03X695467Y193794I-492J1419D01*
G03X695477Y193799I-84J181D01*
G01X695482Y193801D01*
X695484D01*
G03X695515Y193816I-639J1359D01*
G01X695535Y193825D01*
X695587Y193837D01*
G02X695721Y193821I45J-195D01*
G01X695733Y193815D01*
X696004Y193637D01*
G02X696036Y193611I-109J-167D01*
G01X696053Y193594D01*
G02X696071Y193573I-143J-140D01*
G01X696077Y193565D01*
G02X696111Y193445I-166J-112D01*
G01X695760Y184459D01*
Y184450D01*
X692073Y157164D01*
G03X692038Y156699I3891J-527D01*
G01X692017Y155394D01*
X692007Y155350D01*
X691997Y155331D01*
G03X691590Y153648I3519J-1742D01*
G01X691564Y151961D01*
Y151955D01*
G03X691560Y151777I3887J-176D01*
G03Y151766I3891J-6D01*
G01Y151637D01*
G03X691671Y150706I3926J-4D01*
G01X691681Y150667D01*
X691665Y150566D01*
X691658Y150523D01*
X691619Y150284D01*
G03X691568Y149658I3816J-626D01*
G03X691569Y149578I3892J9D01*
G01X691570Y149534D01*
X691567Y149516D01*
G03X691517Y148948I3876J-627D01*
G01Y148942D01*
X691516Y148892D01*
X691487Y146997D01*
Y146996D01*
G03X691486Y146938I3925J-97D01*
G01Y146932D01*
G03X691640Y145849I3927J6D01*
G01X691647Y145824D01*
X691653Y145514D01*
X691635Y145474D01*
G03X691618Y145434I3572J-1542D01*
G01X691605Y145403D01*
X691522Y145308D01*
X691490Y145286D01*
X691412Y145247D01*
G02X691323Y145226I-89J179D01*
G01X691268D01*
X691247Y145231D01*
G03X691017Y145262I-315J-1469D01*
G01X691003D01*
X690995Y145263D01*
X690978D01*
G03X690967Y145264I-141J-1494D01*
G01X690918D01*
G03X689428Y143762I12J-1502D01*
G03X690929Y142260I1502J0D01*
G01X690987D01*
X691007Y142258D01*
G02X691113Y142212I-23J-199D01*
G01X691128Y142199D01*
X691130Y142197D01*
X691321Y142026D01*
G02X691348Y141995I-136J-146D01*
G01X691373Y141956D01*
X691383Y141913D01*
X691386Y141889D01*
Y141884D01*
G03X691410Y141687I3874J372D01*
G03X691563Y141029I3853J549D01*
G03X691645Y140803I3697J1214D01*
G01Y140801D01*
G03X691656Y140775I3589J1503D01*
G01Y140774D01*
X691667Y140748D01*
Y140747D01*
G03X691671Y140739I3480J1735D01*
G02X691673Y140733I-188J-66D01*
G03X691696Y140680I3581J1523D01*
G01X691716Y140635D01*
G02X691728Y140526I-185J-76D01*
G01X691690Y140387D01*
Y140385D01*
X691671Y140314D01*
X691643Y140210D01*
X691638Y140190D01*
X691624Y140139D01*
Y140137D01*
X691582Y139986D01*
X691571Y139946D01*
X691537Y139904D01*
G02X691497Y139869I-150J132D01*
G01X691421Y139822D01*
X691418Y139821D01*
X691307Y139755D01*
G02X691207Y139728I-100J173D01*
G01X691163D01*
X691112Y139735D01*
G03X690200Y139842I-910J-3820D01*
G01X690183D01*
G03X688095Y139230I17J-3927D01*
G01X688087Y139232D01*
X688071Y139235D01*
G03X687801Y139259I-267J-1478D01*
G01X687799D01*
G03X686297Y137757I0J-1502D01*
G01Y137746D01*
G03X686409Y137189I1502J12D01*
G01X686411Y137183D01*
X686418Y137166D01*
X686444Y137103D01*
X686449Y137081D01*
X686431Y137019D01*
G03X686272Y135946I3768J-1107D01*
G01Y135902D01*
G03X686613Y134315I3927J14D01*
G02X686625Y134277I-184J-79D01*
G01X686639Y134217D01*
G02Y134213I-200J-2D01*
G01X686625Y134153D01*
G02X686613Y134115I-196J41D01*
G03X686272Y132515I3586J-1601D01*
G01Y132513D01*
G03X686305Y132006I3927J1D01*
G03X686378Y131609I3894J511D01*
G03X686449Y131351I3819J912D01*
G01X686442Y131320D01*
X686433Y131298D01*
G03X686299Y130760I1366J-626D01*
G01Y130743D01*
G03X686297Y130670I1500J-78D01*
G01Y130640D01*
G03X687799Y129168I1502J30D01*
G01X687800D01*
G03X688027Y129185I2J1502D01*
G02X688161Y129159I31J-197D01*
G03X690199Y128588I2039J3356D01*
G01X690200D01*
G03X692237Y129158I-1J3927D01*
G02X692370Y129185I104J-171D01*
G03X692603Y129168I225J1485D01*
G01X692606D01*
G03X693066Y129242I-6J1501D01*
G01X693120Y129260D01*
X693165Y129256D01*
G02X693278Y129208I-18J-200D01*
G01X693355Y129152D01*
X693525Y129028D01*
G02X693575Y128969I-125J-156D01*
G01X693573Y128888D01*
Y128887D01*
G03X693572Y128829I3925J-97D01*
G01Y128822D01*
G03X693573Y128728I3927J-5D01*
G03X693914Y127225I3926J100D01*
G01X693921Y127209D01*
X693939Y127130D01*
G02Y127126I-200J-2D01*
G01X693925Y127066D01*
G02X693913Y127028I-196J41D01*
G03X693572Y125428I3586J-1601D01*
G03X693578Y125216I3927J5D01*
G01X693582Y125138D01*
G02X693575Y125127I-172J102D01*
G02X693568Y125118I-161J118D01*
G01X693554Y125102D01*
X693552Y125100D01*
X693546Y125093D01*
X693545Y125092D01*
X693475Y125012D01*
G02X693441Y124985I-140J142D01*
G01X693395Y124959D01*
X693379Y124957D01*
X693369Y124956D01*
X693353Y124954D01*
X693352D01*
G03X693312Y124949I463J-3865D01*
G01X693281Y124946D01*
X693219Y124958D01*
X693180Y124970D01*
G03X692883Y125059I-577J-1387D01*
G01X692882D01*
X692865Y125062D01*
G03X692832Y125068I-285J-1475D01*
G01X692829D01*
X692817Y125070D01*
G03X692784Y125075I-242J-1483D01*
G01X692778D01*
X692773Y125076D01*
X692769D01*
G03X692635Y125086I-179J-1491D01*
G01X692597D01*
G03X692342Y125064I1J-1502D01*
G01X692303Y125057D01*
G03X690199Y125668I-2103J-3315D01*
G03X688150Y125092I-2J-3926D01*
G02X688055Y125068I-95J176D01*
G01X688031D01*
X688017Y125070D01*
X688013Y125071D01*
X688008D01*
G03X687938Y125080I-226J-1485D01*
G03X687917Y125082I-153J-1494D01*
G01X687913D01*
X687905Y125083D01*
X687901D01*
G03X687822Y125086I-96J-1499D01*
G01X687799D01*
G03X686297Y123584I0J-1502D01*
G01Y123573D01*
G03X686409Y123016I1502J12D01*
G01X686411Y123010D01*
X686418Y122993D01*
X686444Y122930D01*
X686449Y122908D01*
X686431Y122846D01*
G03X686272Y121750I3768J-1106D01*
G01Y121715D01*
G03X686376Y120844I3927J27D01*
G03X686614Y120139I3823J898D01*
G01X686621Y120123D01*
X686639Y120044D01*
G02Y120040I-200J-2D01*
G01X686621Y119961D01*
X686614Y119945D01*
G03X686272Y118342I3585J-1603D01*
G03X686331Y117663I3927J-1D01*
G03X686411Y117307I3867J682D01*
G03X686450Y117175I3785J1046D01*
G01X686443Y117146D01*
G03X686297Y116499I1357J-646D01*
G01Y116497D01*
G03X687799Y114995I1502J0D01*
G01X687802D01*
G03X688079Y115021I-1J1502D01*
G01X688095Y115024D01*
X688098Y115025D01*
G03X690199Y114416I2100J3317D01*
G03X692299Y115024I1J3926D01*
G01X692303Y115023D01*
X692317Y115021D01*
G03X692598Y114995I278J1476D01*
G01X692602D01*
G03X692997Y115048I0J1502D01*
G01X693004Y115050D01*
X693009Y115051D01*
X693024Y115055D01*
X693079Y115073D01*
X693081D01*
X693102Y115081D01*
X693152Y115086D01*
X693175Y115083D01*
G02X693217Y115072I-29J-198D01*
G02X693265Y115046I-70J-187D01*
G01X693513Y114865D01*
G02X693516Y114863I-110J-168D01*
G01X693535Y114849D01*
G02X693561Y114824I-125J-156D01*
G02X693575Y114805I-154J-128D01*
G01X693573Y114716D01*
Y114715D01*
G03X693572Y114656I3925J-96D01*
G01Y114649D01*
G03X693573Y114555I3927J-5D01*
G03X693914Y113052I3926J100D01*
G01X693921Y113036D01*
X693939Y112957D01*
G02Y112953I-200J-2D01*
G01X693921Y112874D01*
X693914Y112858D01*
G03X693572Y111255I3585J-1603D01*
G03X693631Y110576I3927J-1D01*
G03X693711Y110221I3867J685D01*
G01Y110219D01*
G03X693739Y110126I3773J1085D01*
G01Y110124D01*
G03X693750Y110088I3761J1129D01*
G01X693743Y110059D01*
X693734Y110040D01*
G03X693599Y109500I1365J-628D01*
G01Y109483D01*
G03X693597Y109410I1500J-78D01*
G01Y109380D01*
G03X695099Y107908I1502J30D01*
G03X695375Y107932I8J1503D01*
G01X695383Y107934D01*
G03X695400Y107937I-253J1481D01*
G03X695569Y107835I2113J3310D01*
G03X695573Y107833I91J178D01*
G03X695586Y107826I1868J3454D01*
G01X695655Y107787D01*
G02X695660Y107776I-179J-88D01*
G03X695662Y107770I190J60D01*
G02X695664Y107766I-177J-91D01*
G01X695747Y107462D01*
X695746Y107408D01*
X695739Y107382D01*
X695722Y107321D01*
X695710Y107300D01*
G03X695516Y106562I1308J-738D01*
G01Y106526D01*
X695517Y106510D01*
Y106507D01*
G03X695526Y106388I1501J54D01*
G03X695693Y105854I1492J173D01*
G03X696091Y105379I1325J706D01*
G01X696099Y105373D01*
X696127Y105346D01*
X696178Y105284D01*
X696188Y105263D01*
X696198Y105217D01*
X696182Y104911D01*
X696180Y104862D01*
X696121Y104761D01*
G02X696090Y104720I-174J99D01*
G01X696061Y104691D01*
X696029Y104664D01*
X696020Y104658D01*
G03X695356Y103411I839J-1247D01*
G03X698362I1503J0D01*
G03X697767Y104609I-1504J0D01*
G01X697754Y104619D01*
X697739Y104634D01*
X697715Y104665D01*
G02X697682Y104771I167J110D01*
G01X697697Y105105D01*
X697716Y105142D01*
X697720Y105151D01*
X697770Y105235D01*
X697787Y105252D01*
X697831Y105297D01*
X697856Y105314D01*
G03X698520Y106557I-838J1247D01*
G01Y106575D01*
G03X698441Y107043I-1502J-13D01*
G01X698438Y107052D01*
X698428Y107084D01*
X698432Y107128D01*
G02X698441Y107172I199J-18D01*
G02X698444Y107179I185J-75D01*
G01X698503Y107301D01*
G02X698505Y107303I135J-133D01*
G01X698536Y107365D01*
X698593Y107476D01*
G02X698600Y107485I161J-118D01*
G01X698651Y107501D01*
X698677Y107509D01*
G03X699047Y107646I-1177J3746D01*
G03X699520Y107888I-1548J3609D01*
G02X699641Y107916I103J-171D01*
G03X699656Y107914I206J1487D01*
G01X699662D01*
X699674Y107912D01*
X699678D01*
X699681Y107911D01*
G03X699720Y107909I96J1500D01*
G01X699726D01*
G03X699759Y107907I107J1499D01*
G01X699783D01*
G03X699799I8J1503D01*
G03X699875Y107909I-2J1503D01*
G01X699913Y107912D01*
G03X701002Y108510I-114J1498D01*
G01X701010Y108520D01*
G03X703185Y109624I-602J3880D01*
G01X708705Y115143D01*
X708717Y115149D01*
G03X708729Y115155I-666J1347D01*
G01X708733Y115157D01*
G03X709390Y115814I-682J1339D01*
G01X709392Y115818D01*
G03X709398Y115830I-1341J678D01*
G01X709404Y115842D01*
X709874Y116312D01*
X714598Y121037D01*
G03X714961Y121454I-2773J2780D01*
G03X715185Y121785I-3136J2363D01*
G01X715189Y121792D01*
X715213Y121825D01*
G03X715422Y122072I-2864J2635D01*
G03X715618Y122346I-3064J2399D01*
G03X715683Y122450I-3267J2114D01*
G01X715687Y122458D01*
X715693Y122467D01*
G03X715717Y122507I-3325J2022D01*
G03X715749Y122562I-3348J1984D01*
G01Y122563D01*
X715773Y122607D01*
X715777Y122615D01*
G03X715949Y122977I-3424J1849D01*
G01X717358Y126376D01*
X718414Y128926D01*
X718542Y129236D01*
G02X718569Y129278I181J-86D01*
G01X718639Y129357D01*
X718667Y129373D01*
G03X719411Y130670I-758J1297D01*
G01Y130697D01*
G03X719355Y131084I-1503J-20D01*
G01X719345Y131119D01*
X719347Y131149D01*
G02X719362Y131213I199J-13D01*
G01X723236Y140565D01*
X724154Y142783D01*
X724289Y143108D01*
X724928Y144651D01*
X725497Y146026D01*
G03X725684Y146596I-3593J1495D01*
G01X725686Y146606D01*
X725687Y146610D01*
X725789Y146854D01*
G03X726036Y147684I-3617J1528D01*
G03X726098Y148377I-3865J695D01*
G01Y148379D01*
G03X726097Y148442I-3927J-31D01*
G01Y148443D01*
X726000Y154276D01*
G03X725917Y155016I-3926J-66D01*
G01X725729Y155915D01*
X725399Y157489D01*
X724778Y160457D01*
G02X724822Y160628I196J41D01*
G02X724837Y160644I153J-129D01*
G01X725087Y160877D01*
G02X725279Y160923I137J-146D01*
G03X725689Y160866I410J1446D01*
G03X726716Y161272I0J1502D01*
G01X726717Y161273D01*
G02X726788Y161315I135J-147D01*
G02X726853Y161326I65J-189D01*
G01X727125D01*
G02X727190Y161315I0J-200D01*
G02X727261Y161273I-64J-189D01*
G01X727262Y161272D01*
G03X728289Y160866I1027J1096D01*
G03Y163870I0J1502D01*
G03X727262Y163464I0J-1502D01*
G01X727261Y163463D01*
G02X727190Y163421I-135J147D01*
G02X727125Y163410I-65J189D01*
G01X726853D01*
G02X726788Y163421I0J200D01*
G02X726717Y163463I64J189D01*
G01X726716Y163464D01*
G03X725689Y163870I-1027J-1096D01*
G03X724735Y163528I0J-1502D01*
G02X724733Y163526I-142J140D01*
G01X724732D01*
G02X724641Y163484I-127J155D01*
G01X724616Y163480D01*
X724565Y163484D01*
X724217Y163606D01*
G02X724088Y163753I67J189D01*
G01X722894Y169453D01*
X722264Y172464D01*
X720385Y181439D01*
X718033Y192670D01*
G02X718029Y192709I196J40D01*
G01X717957Y199825D01*
X717882Y207271D01*
G03X717889Y207284I-1328J724D01*
G01X717908Y207302D01*
G02X717959Y207337I137J-145D01*
G01X717968Y207341D01*
X718037Y207357D01*
G03X718140Y207418I-46J195D01*
G03X718189Y207586I-148J134D01*
G01Y207588D01*
G03X718186Y207600I-196J-43D01*
G01Y207601D01*
X718183Y207614D01*
X718058Y207964D01*
Y207997D01*
G03X717888Y208675I-1514J-19D01*
G01X717881Y208688D01*
G02X717866Y208751I185J77D01*
G01X717855Y209702D01*
Y209741D01*
X717866Y209762D01*
G03X718047Y210463I-1321J715D01*
G03X718046Y210535I-1503J15D01*
G01X718043Y210578D01*
G03X717864Y211196I-1499J-99D01*
G02X717840Y211290I176J95D01*
G01X717839Y211346D01*
X717832Y212047D01*
G02X717840Y212104I200J1D01*
G01X717861Y212179D01*
X717874Y212201D01*
G03X718084Y212978I-1330J776D01*
G01Y212980D01*
G03X717855Y213788I-1542J-1D01*
G01X717844Y213806D01*
X717821Y213879D01*
G02X717813Y213936I192J56D01*
G01X717805Y214632D01*
X717819Y214684D01*
X717834Y214708D01*
G03X718047Y215478I-1289J771D01*
G03X718043Y215596I-1503J8D01*
G01X718036Y215655D01*
G03X717846Y216227I-1493J-178D01*
G03X717818Y216274I-1304J-745D01*
G01X717798Y216305D01*
X717788Y216322D01*
X717786Y216511D01*
X717722Y222724D01*
G02X717732Y222788I200J2D01*
G01X717741Y222815D01*
X717754Y222834D01*
X717756Y222836D01*
G03X718046Y223723I-1213J887D01*
G01Y223763D01*
G03X718045Y223797I-1502J-27D01*
G01Y223799D01*
G03X717973Y224189I-1500J-75D01*
G03X717938Y224287I-1431J-456D01*
G03X717936Y224291I-179J-87D01*
G01X717935Y224295D01*
G02X717933Y224297I130J132D01*
G03X717790Y224565I-1390J-569D01*
G03X717770Y224594I-1246J-838D01*
G03X717744Y224630I-1231J-861D01*
G01X717743Y224631D01*
G02X717702Y224739I159J122D01*
G01X717697Y225192D01*
G02X717708Y225258I200J1D01*
G01X717717Y225286D01*
X717738Y225313D01*
G03X717755Y225337I-1217J880D01*
G01X717756Y225338D01*
G03X717762Y225346I-1199J906D01*
G03X717807Y225410I-1207J896D01*
G01X717835Y225457D01*
G03X717972Y225758I-1291J769D01*
G01X717988Y225807D01*
G03X717993Y225823I-188J68D01*
G01X718005Y225873D01*
G03X718025Y225972I-1462J347D01*
G03X718046Y226223I-1481J250D01*
G01Y226265D01*
G03X717723Y227157I-1502J-39D01*
G01X717713Y227170D01*
X717686Y227221D01*
X717677Y227261D01*
X717676Y227317D01*
Y227384D01*
X717675Y227386D01*
Y227391D01*
X717673Y227661D01*
G02X717710Y227779I200J2D01*
G01X717717Y227788D01*
G03X718043Y228627I-1173J939D01*
G03X718046Y228710I-1499J96D01*
G01Y228722D01*
G03X717930Y229306I-1502J5D01*
G01Y229307D01*
X717925Y229317D01*
G03X717760Y229608I-1381J-591D01*
G01X717736Y229641D01*
X717718Y229664D01*
G02X717701Y229691I160J120D01*
G01X717697Y229699D01*
G02X717676Y229788I179J89D01*
G01Y229872D01*
G03X717659Y229952I-200J-1D01*
G01X717658Y229955D01*
X717649Y229978D01*
X717647Y230129D01*
G02X717660Y230201I200J1D01*
G01X717671Y230231D01*
X717694Y230259D01*
G03X718043Y231127I-1150J967D01*
G03X717972Y231692I-1499J99D01*
G03X717674Y232218I-1430J-463D01*
G01X717653Y232242D01*
X717650Y232245D01*
X717638Y232278D01*
G02X717625Y232347I187J71D01*
G01X717408Y253607D01*
X717402Y254167D01*
Y269165D01*
G03X717396Y269367I-3892J-15D01*
G01X714308Y328702D01*
X714284Y329171D01*
X714241Y330003D01*
X714152Y331711D01*
X713928Y336016D01*
X713832Y337855D01*
X712957Y354721D01*
Y354723D01*
X712955Y354758D01*
X712964Y354789D01*
G02X712998Y354854I191J-59D01*
G01X713019Y354882D01*
X713077Y354920D01*
X713113Y354928D01*
G03X714590Y356779I-421J1851D01*
G03X712983Y358655I-1899J0D01*
G01X712976Y358656D01*
G02X712921Y358675I37J197D01*
G01X712891Y358691D01*
X712859Y358724D01*
G02X712857Y358726I140J142D01*
G01X712808Y358778D01*
X712806Y358780D01*
X712788Y358800D01*
X712786Y358802D01*
G02X712737Y358914I150J132D01*
G01X712575Y362016D01*
X712490Y363637D01*
X708473Y440810D01*
Y441330D01*
X708481Y441357D01*
X708483Y441365D01*
G02X708519Y441436I193J-53D01*
G01X708544Y441467D01*
X708640Y441519D01*
X708641Y441520D01*
X708720Y441567D01*
X708741Y441580D01*
X708763Y441593D01*
X708826Y441633D01*
G02X708890Y441657I101J-172D01*
G01X708892D01*
G02X708928Y441661I40J-196D01*
G01X708965D01*
X709019Y441652D01*
G02X709062Y441637I-44J-195D01*
G01X709070Y441633D01*
G03X709087Y441623I770J1289D01*
G01X709088D01*
G03X709095Y441619I748J1301D01*
G01X709127Y441603D01*
G03X709779Y441454I652J1353D01*
G01X710579D01*
G03X710777Y441681I-1J200D01*
G01X710773Y441711D01*
X710780Y441758D01*
X710803Y441814D01*
Y441815D01*
X710808Y441828D01*
X710822Y441861D01*
X710830Y441880D01*
X710857Y441908D01*
G03X711283Y442956I-1076J1048D01*
G03X709957Y444448I-1502J0D01*
G01X709873Y444458D01*
G03X709853Y444459I-20J-199D01*
G01X709780D01*
G03X708933Y444197I1J-1503D01*
G01X708908Y444180D01*
X708845Y444160D01*
X708843D01*
X708831Y444154D01*
X708783Y444153D01*
G02X708692Y444173I-4J200D01*
G01X708610Y444213D01*
X708608D01*
X708378Y444328D01*
X708355Y444351D01*
G03X708351Y444355I-134J-130D01*
G01X708320Y444382D01*
X708303Y444417D01*
G02X708283Y444495I180J88D01*
G01X707822Y453350D01*
X707235Y464642D01*
X707233Y464679D01*
X707253Y464739D01*
X707268Y464776D01*
X707275Y464794D01*
X707312Y464851D01*
X707324Y464864D01*
G03X707713Y465864I-1115J1009D01*
G01Y465875D01*
G03X707175Y467027I-1502J0D01*
G01X707174D01*
X707152Y467046D01*
X707141Y467055D01*
X707123Y467090D01*
G02X707103Y467153I178J91D01*
G01X706729Y474341D01*
X706135Y485742D01*
X703510Y536175D01*
X703493Y536510D01*
X703462Y537111D01*
X703390Y538493D01*
X703358Y539102D01*
X703354Y539181D01*
X703259Y541006D01*
X703256Y541063D01*
G02X703351Y541244I200J11D01*
G03X704172Y542712I-902J1468D01*
G03X703241Y544242I-1723J0D01*
G01X703218Y544254D01*
X703158Y544300D01*
G02X703080Y544449I122J159D01*
G01X703078Y544491D01*
X703053Y544966D01*
Y544968D01*
X703050Y545028D01*
X703047Y545080D01*
X703045Y545136D01*
G02X703046Y545169I200J10D01*
G01X703047Y545180D01*
X703053Y545215D01*
X703057Y545232D01*
X703125Y545348D01*
G02X703143Y545370I163J-115D01*
G01X703161Y545388D01*
X703189Y545404D01*
G03X703950Y546711I-743J1307D01*
G01Y546713D01*
G03X703947Y546818I-1502J10D01*
G01Y546820D01*
G03X703862Y547223I-1499J-106D01*
G03X703546Y547738I-1413J-512D01*
G03X703021Y548103I-1101J-1023D01*
G02X702973Y548131I76J185D01*
G01X702919Y548174D01*
Y548175D01*
G02X702889Y548234I161J119D01*
G01X702881Y548267D01*
X702546Y554712D01*
X701196Y580641D01*
X701154Y581451D01*
X700340Y597096D01*
X696737Y666315D01*
X696728Y666491D01*
X696448Y671867D01*
X695682Y686590D01*
X694777Y703984D01*
X693500Y728522D01*
X693454Y729397D01*
Y729454D01*
X693492Y729530D01*
X693521Y729559D01*
G03X693612Y731627I-1044J1082D01*
G03X693479Y731762I-1135J-985D01*
G03X693418Y731814I-1005J-1117D01*
G01X693410Y731821D01*
X693376Y731855D01*
X693359Y731876D01*
G02X693321Y731966I160J120D01*
G01X693244Y733438D01*
X693209Y734107D01*
X693105Y736105D01*
X692619Y745445D01*
X692414Y749389D01*
X692128Y754871D01*
X691983Y757666D01*
X691973Y757862D01*
Y757874D01*
G02X692084Y758052I200J-1D01*
G01X692151Y758086D01*
X692185Y758091D01*
G03X693493Y759581I-195J1490D01*
G03X692056Y761082I-1502J0D01*
G01X692031Y761083D01*
X691999Y761097D01*
G02X691940Y761135I77J185D01*
G01X691853Y761218D01*
G02X691792Y761352I139J144D01*
G01X691790Y761379D01*
X691787Y761436D01*
X691737Y762397D01*
X691722Y762707D01*
G02X691747Y762814I200J10D01*
G01X691765Y762846D01*
X692007Y763070D01*
X692031Y763092D01*
X692090Y763119D01*
X692136Y763124D01*
X692166D01*
X692178Y763123D01*
G03X692356Y763112I181J1491D01*
G01X692357D01*
G03X693858Y764614I-1J1502D01*
G03X692356Y766116I-1502J0D01*
G03X692017Y766077I1J-1502D01*
G01X691974Y766067D01*
X691931Y766076D01*
G02X691918Y766079I38J196D01*
G02X691852Y766112I55J192D01*
G01X691714Y766215D01*
X691701Y766225D01*
X691700Y766226D01*
X691622Y766286D01*
X691604Y766299D01*
G02X691530Y766436I125J156D01*
G01X691262Y771615D01*
Y771616D01*
G02X691337Y771782I200J10D01*
G01X691346Y771789D01*
X691596Y771982D01*
G02X691673Y772016I117J-162D01*
G01X691696Y772020D01*
X691749D01*
X691793Y772009D01*
X691796Y772008D01*
G03X692206Y771947I424J1441D01*
G01X692227D01*
G03X693723Y773449I-6J1502D01*
G03X692221Y774951I-1502J0D01*
G01X692220D01*
G03X692136Y774949I-6J-1502D01*
G01X692133D01*
G03X692120Y774948I109J-1498D01*
G01X692118D01*
G03X691975Y774931I106J-1498D01*
G03X691631Y774830I248J-1481D01*
G01X691601Y774818D01*
X691540Y774812D01*
X691500Y774820D01*
G02X691439Y774846I47J195D01*
G01X691164Y775019D01*
G02X691132Y775045I109J167D01*
G01X691103Y775074D01*
X691074Y775140D01*
X691072Y775178D01*
X691017Y776231D01*
X690966Y777205D01*
Y777207D01*
X690965Y777223D01*
G02X691051Y777398I200J10D01*
G01X691178Y777486D01*
X691180D01*
X691307Y777573D01*
G02X691375Y777603I113J-165D01*
G02X691419Y777608I44J-195D01*
G01X691529D01*
X691567Y777592D01*
G03X692155Y777472I588J1381D01*
G03X693634Y778710I0J1502D01*
G01Y778712D01*
X693641Y778747D01*
X693657Y778775D01*
G02X693690Y778819I175J-97D01*
G01X693708Y778835D01*
X693795Y778910D01*
G02X693906Y778950I120J-160D01*
G01X718897D01*
X718898D01*
G02X719093Y778790I-1J-200D01*
G01X726907Y733916D01*
G02X726839Y733749I-199J-16D01*
G01X726532Y733520D01*
G02X726355Y733498I-111J167D01*
G02X726332Y733507I61J190D01*
G03X725667Y733663I-666J-1346D01*
G03Y730659I0J-1502D01*
G03X726749Y731119I0J1503D01*
G01X726754Y731124D01*
G02X726942Y731175I140J-143D01*
G01X727297Y731066D01*
G02X727431Y730910I-63J-190D01*
G01X736859Y676779D01*
X748415Y610424D01*
X748412Y610417D01*
X748392Y610388D01*
X748349Y610345D01*
G02X748347Y610343I-142J140D01*
G03X747899Y609273I1055J-1071D01*
G01Y609235D01*
X747901Y609204D01*
X747903Y609179D01*
Y609172D01*
G03X747905Y609146I1499J102D01*
G03X748755Y607916I1497J126D01*
G01X748771Y607908D01*
X748825Y607876D01*
X748848Y607846D01*
X748868Y607821D01*
X748918Y607533D01*
X748983Y607160D01*
G02X748984Y607157I-188J-64D01*
G01Y607156D01*
X751502Y587580D01*
X753710Y570416D01*
X754020Y568008D01*
G02X754022Y567984I-198J-29D01*
G01X754069Y563030D01*
X754086Y561260D01*
X754103Y559448D01*
X754325Y535936D01*
X754801Y485503D01*
X755039Y460244D01*
G03X755066Y459816I3891J31D01*
G03X755114Y459517I3864J467D01*
G01X764151Y414360D01*
X764924Y410498D01*
X764931Y410463D01*
X764923Y410411D01*
X764918Y410395D01*
G03X764842Y409924I1426J-472D01*
G01Y409886D01*
G03X765204Y408945I1502J38D01*
G01X765210Y408938D01*
X765218Y408927D01*
G02X765252Y408856I-160J-120D01*
G01X765255Y408844D01*
X765291Y408663D01*
X765343Y408404D01*
X765416Y408040D01*
Y408039D01*
X765436Y407941D01*
Y407939D01*
X765554Y407338D01*
Y407287D01*
X765549Y407264D01*
X765548Y407257D01*
G02X765498Y407173I-192J57D01*
G01X765472Y407147D01*
X765459Y407138D01*
G03X764842Y405924I886J-1214D01*
G03X765990Y404464I1502J0D01*
G01X766018Y404457D01*
X766051Y404438D01*
X766085Y404426D01*
X766129Y404375D01*
G02X766162Y404309I-159J-121D01*
G01X766199Y404127D01*
X766226Y403992D01*
X766229Y403978D01*
X766263Y403808D01*
X766585Y402199D01*
X766612Y402064D01*
X766839Y400930D01*
X766981Y400221D01*
X766988Y400185D01*
X767028Y399986D01*
X767030Y399975D01*
X767039Y399928D01*
X767053Y399851D01*
G02X767008Y399699I-198J-24D01*
G01X766885Y399570D01*
X766787Y399468D01*
X766770Y399451D01*
G02X766629Y399393I-141J142D01*
G01X766595D01*
X766579Y399395D01*
G03X766344Y399414I-238J-1483D01*
G03X764842Y397912I0J-1502D01*
G03X766334Y396410I1502J0D01*
G01X766345D01*
G03X767124Y396628I0J1502D01*
G01X767147Y396642D01*
X767216Y396663D01*
G02X767254Y396668I45J-195D01*
G01X767256D01*
G02X767326Y396658I7J-200D01*
G01X767341Y396652D01*
X767556Y396558D01*
X767632Y396525D01*
G02X767745Y396393I-80J-183D01*
G01X769300Y388632D01*
X771442Y377927D01*
X773024Y370023D01*
X773475Y367769D01*
X775517Y357566D01*
X775697Y356664D01*
X776028Y355009D01*
G02X775934Y354798I-196J-39D01*
G01X775836Y354739D01*
X775834D01*
X775664Y354638D01*
G02X775601Y354616I-97J175D01*
G02X775575Y354614I-28J198D01*
G01X775462D01*
G02X775400Y354624I0J200D01*
G01X775371Y354634D01*
X775341Y354656D01*
X775340Y354657D01*
G03X774420Y354972I-920J-1187D01*
G01X774383D01*
G03X772917Y353470I36J-1502D01*
G03X774419Y351968I1502J0D01*
G03X775750Y352774I0J1502D01*
G01X775764Y352801D01*
X775778Y352816D01*
G02X775944Y352881I148J-134D01*
G01X775973Y352877D01*
X776127Y352855D01*
G02X776201Y352826I-34J-197D01*
G01X776202D01*
G02X776252Y352777I-113J-165D01*
G01X776261Y352764D01*
X776268Y352753D01*
X776272Y352748D01*
G03X776274Y352745I1251J832D01*
G01X776279Y352736D01*
G03X776344Y352636I1291J768D01*
G03X776364Y352608I1232J859D01*
G02X776366Y352606I-139J-141D01*
G03X776403Y352557I1217J881D01*
G03X776407Y352553I143J139D01*
G03X776423Y352534I1157J958D01*
G01X776425Y352532D01*
G03X776430Y352526I1157J959D01*
G01X776435Y352520D01*
G03X776437Y352518I142J140D01*
G03X776449Y352505I1110J1012D01*
G01X776450Y352504D01*
X776509Y352437D01*
X776513Y352433D01*
X776524Y352411D01*
X776551Y352359D01*
X776563Y352336D01*
X776638Y351964D01*
X776704Y351634D01*
X777204Y349128D01*
X777216Y349068D01*
G02X777219Y349035I-197J-35D01*
G01Y348853D01*
G02X777214Y348810I-200J1D01*
G01X777206Y348778D01*
X777193Y348755D01*
G03X776999Y348016I1310J-739D01*
G01Y348015D01*
G03X777600Y346813I1503J0D01*
G01X777621Y346795D01*
X777651Y346765D01*
G02X777693Y346689I-150J-133D01*
G01X779105Y339638D01*
X781134Y329498D01*
X783796Y316081D01*
X788065Y294563D01*
G02X787969Y294364I-198J-27D01*
G01X787645Y294170D01*
G02X787526Y294142I-103J171D01*
G01X787498Y294144D01*
X787441Y294167D01*
X787416Y294188D01*
G03X786463Y294530I-954J-1160D01*
G01X786461D01*
G03Y291526I0J-1502D01*
G03X787786Y292321I0J1502D01*
G01X787793Y292333D01*
G02X787992Y292425I170J-106D01*
G01X788243Y292388D01*
X788372Y292369D01*
G02X788531Y292211I-37J-197D01*
G01X789241Y288632D01*
G02X789237Y288539I-196J-38D01*
G01X789224Y288493D01*
X789190Y288457D01*
G03X788778Y287426I1090J-1033D01*
G01Y287421D01*
G03X789668Y286048I1504J0D01*
G02X789743Y285990I-81J-183D01*
G01X789757Y285973D01*
X789777Y285930D01*
X797220Y248418D01*
G02X797139Y248226I-198J-30D01*
G01X797030Y248154D01*
X796996Y248133D01*
X796988Y248128D01*
X796980Y248122D01*
X796974Y248118D01*
G02X796918Y248095I-103J172D01*
G02X796870Y248089I-49J194D01*
G01X796808D01*
G02X796771Y248093I3J200D01*
G01X796718Y248106D01*
X796698Y248119D01*
X796688Y248126D01*
G03X795857Y248377I-832J-1252D01*
G03X795855I-1J-1503D01*
G03X795798Y248376I-2J-1503D01*
G01X795744Y248372D01*
G03X794363Y247050I111J-1498D01*
G01X794360Y247021D01*
G03X794353Y246874I1495J-145D01*
G03X795826Y245372I1502J0D01*
G01X795858D01*
G03X796187Y245409I-2J1502D01*
G01X796189D01*
X796219Y245416D01*
X796232Y245419D01*
X796252Y245421D01*
X796254D01*
G02X796386Y245388I20J-199D01*
G02X796412Y245367I-112J-166D01*
G01X796662Y245076D01*
G02X796698Y244919I-160J-119D01*
G01X796687Y244878D01*
X796683Y244867D01*
G03X796572Y244300I1392J-567D01*
G01Y244297D01*
G03X796577Y244178I1503J4D01*
G01X796579Y244162D01*
Y244158D01*
G03X798075Y242795I1496J139D01*
G03X798160Y242797I7J1502D01*
G01X798165D01*
G02X798365Y242646I6J-200D01*
G01X798551Y241707D01*
X798861Y240144D01*
G02X798865Y240108I-196J-40D01*
G01X798884Y238905D01*
X798882Y238891D01*
G03X798872Y238715I1492J-173D01*
G01Y238710D01*
G03X798887Y238497I1504J-1D01*
G01X798888Y238491D01*
X798890Y238464D01*
X799010Y230807D01*
X799000Y230763D01*
X798991Y230743D01*
G03X798855Y230117I1367J-625D01*
G03X798856Y230063I1503J1D01*
G01X798860Y230004D01*
G03X799012Y229451I1498J114D01*
G01X799022Y229430D01*
X799032Y229388D01*
X799364Y208112D01*
X799566Y195153D01*
G02X799565Y195138I-200J6D01*
G01X799564Y195131D01*
X794339Y156450D01*
G03X794304Y155981I3891J-526D01*
G01X794303Y155928D01*
X794301Y155787D01*
X794298Y155603D01*
G02X794296Y155577I-200J2D01*
G01X793960Y153273D01*
G03X793920Y152711I3851J-557D01*
G01Y151569D01*
G02X793916Y151527I-200J-2D01*
G01X793913Y151518D01*
G03X793774Y150539I3787J-1037D01*
G01X793745Y148588D01*
Y148587D01*
G03X793744Y148531I3925J-98D01*
G01Y148522D01*
G03X793911Y147398I3927J9D01*
G01X793920Y147368D01*
Y147321D01*
X793914Y147294D01*
X793908Y147270D01*
X793901Y147253D01*
X793900Y147251D01*
G03X793644Y146437I3562J-1568D01*
G03X793576Y145903I3817J-757D01*
G03X793569Y145686I3884J-234D01*
G01Y145676D01*
X793565Y145639D01*
X793557Y145598D01*
G02X793518Y145526I-192J57D01*
G01X793329Y145324D01*
X793294Y145308D01*
X793195Y145261D01*
X793178Y145260D01*
X793159Y145258D01*
G03X791790Y143762I133J-1496D01*
G03X793181Y142264I1502J0D01*
G01X793216Y142261D01*
X793282Y142232D01*
X793311Y142219D01*
G02X793371Y142178I-81J-183D01*
G01X793393Y142156D01*
G02X793450Y142030I-142J-140D01*
G01X793449Y141933D01*
G02X793432Y141913I-161J119D01*
G01X793397Y141880D01*
X793361Y141846D01*
G02X793323Y141821I-128J154D01*
G01X793270Y141798D01*
X793231D01*
G03X793222I-5J-1502D01*
G01X793221D01*
G03X791719Y140296I0J-1502D01*
G01Y140288D01*
G03X791745Y140005I1503J-5D01*
G01X791748Y139991D01*
X791751Y139932D01*
X791753Y139894D01*
G02Y139884I-200J-5D01*
G02X791689Y139744I-200J7D01*
G01X791600Y139722D01*
G03X790458Y139231I960J-3807D01*
G01X790419Y139238D01*
G03X790198Y139259I-252J-1481D01*
G01X790155D01*
G03X788659Y137761I6J-1502D01*
G01Y137759D01*
G03Y137757I1502J-1D01*
G01Y137746D01*
G03X788771Y137189I1502J12D01*
G01X788773Y137183D01*
X788780Y137166D01*
X788806Y137103D01*
X788811Y137081D01*
X788793Y137019D01*
G03X788634Y135946I3768J-1107D01*
G01Y135902D01*
G03X788975Y134315I3927J14D01*
G02X788987Y134277I-184J-79D01*
G01X789001Y134217D01*
G02Y134213I-200J-2D01*
G01X788987Y134153D01*
G02X788975Y134115I-196J41D01*
G03X788634Y132515I3586J-1601D01*
G01Y132513D01*
G03X788667Y132006I3927J1D01*
G03X788740Y131609I3894J511D01*
G03X788811Y131351I3819J912D01*
G01X788804Y131320D01*
X788795Y131298D01*
G03X788661Y130760I1366J-626D01*
G01Y130743D01*
G03X788659Y130670I1500J-78D01*
G01Y130640D01*
G03X790161Y129168I1502J30D01*
G01X790162D01*
G03X790389Y129185I2J1502D01*
G02X790523Y129159I31J-197D01*
G03X792561Y128588I2039J3356D01*
G01X792562D01*
G03X794599Y129158I-1J3927D01*
G02X794732Y129185I104J-171D01*
G03X794965Y129168I225J1485D01*
G01X794968D01*
G03X795428Y129242I-6J1501D01*
G01X795482Y129260D01*
X795527Y129256D01*
G02X795640Y129208I-18J-200D01*
G01X795717Y129152D01*
X795887Y129028D01*
G02X795937Y128969I-125J-156D01*
G01X795935Y128888D01*
Y128887D01*
G03X795934Y128829I3925J-97D01*
G01Y128822D01*
G03X795935Y128728I3927J-5D01*
G03X796276Y127225I3926J100D01*
G01X796283Y127209D01*
X796301Y127130D01*
G02Y127126I-200J-2D01*
G01X796283Y127047D01*
X796276Y127031D01*
G03X795935Y125528I3585J-1603D01*
G03X795934Y125434I3926J-89D01*
G01Y125427D01*
G03X795935Y125367I3926J35D01*
G01Y125356D01*
X795937Y125282D01*
G02X795889Y125227I-172J102D01*
G01X795711Y125097D01*
X795709D01*
X795633Y125042D01*
G02X795538Y125008I-113J165D01*
G01X795536D01*
G02X795520Y125007I-20J199D01*
G01X795443D01*
X795413Y125016D01*
G03X794967Y125086I-453J-1432D01*
G01X794959D01*
G03X794704Y125064I1J-1502D01*
G01X794665Y125057D01*
G03X792561Y125668I-2103J-3315D01*
G03X790512Y125092I-2J-3926D01*
G02X790417Y125068I-95J176D01*
G01X790393D01*
X790379Y125070D01*
X790375Y125071D01*
X790370D01*
G03X790300Y125080I-226J-1485D01*
G03X790279Y125082I-153J-1494D01*
G01X790275D01*
X790267Y125083D01*
X790263D01*
G03X790184Y125086I-96J-1499D01*
G01X790161D01*
G03X788659Y123584I0J-1502D01*
G01Y123573D01*
G03X788771Y123016I1502J12D01*
G01X788773Y123010D01*
X788780Y122993D01*
X788806Y122930D01*
X788811Y122908D01*
X788793Y122846D01*
G03X788634Y121750I3768J-1106D01*
G01Y121715D01*
G03X788738Y120844I3927J27D01*
G03X788976Y120139I3823J898D01*
G01X788983Y120123D01*
X789001Y120044D01*
G02Y120040I-200J-2D01*
G01X788983Y119961D01*
X788976Y119945D01*
G03X788634Y118342I3585J-1603D01*
G03X788693Y117663I3927J-1D01*
G03X788773Y117307I3867J682D01*
G03X788812Y117175I3785J1046D01*
G01X788805Y117146D01*
G03X788659Y116499I1357J-646D01*
G01Y116497D01*
G03X790161Y114995I1502J0D01*
G01X790164D01*
G03X790441Y115021I-1J1502D01*
G01X790457Y115024D01*
X790460Y115025D01*
G03X792561Y114416I2100J3317D01*
G03X794661Y115024I1J3926D01*
G01X794665Y115023D01*
X794679Y115021D01*
G03X794960Y114995I278J1476D01*
G01X794964D01*
G03X795359Y115048I0J1502D01*
G01X795366Y115050D01*
X795371Y115051D01*
X795386Y115055D01*
X795441Y115073D01*
X795443D01*
X795464Y115081D01*
X795514Y115086D01*
X795537Y115083D01*
G02X795579Y115072I-29J-198D01*
G02X795627Y115046I-70J-187D01*
G01X795875Y114865D01*
G02X795878Y114863I-110J-168D01*
G01X795897Y114849D01*
G02X795923Y114824I-125J-156D01*
G02X795937Y114805I-154J-128D01*
G01X795935Y114716D01*
Y114715D01*
G03X795934Y114656I3925J-96D01*
G01Y114649D01*
G03X795935Y114555I3927J-5D01*
G03X796276Y113052I3926J100D01*
G01X796283Y113036D01*
X796301Y112957D01*
G02Y112953I-200J-2D01*
G01X796283Y112874D01*
X796276Y112858D01*
G03X795934Y111255I3585J-1603D01*
G03X795993Y110576I3927J-1D01*
G03X796073Y110221I3867J685D01*
G01Y110219D01*
G03X796101Y110126I3773J1085D01*
G01Y110124D01*
G03X796112Y110088I3761J1129D01*
G01X796105Y110059D01*
X796096Y110040D01*
G03X795961Y109500I1365J-628D01*
G01Y109483D01*
G03X795959Y109410I1500J-78D01*
G01Y109380D01*
G03X797461Y107908I1502J30D01*
G03X797737Y107932I8J1503D01*
G01X797745Y107934D01*
G03X797762Y107937I-253J1481D01*
G03X797931Y107835I2113J3310D01*
G03X797935Y107833I91J178D01*
G03X797948Y107826I1868J3454D01*
G01X798017Y107787D01*
G02X798022Y107776I-179J-88D01*
G03X798024Y107770I190J60D01*
G02X798026Y107766I-177J-91D01*
G01X798109Y107462D01*
X798108Y107408D01*
X798101Y107382D01*
X798084Y107321D01*
X798072Y107300D01*
G03X797878Y106562I1308J-738D01*
G01Y106526D01*
X797879Y106510D01*
Y106507D01*
G03X797888Y106388I1501J54D01*
G03X798055Y105854I1492J173D01*
G03X798453Y105379I1325J706D01*
G01X798461Y105373D01*
X798489Y105346D01*
X798540Y105284D01*
X798550Y105263D01*
X798560Y105217D01*
X798544Y104911D01*
X798542Y104862D01*
X798483Y104761D01*
G02X798452Y104720I-174J99D01*
G01X798423Y104691D01*
X798391Y104664D01*
X798382Y104658D01*
G03X797718Y103411I839J-1247D01*
G03X800724I1503J0D01*
G03X800129Y104609I-1504J0D01*
G01X800116Y104619D01*
X800101Y104634D01*
X800077Y104665D01*
G02X800044Y104771I167J110D01*
G01X800059Y105105D01*
X800078Y105142D01*
X800082Y105151D01*
X800132Y105235D01*
X800149Y105252D01*
X800193Y105297D01*
X800218Y105314D01*
G03X800882Y106557I-838J1247D01*
G01Y106575D01*
G03X800803Y107043I-1502J-13D01*
G01X800800Y107052D01*
X800790Y107084D01*
X800794Y107128D01*
G02X800803Y107172I199J-18D01*
G02X800806Y107179I185J-75D01*
G01X800865Y107301D01*
G02X800867Y107303I135J-133D01*
G01X800898Y107365D01*
X800955Y107476D01*
G02X800962Y107485I161J-118D01*
G01X801013Y107501D01*
X801039Y107509D01*
G03X801409Y107646I-1177J3746D01*
G03X801882Y107888I-1548J3609D01*
G02X802003Y107916I103J-171D01*
G03X802018Y107914I206J1487D01*
G01X802024D01*
X802036Y107912D01*
X802040D01*
X802043Y107911D01*
G03X802082Y107909I96J1500D01*
G01X802088D01*
G03X802121Y107907I107J1499D01*
G01X802145D01*
G03X802161I8J1503D01*
G03X802237Y107909I-2J1503D01*
G01X802275Y107912D01*
G03X803280Y108407I-113J1498D01*
G01X803281Y108408D01*
G02X803429Y108474I148J-134D01*
G01X803587D01*
G03X806363Y109624I0J3926D01*
G01X816366Y119627D01*
G03X817208Y120879I-2776J2776D01*
G01X817704Y122054D01*
X817714Y122069D01*
G03X818064Y122728I-3247J2147D01*
G01X820733Y129169D01*
X820748Y129206D01*
X820774Y129233D01*
G02X820830Y129274I144J-138D01*
G01X820842Y129279D01*
G03X820874Y129293I-586J1384D01*
G01X820880Y129296D01*
G03X821773Y130640I-609J1374D01*
G01Y130715D01*
G03X821770Y130774I-1502J-47D01*
G01Y130776D01*
X821766Y130841D01*
G03X821763Y130863I-199J-16D01*
G01X821761Y130877D01*
Y130879D01*
G03X821670Y131219I-1488J-216D01*
G01X821657Y131250D01*
X821648Y131289D01*
G02X821660Y131410I196J42D01*
G01X821928Y132057D01*
X822527Y133501D01*
Y133503D01*
X827808Y146040D01*
G03X828045Y146820I-3618J1525D01*
G01X828479Y149068D01*
G03X828550Y149812I-3855J743D01*
G03X828527Y150245I-3926J9D01*
G01X828526Y150250D01*
X828275Y152484D01*
X828157Y153534D01*
G02X828156Y153556I199J20D01*
G01Y154606D01*
G03X828126Y155086I-3892J-2D01*
G03X828109Y155208I-3862J-476D01*
G03X828093Y155301I-3843J-613D01*
G03X828076Y155387I-3826J-712D01*
G01X827799Y156744D01*
G02X827796Y156762I195J42D01*
G01X827693Y157677D01*
X827681Y157783D01*
G03X827622Y158150I-3902J-439D01*
G01X827092Y160681D01*
X827094Y160683D01*
X827129Y160714D01*
X827360Y160916D01*
X827362Y160917D01*
X827371Y160925D01*
X827405Y160938D01*
G02X827412Y160941I82J-182D01*
G02X827429Y160946I65J-189D01*
G01X827431D01*
G02X827445Y160949I49J-194D01*
G03X828050Y160825I606J1419D01*
G01X828051D01*
G03X829188Y161325I0J1543D01*
G02X829211Y161326I20J-199D01*
G01X829491D01*
G02X829514Y161325I3J-200D01*
G03X830651Y160825I1137J1043D01*
G03Y163911I0J1543D01*
G03X829514Y163411I0J-1543D01*
G02X829491Y163410I-20J199D01*
G01X829211D01*
G02X829188Y163411I-3J200D01*
G03X828051Y163911I-1137J-1043D01*
G03X826942Y163441I0J-1543D01*
G01X826919Y163437D01*
G02X826852Y163436I-36J197D01*
G01X826806Y163445D01*
X826680Y163486D01*
X826609Y163509D01*
X826499Y163545D01*
G02X826492Y163548I75J185D01*
G01X826347Y164243D01*
X826071Y165561D01*
X822219Y183960D01*
X821448Y187720D01*
X820039Y194595D01*
G02X820036Y194627I197J35D01*
G01Y206876D01*
X820043Y206923D01*
G02X820051Y206955I197J-32D01*
G01X820056Y206968D01*
X820066Y206998D01*
G02X820071Y207009I184J-77D01*
G01X820091Y207050D01*
X820097Y207061D01*
G02X820099Y207063I141J-139D01*
G03X820106Y207073I-1227J867D01*
G01X820114Y207081D01*
G03X820117Y207084I-1054J1057D01*
G01X820146Y207128D01*
X820147Y207130D01*
X820152Y207138D01*
G03X820235Y207276I-1245J842D01*
G03X820264Y207334I-1330J701D01*
G02X820266Y207337I166J-108D01*
G01Y207338D01*
X820268Y207342D01*
G03X820409Y207978I-1364J636D01*
G01Y207980D01*
G03X820323Y208481I-1503J0D01*
G01X820321Y208486D01*
X820295Y208566D01*
G03X820278Y208604I-190J-62D01*
G01X820228Y208692D01*
X820227Y208695D01*
G03X820209Y208727I-1319J-721D01*
G01X820207Y208730D01*
G03X820176Y208781I-1299J-755D01*
G03X820080Y208916I-1271J-802D01*
G01X820058Y208944D01*
X820047Y208974D01*
G02X820038Y209013I189J64D01*
G01Y209015D01*
G02X820036Y209039I198J29D01*
G01Y209380D01*
G02X820045Y209440I200J1D01*
G01X820080Y209540D01*
X820100Y209566D01*
G03X820091Y211403I-1194J913D01*
G01X820084Y211412D01*
X820079Y211418D01*
X820057Y211459D01*
G02X820036Y211539I179J90D01*
G01Y211880D01*
G02X820045Y211940I200J1D01*
G01X820080Y212040D01*
X820100Y212066D01*
G03X820091Y213903I-1194J913D01*
G01X820084Y213912D01*
X820079Y213918D01*
X820057Y213959D01*
G02X820036Y214039I179J90D01*
G01Y214416D01*
G02X820047Y214481I200J0D01*
G01X820058Y214513D01*
X820080Y214540D01*
G03X820408Y215477I-1174J937D01*
G01Y215510D01*
G03X820100Y216390I-1502J-32D01*
G01X820080Y216416D01*
X820045Y216516D01*
G02X820036Y216576I191J59D01*
G01Y220171D01*
X820037Y220185D01*
Y220210D01*
G03X820038Y220274I-3892J93D01*
G01Y220276D01*
G03Y220279I-200J1D01*
G03X820037Y220340I-3892J-33D01*
G01Y220365D01*
X820036Y220368D01*
X820005Y221720D01*
X819988Y222445D01*
X819985Y222569D01*
G02X819998Y222642I200J2D01*
G01X820033Y222732D01*
X820055Y222758D01*
G03X820408Y223725I-1149J967D01*
G01Y223754D01*
X820407Y223789D01*
G03X819987Y224769I-1501J-63D01*
G01X819961Y224796D01*
X819953Y224814D01*
X819946Y224831D01*
X819945Y224832D01*
G02X819930Y224892I185J78D01*
G01X819927Y225035D01*
X819926Y225076D01*
X819955Y225150D01*
X819983Y225179D01*
G03X820408Y226225I-1077J1047D01*
G01Y226230D01*
G03X820407Y226293I-1502J8D01*
G01X820406Y226310D01*
Y226312D01*
G03X820258Y226881I-1500J-86D01*
G01X820233Y226933D01*
X820215Y226964D01*
X820214Y226965D01*
X820201Y226987D01*
G03X819944Y227312I-1295J-760D01*
G01X819929Y227328D01*
X819922Y227336D01*
G02X819881Y227422I155J126D01*
G01X819869Y227475D01*
Y227485D01*
X819930Y227626D01*
X819958Y227654D01*
G03X820408Y228726I-1052J1072D01*
G03X820395Y228926I-1502J3D01*
G01X820394Y228937D01*
G03X820156Y229560I-1488J-211D01*
G01X820134Y229592D01*
X820122Y229609D01*
X820098Y229642D01*
X820081Y229662D01*
G02X820063Y229691I161J120D01*
G01X820059Y229699D01*
G02X820038Y229788I179J89D01*
G01Y229871D01*
G03X820020Y229954I-200J0D01*
G01X819996Y230007D01*
G02X820021Y230215I181J84D01*
G01X820043Y230243D01*
X820057Y230261D01*
X820059Y230264D01*
X820065Y230271D01*
G03X820408Y231216I-1159J955D01*
G01Y231224D01*
G03Y231227I-1502J2D01*
G01Y231229D01*
G03X819827Y232413I-1502J-2D01*
G01X819826D01*
G02X819771Y232481I124J157D01*
G01X819761Y232501D01*
X819750Y232543D01*
X819589Y239405D01*
G03X819507Y240117I-3891J-87D01*
G01Y240119D01*
X819450Y240403D01*
X819449Y240404D01*
X819393Y240685D01*
X819143Y241935D01*
G02X819141Y241945I195J44D01*
G03X819107Y242142I-3885J-569D01*
G01X807385Y301223D01*
X807395Y301258D01*
X807396Y301261D01*
Y301262D01*
X807398Y301269D01*
G03X807454Y301661I-1446J407D01*
G01Y301687D01*
G03X807403Y302064I-1502J-11D01*
G03X807145Y302588I-1452J-389D01*
G01X807134Y302603D01*
X807105Y302665D01*
G02X807090Y302711I181J85D01*
G01X805059Y312949D01*
X802563Y325528D01*
X802567Y325547D01*
G03X802570Y325561I-1467J322D01*
G01X802571Y325567D01*
G03X802599Y325858I-1474J289D01*
G01Y325887D01*
G03X802487Y326428I-1502J-29D01*
G03X802358Y326676I-1392J-566D01*
G01X802348Y326692D01*
X802326Y326744D01*
G02X802314Y326783I184J78D01*
G01X801251Y332142D01*
G02X801247Y332181I196J40D01*
G01Y332486D01*
X801269Y332520D01*
G03X801531Y333367I-1242J848D01*
G01Y333368D01*
G03X800800Y334657I-1502J0D01*
G01X800782Y334668D01*
X800761Y334699D01*
G02X800729Y334774I164J114D01*
G01X800538Y335737D01*
G02X800536Y335754I197J32D01*
G01X800535Y335767D01*
G02X800666Y335956I200J1D01*
G01X800667D01*
G03X801657Y337368I-512J1412D01*
G03X800156Y338870I-1502J0D01*
G01X800154D01*
G03X800089Y338869I-9J-1502D01*
G02X799957Y338911I-9J200D01*
G01X799929Y338934D01*
X799892Y338994D01*
X799297Y341990D01*
G02X799333Y342143I197J34D01*
G02X799340Y342151I154J-128D01*
G01X799341Y342152D01*
G02X799409Y342205I154J-128D01*
G01X799449Y342224D01*
X815661D01*
G03X815803Y342283I0J200D01*
G01X816770Y343250D01*
G02X816876Y343304I140J-143D01*
G01X816878D01*
G02X816910Y343307I35J-197D01*
G01X839948D01*
G02X839986Y343303I-2J-200D01*
G02X840088Y343250I-37J-196D01*
G01X841781Y341557D01*
G02X841834Y341455I-143J-139D01*
G02X841838Y341417I-196J-40D01*
G01Y326446D01*
G02X841813Y326349I-200J0D01*
G01X841797Y326326D01*
G02X841758Y326286I-161J118D01*
G01X841739Y326271D01*
X841709Y326259D01*
G03X840738Y324854I531J-1405D01*
G03X840751Y324654I1502J-3D01*
G03X840924Y324128I1490J198D01*
G01X840934Y324109D01*
Y315073D01*
G03X841316Y314151I1306J1D01*
G01X872087Y283380D01*
G03X873009Y282998I923J924D01*
G01X874832D01*
G02X874869Y282995I2J-200D01*
G02X874973Y282940I-37J-197D01*
G01X879515Y278397D01*
G02X879518Y278367I-197J-35D01*
G01Y266275D01*
G02X879496Y266184I-200J0D01*
G02X879460Y266134I-178J90D01*
G01X878479Y265153D01*
G03X878096Y264229I923J-924D01*
G01Y261145D01*
G03X878479Y260221I1306J0D01*
G01X881489Y257211D01*
G02X881542Y257109I-143J-139D01*
G02X881546Y257071I-196J-40D01*
G01Y252199D01*
G03X881552Y252079I1306J5D01*
G03X881581Y251902I1301J122D01*
G01X881586Y251879D01*
Y250908D01*
G03X881957Y250012I1267J0D01*
G01X884891Y247078D01*
G02X884945Y246972I-143J-140D01*
G01Y246970D01*
G02X884948Y246938I-197J-35D01*
G01Y236526D01*
X884945Y236509D01*
G03X884938Y236468I2270J-409D01*
G01Y236466D01*
G03X884908Y236101I2277J-371D01*
G01Y210526D01*
G03X885584Y208895I2307J1D01*
G01X897209Y197271D01*
G02X897262Y197169I-143J-139D01*
G02X897266Y197131I-196J-40D01*
G01Y158195D01*
G03X901880I2307J0D01*
G01Y198170D01*
G03X901204Y199801I-2307J-1D01*
G01X889580Y211424D01*
G02X889544Y211474I142J140D01*
G02X889522Y211565I178J91D01*
G01Y230456D01*
G02X889527Y230463I165J-113D01*
G01X889698Y230634D01*
X890884Y231821D01*
G02X890989Y231874I139J-144D01*
G01X890991D01*
G02X891023Y231877I35J-197D01*
G01X892139D01*
G02X892191Y231870I0J-200D01*
G01X892238Y231856D01*
G02X892262Y231847I-58J-192D01*
G01X892301Y231829D01*
G03X893270Y231538I982J1511D01*
G01X893284D01*
G03X893430Y231544I-1J1802D01*
G02X893446Y231543I-4J-200D01*
G01X893450D01*
G03X893578Y231538I134J1797D01*
G01X893580D01*
G03X895382Y233340I0J1802D01*
G01Y235829D01*
X895383Y236740D01*
G03X893847Y238525I-1805J0D01*
G01X893846D01*
X893834Y238527D01*
X893807Y238534D01*
X893787Y238542D01*
X893749Y238558D01*
G02X893703Y238586I80J183D01*
G01X893628Y238646D01*
X893612Y238669D01*
X893594Y238693D01*
X893537Y238854D01*
Y238856D01*
X893494Y238980D01*
G02X893485Y239039I191J59D01*
G01Y239082D01*
G02X893487Y239112I200J2D01*
G01X895081Y240705D01*
X895175Y240799D01*
G03X895743Y241734I-1631J1631D01*
G01X895744Y241735D01*
G02X895801Y241780I150J-132D01*
G01X895811Y241785D01*
G02X895909Y241807I91J-178D01*
G03X896034Y241802I123J1500D01*
G01X896035D01*
G03X896183Y241809I3J1505D01*
G01X896192Y241810D01*
X896213D01*
X896220Y241809D01*
G03X896327Y241805I110J1498D01*
G01X896352D01*
G03X897832Y243307I-22J1502D01*
G03X896591Y244786I-1502J0D01*
G01X896590D01*
X896573Y244789D01*
G03X896506Y244799I-255J-1480D01*
G01X896505D01*
X896490Y244801D01*
X896489D01*
X896428Y244808D01*
G03X896408Y244809I-20J-199D01*
G01X896328D01*
G03X896233Y244806I0J-1502D01*
G01X896216D01*
G02X896113Y244837I4J200D01*
G02X896087Y244858I112J165D01*
G01X895873Y245060D01*
G02X895850Y245086I138J145D01*
G01Y247810D01*
Y247811D01*
Y247813D01*
G03X895848Y247923I-2306J13D01*
G01X895849Y247925D01*
X895902Y247967D01*
G02X895962Y247999I123J-158D01*
G03X897627Y250186I-604J2187D01*
G01Y251820D01*
X897629Y251830D01*
Y251832D01*
X897630Y251836D01*
X897631Y251842D01*
G03X897634Y251859I-2269J409D01*
G03X897666Y252248I-2274J383D01*
G01Y253853D01*
G03X896991Y255483I-2306J0D01*
G01X896837Y255637D01*
G02X896791Y255848I141J141D01*
G01X896839Y255963D01*
X896859Y255971D01*
X896880Y255979D01*
X896981Y255978D01*
X897004D01*
G03X897134Y255983I7J1502D01*
G01X897145Y255984D01*
G02X897157I6J-200D01*
G01X897168Y255983D01*
G03X897297Y255978I123J1497D01*
G01X897300D01*
G03Y258982I0J1502D01*
G03X897169Y258977I-8J-1504D01*
G01X897158Y258976D01*
G02X897146I-6J200D01*
G01X897135Y258977D01*
G03X897004Y258982I-123J-1497D01*
G03X895502Y257480I0J-1502D01*
G01Y257459D01*
X895503Y257397D01*
X895434Y257294D01*
X895405Y257282D01*
X895404D01*
X895324Y257250D01*
G02X895271Y257240I-63J190D01*
G02X895232Y257242I-9J200D01*
G01X893416Y259058D01*
Y259104D01*
X893429Y259213D01*
Y259215D01*
X893456Y259431D01*
G02X893459Y259442I194J-47D01*
G01X893462Y259452D01*
G02X893496Y259521I193J-52D01*
G01X893518Y259550D01*
X893551Y259570D01*
G03X894282Y260860I-773J1290D01*
G03X894269Y261060I-1502J3D01*
G03X893454Y262203I-1489J-200D01*
G03X893344Y262253I-676J-1342D01*
G01X893307Y262268D01*
X893196Y262379D01*
G02X893182Y262452I186J73D01*
G01Y275789D01*
G02X893185Y275821I200J-3D01*
G01Y275823D01*
G02X893239Y275929I197J-34D01*
G01X896767Y279457D01*
G02X896869Y279510I139J-143D01*
G02X896907Y279514I40J-196D01*
G01X907191D01*
G02X907384Y279366I0J-200D01*
G01X907473Y278979D01*
G02X907476Y278961I-195J-42D01*
G02X907364Y278754I-198J-27D01*
G03X911356I1996J-4147D01*
G01X911355Y278755D01*
G02X911262Y278848I87J180D01*
G01X911247Y278878D01*
X911240Y278944D01*
X911334Y279358D01*
G02X911342Y279385I195J-43D01*
G02X911528Y279514I187J-71D01*
G01X912839D01*
G02X912877Y279510I-2J-200D01*
G02X912979Y279457I-37J-196D01*
G01X915089Y277347D01*
G02X915142Y277245I-143J-139D01*
G02X915146Y277207I-196J-40D01*
G01Y168717D01*
X915137Y168700D01*
G03X914951Y167981I1316J-724D01*
G01Y167945D01*
G03X917953Y167903I1502J30D01*
G03X917955Y167968I-1500J79D01*
G01Y167976D01*
G03X917769Y168700I-1502J0D01*
G01X917760Y168717D01*
Y239838D01*
G02X917827Y239895I160J-120D01*
G01X917840Y239901D01*
X917938Y239938D01*
X917940D01*
X918134Y240011D01*
G03X918158Y240022I-71J187D01*
G01X918184Y240037D01*
X918204Y240042D01*
G02X918265Y240048I50J-193D01*
G01X918294Y240047D01*
G02X918416Y239985I-24J-199D01*
G01X918430Y239970D01*
X918440Y239960D01*
X918452Y239944D01*
G03X919572Y239443I1121J1004D01*
G01X919573D01*
G03X919578I3J1502D01*
G03X919685Y239447I-3J1502D01*
G01X919687D01*
G03X919709Y239449I-125J1497D01*
G01X919725Y239450D01*
X919733D01*
G03X919868Y239443I145J1495D01*
G01X919874D01*
G03Y242447I-1J1502D01*
G01X919868D01*
G03X919725Y242440I2J-1502D01*
G01X919722D01*
G03X919572Y242447I-145J-1495D01*
G01X919494D01*
G03X919470Y242446I-4J-200D01*
G01X919424Y242440D01*
X919421D01*
G03X918915Y242295I154J-1494D01*
G03X918449Y241941I658J-1350D01*
G01X918444Y241936D01*
X918421Y241910D01*
X918412Y241901D01*
G02X918214Y241851I-141J142D01*
G01X917939Y241952D01*
X917866Y241979D01*
G02X917864Y241980I87J176D01*
G01X917854Y241983D01*
X917835Y241990D01*
G02X917830Y241993I100J172D01*
G01X917828D01*
G02X917761Y242049I92J178D01*
G01X917760Y242050D01*
Y249287D01*
G02X917827Y249344I160J-120D01*
G01X917840Y249350D01*
X917938Y249387D01*
X917940D01*
X918134Y249460D01*
G03X918158Y249471I-71J187D01*
G01X918184Y249486D01*
X918204Y249491D01*
G02X918265Y249497I50J-193D01*
G01X918294Y249496D01*
G02X918416Y249434I-24J-199D01*
G01X918430Y249419D01*
X918440Y249409D01*
X918452Y249393D01*
G03X919572Y248892I1121J1004D01*
G01X919573D01*
G03X919578I3J1502D01*
G03X919685Y248896I-3J1502D01*
G01X919687D01*
G03X919709Y248898I-125J1497D01*
G01X919725Y248899D01*
X919733D01*
G03X919868Y248892I145J1495D01*
G01X919874D01*
G03Y251896I-1J1502D01*
G01X919868D01*
G03X919725Y251889I2J-1502D01*
G01X919722D01*
G03X919572Y251896I-145J-1495D01*
G01X919494D01*
G03X919470Y251895I-4J-200D01*
G01X919424Y251889D01*
X919421D01*
G03X918915Y251744I154J-1494D01*
G03X918449Y251390I658J-1350D01*
G01X918444Y251385D01*
X918420Y251358D01*
X918412Y251350D01*
G02X918337Y251303I-141J142D01*
G01X918238D01*
G02X918203Y251306I0J200D01*
G02X918170Y251315I36J197D01*
G01X917847Y251435D01*
G02X917803Y251459I73J186D01*
G02X917760Y251502I118J161D01*
G01Y263460D01*
G02X917827Y263517I160J-120D01*
G01X917840Y263523D01*
X917938Y263560D01*
X917940D01*
X918134Y263633D01*
G03X918158Y263644I-71J187D01*
G01X918184Y263659D01*
X918204Y263664D01*
G02X918265Y263670I50J-193D01*
G01X918294Y263669D01*
G02X918416Y263607I-24J-199D01*
G01X918430Y263592D01*
X918440Y263582D01*
X918452Y263566D01*
G03X919572Y263065I1121J1004D01*
G01X919573D01*
G03X919578I3J1502D01*
G03X919685Y263069I-3J1502D01*
G01X919687D01*
G03X919709Y263071I-125J1497D01*
G01X919725Y263072D01*
X919733D01*
G03X919868Y263065I145J1495D01*
G01X919874D01*
G03X921375Y264567I-1J1502D01*
G03X919873Y266069I-1502J0D01*
G03X919743Y266063I4J-1502D01*
G01X919724Y266062D01*
X919695Y266065D01*
G03X918433Y265546I-122J-1498D01*
G01X918428Y265540D01*
X918412Y265524D01*
G02X918314Y265470I-142J141D01*
G02X918202Y265478I-42J196D01*
G01X917939Y265574D01*
X917866Y265601D01*
G02X917864Y265602I87J176D01*
G01X917854Y265605D01*
X917835Y265612D01*
G02X917830Y265615I100J172D01*
G01X917828D01*
G02X917761Y265671I92J178D01*
G01X917760Y265672D01*
Y267408D01*
G02X917782Y267433I161J-119D01*
G02X917845Y267473I137J-146D01*
G01X918214Y267601D01*
G02X918276Y267612I66J-189D01*
G01X918305D01*
X918334Y267604D01*
X918363Y267595D01*
X918414Y267561D01*
X918435Y267534D01*
G03X918442Y267525I1189J917D01*
G03X918446Y267520I158J122D01*
G03X918634Y267325I1171J941D01*
G01X918661Y267301D01*
X918679Y267288D01*
G03X918781Y267213I940J1171D01*
G01X918782Y267212D01*
G03X919662Y266934I879J1251D01*
G01X919663D01*
G03X919910Y266954I1J1528D01*
G01X919931Y266957D01*
X919953Y266960D01*
X919962D01*
G03X921414Y268462I-51J1502D01*
G03X920469Y269857I-1502J0D01*
G01X920454Y269863D01*
G02X920343Y270042I89J179D01*
G01Y270052D01*
G03Y270057I-200J2D01*
G01X920342Y270080D01*
G02X920369Y270189I200J8D01*
G01X920378Y270202D01*
G02X920380Y270205I167J-109D01*
G01X920381Y270206D01*
X920387Y270215D01*
G02X920414Y270243I157J-124D01*
G01X920433Y270259D01*
X920451Y270267D01*
X920465Y270273D01*
G03X921375Y271654I-593J1381D01*
G03X919873Y273156I-1502J0D01*
G03X919743Y273150I4J-1502D01*
G01X919724Y273149D01*
X919695Y273152D01*
G03X918433Y272633I-122J-1498D01*
G01X918428Y272627D01*
X918412Y272611D01*
G02X918314Y272557I-142J141D01*
G02X918202Y272565I-42J196D01*
G01X917939Y272661D01*
X917866Y272688D01*
G02X917864Y272689I87J176D01*
G01X917854Y272692D01*
X917835Y272699D01*
G02X917830Y272702I100J172D01*
G01X917828D01*
G02X917761Y272758I92J178D01*
G01X917760Y272759D01*
Y277831D01*
G03X917754Y277951I-1306J-5D01*
G03X917725Y278128I-1301J-122D01*
G01X917720Y278151D01*
Y310420D01*
G02X917723Y310452I200J-3D01*
G01Y310454D01*
G02X917777Y310560I197J-34D01*
G01X921216Y313999D01*
G03X921511Y314463I-896J895D01*
G01X921521Y314493D01*
X921536Y314534D01*
G03X921543Y314556I-187J72D01*
G01X921544Y314561D01*
G03X921578Y314744I-1226J322D01*
G01Y314746D01*
G03X921584Y314811I-1258J149D01*
G01Y314813D01*
G03X921585Y314829I-1263J87D01*
G01Y314832D01*
G03X921586Y314892I-1265J51D01*
G01Y323357D01*
G03X921582Y323457I-1266J-1D01*
G03X921480Y323864I-1262J-100D01*
G01X921465Y323898D01*
X921456Y323916D01*
X921447Y323935D01*
X921446Y323938D01*
X921440Y323950D01*
X921412Y323997D01*
X921411Y323998D01*
X921402Y324013D01*
X921401Y324014D01*
X921398Y324018D01*
X921394Y324025D01*
G03X921307Y324148I-1076J-669D01*
G03X921216Y324250I-989J-791D01*
G01X919742Y325724D01*
G02X919706Y325774I142J140D01*
G02X919684Y325865I178J91D01*
G01Y327041D01*
X919685Y328217D01*
G03X917878Y330020I-1803J0D01*
G03X916608Y329493I4J-1803D01*
G01X916601Y329486D01*
X916586Y329470D01*
G03X916581Y329465I1272J-1277D01*
G03X916579Y329463I140J-142D01*
G02X916438Y329402I-144J139D01*
G01X916437D01*
X916152Y329399D01*
G02X916009Y329457I-2J200D01*
G01X913611Y331855D01*
G02X913557Y331956I142J141D01*
G01Y332036D01*
X913561Y332054D01*
G03X913587Y332329I-1476J278D01*
G01Y332339D01*
G03X912085Y333837I-1502J-4D01*
G01X912084D01*
G03X911353Y333647I0J-1502D01*
G01X911334Y333636D01*
X911272Y333617D01*
G02X911215Y333609I-56J192D01*
G01X907800D01*
X907731Y333636D01*
X907716Y333650D01*
X907707Y333659D01*
G03X907565Y333718I-142J-141D01*
G01X906709D01*
G02X906509Y333918I0J200D01*
G01Y342152D01*
G03X906356Y342346I-199J0D01*
G02X906262Y342399I48J194D01*
G01X906248Y342413D01*
X906218Y342486D01*
Y346486D01*
G03X905835Y347410I-1306J0D01*
G01X904501Y348743D01*
G02X904444Y348854I141J142D01*
G02X904442Y348885I198J28D01*
G01Y353471D01*
G02X904450Y353528I200J1D01*
G02X904527Y353635I192J-57D01*
G01X904794Y353823D01*
G02X904910Y353860I116J-163D01*
G01X904975Y353848D01*
X904991Y353843D01*
G03X905483Y353760I492J1419D01*
G03X906984Y355200I0J1502D01*
G02X907015Y355299I200J-8D01*
G01X907020Y355307D01*
G02X907089Y355368I163J-115D01*
G01X907334Y355485D01*
G02X907420Y355504I85J-181D01*
G01X907590D01*
X907647Y355486D01*
X907663Y355475D01*
G03X908521Y355206I858J1234D01*
G03X910023Y356708I0J1502D01*
G01Y356710D01*
G03X909654Y357695I-1502J-1D01*
G01X909628Y357725D01*
X909616Y357760D01*
G02X909605Y357834I189J66D01*
G01X909616Y358109D01*
G02X909675Y358243I200J-8D01*
G01X909676Y358244D01*
G03X910127Y359317I-1051J1073D01*
G03X909513Y360529I-1502J1D01*
G01X909511D01*
Y360530D01*
G02X909456Y360592I119J161D01*
G02X909431Y360675I174J98D01*
G01X909407Y360983D01*
G02X909454Y361123I200J11D01*
G01X910246Y361915D01*
G03X910628Y362837I-924J923D01*
G01Y373919D01*
G03X910608Y374145I-1306J-2D01*
G01Y374146D01*
G02X910639Y374292I197J34D01*
G01X910720Y374410D01*
X910800Y374526D01*
G02X910918Y374607I165J-113D01*
G01X910927Y374609D01*
G03X912148Y376084I-280J1475D01*
G03X910646Y377586I-1502J0D01*
G03X909247Y376631I0J-1502D01*
G01X909243Y376621D01*
G02X909106Y376509I-182J83D01*
G02X909102Y376508I-50J193D01*
G01X908792Y376443D01*
X908772Y376439D01*
G02X908602Y376484I-39J196D01*
G01X908478Y376607D01*
G02X908424Y376719I144J139D01*
G02X908422Y376746I198J28D01*
G01Y377080D01*
G02X908423Y377099I200J-1D01*
G02X908478Y377219I199J-19D01*
G01X909368Y378108D01*
X909806Y378546D01*
G02X909947Y378604I141J-142D01*
G01X914484D01*
G02X914641Y378527I-1J-200D01*
G01X914835Y378279D01*
G02X914872Y378202I-157J-123D01*
G01Y378110D01*
X914868Y378089D01*
G03X914828Y377748I1463J-344D01*
G03X916330Y376246I1502J0D01*
G03X917831Y377684I0J1502D01*
G01X917833Y377733D01*
Y377748D01*
G03X917789Y378109I-1503J0D01*
G01X917784Y378128D01*
G02X917819Y378271I198J27D01*
G01X917972Y378467D01*
X918019Y378527D01*
G02X918176Y378604I158J-123D01*
G01X919970D01*
X919978D01*
G02X920141Y378508I-8J-200D01*
G02X920154Y378482I-172J-102D01*
G01X920298Y378145D01*
G02X920311Y378030I-184J-79D01*
G01Y378029D01*
G02X920259Y377928I-197J37D01*
G03X919841Y376888I1085J-1040D01*
G03X922845I1502J0D01*
G03X922427Y377928I-1503J0D01*
G01X922407Y377949D01*
X922381Y378000D01*
X922375Y378030D01*
G02X922388Y378145I197J36D01*
G01X922532Y378482D01*
G02X922545Y378508I185J-76D01*
G02X922708Y378604I171J-104D01*
G01X924381D01*
G02X924565Y378481I-1J-200D01*
G01X924588Y378425D01*
X924580Y378386D01*
X924564Y378306D01*
X924557Y378299D01*
X928380D01*
G02X928557Y378192I0J-200D01*
G01X928722Y377878D01*
G02X928721Y377689I-177J-94D01*
G01X928709Y377672D01*
G03X928445Y376822I1238J-851D01*
G01Y376821D01*
G03X931449I1502J0D01*
G01Y376822D01*
G03X931185Y377672I-1502J-1D01*
G01X931173Y377689D01*
G02X931172Y377878I176J95D01*
G01X931337Y378192D01*
G02X931514Y378299I177J-93D01*
G01X933222D01*
G03X933422Y378499I0J200D01*
G01Y378996D01*
G02X933426Y379034I200J-2D01*
G02X933479Y379136I196J-37D01*
G01X947147Y392804D01*
G02X947177Y392807I35J-197D01*
G01X958701D01*
G02X958819Y392757I-15J-200D01*
G01X958846Y392733D01*
X958879Y392669D01*
X958884Y392631D01*
Y392630D01*
G03X960376Y391305I1492J178D01*
G03X961878Y392807I0J1502D01*
G03X961704Y393511I-1503J2D01*
G01X961684Y393549D01*
Y441299D01*
G02X961727Y441344I164J-114D01*
G01X962024Y441537D01*
G02X962109Y441564I101J-172D01*
G01X962158Y441568D01*
X962205Y441547D01*
G03X962816Y441417I611J1371D01*
G03Y444421I0J1502D01*
G03X962205Y444291I0J-1501D01*
G01X962198Y444288D01*
G02X962107Y444274I-75J185D01*
G01X962058Y444278D01*
X961795Y444449D01*
X961729Y444492D01*
G02X961692Y444525I114J165D01*
G02X961684Y444535I152J130D01*
G01Y449782D01*
G02X961717Y449816I159J-121D01*
G01X961727Y449824D01*
X961847Y449905D01*
X961883Y449928D01*
X961996Y450001D01*
G02X962100Y450031I105J-170D01*
G01X962192D01*
X962232Y450015D01*
X962263Y450004D01*
G03X962754Y449917I504J1415D01*
G01X962774D01*
G03X964261Y451242I-5J1502D01*
G01Y451243D01*
X964264Y451269D01*
G03X964270Y451350I-1495J151D01*
G01Y451352D01*
G03X964271Y451418I-1501J56D01*
G01Y451420D01*
G03X962795Y452921I-1502J-1D01*
G01X962767D01*
G03X962210Y452814I0J-1502D01*
G01X962193Y452807D01*
X962154Y452799D01*
G02X962011Y452826I-37J196D01*
G01X961883Y452910D01*
X961881D01*
X961718Y453020D01*
G02X961684Y453054I124J158D01*
G01Y467124D01*
G03X961274Y468074I-1308J-1D01*
G02X961270Y468078I139J143D01*
G01X958424Y470924D01*
G03X957502Y471306I-923J-924D01*
G01X956224D01*
G02X956133Y471328I0J200D01*
G02X956083Y471364I90J178D01*
G01X955990Y471457D01*
X955992Y471487D01*
X956084Y471836D01*
G02X956120Y471902I191J-61D01*
G01X956146Y471934D01*
X956223Y471973D01*
X956240Y471978D01*
G03X957318Y473419I-424J1441D01*
G03X955816Y474921I-1502J0D01*
G03X954368Y473826I0J-1505D01*
G01Y473824D01*
X954362Y473804D01*
G02X954297Y473718I-186J73D01*
G02X954234Y473687I-118J161D01*
G01X954126Y473658D01*
X954121Y473657D01*
X953912Y473603D01*
G02X953867Y473597I-49J194D01*
G01X953850D01*
X929264Y498183D01*
G02X929228Y498233I142J140D01*
G02X929206Y498324I178J91D01*
G01Y631557D01*
G02X929228Y631648I200J0D01*
G02X929264Y631698I178J-90D01*
G01X929969Y632403D01*
G02X930075Y632457I140J-143D01*
G01X930077D01*
G02X930109Y632460I35J-197D01*
G01X932835D01*
G02X932865Y632457I-5J-200D01*
G01X939983Y625339D01*
G02Y625283I-198J-28D01*
G01X935681Y620981D01*
G03X935298Y620057I923J-924D01*
G01Y599961D01*
G02X935196Y599787I-200J0D01*
G01X934843Y599590D01*
X934734Y599592D01*
X934688Y599621D01*
G03X933741Y599890I-947J-1534D01*
G03X931938Y598087I0J-1803D01*
G01Y594687D01*
G03X933741Y592884I1803J0D01*
G03X934688Y593153I0J1803D01*
G01X934734Y593182D01*
X934843Y593184D01*
X935196Y592987D01*
G02X935298Y592813I-98J-174D01*
G01Y591200D01*
G02X935195Y591025I-200J0D01*
G01X934888Y590856D01*
G02X934685Y590862I-96J175D01*
G03X933728Y591138I-959J-1526D01*
G01X933725D01*
G03X931922Y589336I0J-1803D01*
G01Y585936D01*
G03X933725Y584134I1802J0D01*
G03X934685Y584410I1J1802D01*
G02X934888Y584416I107J-169D01*
G01X935195Y584247D01*
G02X935298Y584072I-97J-175D01*
G01Y548194D01*
G03X935681Y547270I1306J0D01*
G01X938517Y544435D01*
X938526Y544396D01*
G03X938530Y544379I1465J336D01*
G03X938578Y544218I1462J348D01*
G03X939969Y543223I1414J508D01*
G01X940019Y543224D01*
G03X940360Y543269I-25J1502D01*
G01X940376Y543273D01*
X940411Y543276D01*
G02X940508Y543260I17J-199D01*
G02X940550Y543235I-80J-183D01*
G01X940708Y543114D01*
X940724Y543101D01*
X940802Y543041D01*
G02X940833Y543009I-127J-154D01*
G02X940836Y543005I-159J-122D01*
G01Y530739D01*
G02X940835Y530719I-200J0D01*
G02X940780Y530600I-199J20D01*
G01X939686Y529507D01*
X939149Y528970D01*
X939142Y528965D01*
X939132Y528958D01*
G03X938490Y527726I861J-1232D01*
G03X939992Y526224I1502J0D01*
G03X941484Y527548I0J1503D01*
G01X941488Y527582D01*
X941517Y527642D01*
X943066Y529191D01*
G03X943448Y530113I-924J923D01*
G01Y532508D01*
G02X943489Y532549I160J-119D01*
G01X943671Y532683D01*
X943673Y532686D01*
X943733Y532731D01*
G02X943853Y532771I120J-160D01*
G01X943923D01*
X943949Y532764D01*
G03X944047Y532740I406J1446D01*
G03X944250Y532712I306J1471D01*
G01X944253D01*
X944265Y532711D01*
X944278D01*
X944285Y532710D01*
X944289D01*
G03X944323Y532709I61J1500D01*
G01X944362D01*
G03Y535713I-11J1502D01*
G01X944348D01*
G03X943921Y535651I0J-1502D01*
G01X943920D01*
G02X943826Y535646I-57J191D01*
G01X943783Y535654D01*
X943688Y535725D01*
X943488Y535875D01*
G02X943448Y535915I120J160D01*
G01Y570348D01*
G03X943066Y571270I-1306J-1D01*
G01X939760Y574575D01*
G02X939705Y574683I142J140D01*
G02X939702Y574716I197J35D01*
G01Y610603D01*
G02X939708Y610652I200J0D01*
G02X939760Y610744I194J-49D01*
G01X948718Y619701D01*
G03X949100Y620623I-924J923D01*
G01Y620797D01*
G02X949135Y620833I160J-120D01*
G01X949157Y620851D01*
X949466Y621020D01*
X949479Y621025D01*
X949505Y621037D01*
X949566Y621045D01*
X949615Y621037D01*
X949672Y621018D01*
X949695Y621004D01*
G03X950479Y620783I784J1280D01*
G03Y623787I0J1502D01*
G01X950478D01*
G03X949690Y623564I0J-1502D01*
G01X949671Y623552D01*
X949610Y623531D01*
X949576Y623529D01*
X949573D01*
X949545Y623527D01*
X949520Y623532D01*
G02X949465Y623552I40J196D01*
G01X949326Y623627D01*
X949324D01*
X949160Y623718D01*
G02X949131Y623738I99J174D01*
G02X949100Y623771I129J153D01*
G01Y626432D01*
G02X949175Y626493I160J-120D01*
G01X949375Y626582D01*
X949512Y626643D01*
G02X949557Y626654I70J-188D01*
G01X949577Y626655D01*
G02X949622Y626651I5J-200D01*
G01X949657Y626640D01*
X949691Y626630D01*
X949710Y626620D01*
X949727Y626610D01*
X949730Y626608D01*
X949744Y626595D01*
G03X950740Y626211I1003J1118D01*
G01X950761D01*
G03X952250Y627713I-13J1502D01*
G03X950919Y629205I-1502J0D01*
G03X950807Y629214I-176J-1492D01*
G01X950799D01*
G03X950750Y629215I-55J-1501D01*
G01X950735D01*
G03X950647Y629212I7J-1502D01*
G03X949752Y628838I101J-1499D01*
G01X949735Y628823D01*
X949682Y628794D01*
G02X949505Y628786I-97J175D01*
G01X949480Y628797D01*
X949477Y628799D01*
X949234Y628905D01*
G02X949190Y628936I92J178D01*
G01X949177Y628949D01*
G02X949159Y628971I145J137D01*
G01X949138Y629001D01*
G02X949100Y629117I162J117D01*
G01Y632560D01*
G02X949146Y632604I160J-121D01*
G01X949174Y632623D01*
X949487Y632744D01*
X949489D01*
X949525Y632759D01*
G02X949755Y632712I83J-182D01*
G01X949766Y632700D01*
G03X949832Y632633I1102J1020D01*
G03X949867Y632601I1031J1092D01*
G01X949868Y632600D01*
G03X950602Y632245I997J1124D01*
G03X950858Y632222I262J1479D01*
G01X950871D01*
G03X952367Y633724I-6J1502D01*
G03X950865Y635226I-1502J0D01*
G01X950863D01*
G03X950010Y634959I2J-1502D01*
G03X949766Y634748I854J-1235D01*
G01X949755Y634736D01*
G02X949525Y634689I-147J135D01*
G01X949489Y634704D01*
X949487D01*
X949183Y634823D01*
G02X949119Y634866I77J184D01*
G03X949117Y634868I-142J-140D01*
G02X949100Y634887I140J142D01*
G01Y642050D01*
G02X949102Y642080I200J2D01*
G02X949157Y642190I198J-30D01*
G01X952575Y645607D01*
X954259Y647291D01*
G02X954336Y647338I140J-143D01*
G02X954399Y647348I62J-190D01*
G01X971770D01*
G02X971808Y647344I-2J-200D01*
G02X971910Y647291I-37J-196D01*
G01X977364Y641837D01*
G02X977394Y641799I-141J-142D01*
G01X977429Y641740D01*
G02X977430Y641738I-176J-89D01*
G03X978865Y640682I1435J447D01*
G03X980367Y642184I0J1502D01*
G03X979311Y643618I-1502J0D01*
G01X979296Y643623D01*
G02X979267Y643638I77J185D01*
G02X979230Y643667I104J171D01*
G01X973318Y649579D01*
G03X972394Y649962I-924J-923D01*
G01X953775D01*
G03X952851Y649579I0J-1306D01*
G01X952343Y649071D01*
G02X952258Y649028I-130J152D01*
G02X951784Y649421I-74J393D01*
G01Y667362D01*
X951755Y667390D01*
X951754Y667392D01*
X951735Y667411D01*
G03X951733Y667413I-142J-140D01*
G01X951252Y667894D01*
G02X951213Y667959I149J134D01*
G01X951207Y667980D01*
G02Y668077I194J48D01*
G01Y668078D01*
X951216Y668117D01*
X951285Y668405D01*
G02X951297Y668441I195J-45D01*
G02X951315Y668473I183J-82D01*
G01X951382Y668495D01*
G02X951386Y668497I90J-176D01*
G03X951925Y668821I-384J1249D01*
G01X995224Y712120D01*
G03X995606Y713042I-924J923D01*
G01Y751915D01*
G02X995628Y752006I200J0D01*
G02X995664Y752056I178J-90D01*
G01X1000612Y757004D01*
G02X1000718Y757058I140J-143D01*
G01X1000720D01*
G02X1000752Y757061I35J-197D01*
G01X1000792D01*
G02X1000839Y757055I-2J-200D01*
G01X1000980Y757015D01*
X1000982D01*
X1001160Y756963D01*
G02X1001240Y756913I-63J-190D01*
G02X1001286Y756835I-145J-138D01*
G01X1001290Y756820D01*
G03X1002751Y755667I1461J349D01*
G03X1004253Y757169I0J1502D01*
G03X1003100Y758630I-1502J0D01*
G01X1003099D01*
X1003088Y758633D01*
G02X1003007Y758680I57J192D01*
G02X1002955Y758764I139J144D01*
G01X1002926Y758866D01*
X1002856Y759112D01*
G02X1002853Y759187I195J45D01*
G02X1002855Y759198I198J-30D01*
G01Y759200D01*
G02X1002858Y759212I195J-42D01*
G02X1002897Y759286I192J-54D01*
G01X1002900Y759289D01*
X1002903Y759293D01*
X1002904Y759294D01*
G02X1002924Y759313I147J-135D01*
G01X1002922Y759315D01*
X1007964Y764357D01*
X1007996Y764377D01*
X1008009Y764383D01*
G02X1008049Y764396I82J-183D01*
G01X1008074Y764399D01*
X1008082Y764400D01*
X1008085D01*
G03X1008380Y764449I-97J1499D01*
G03X1008583Y764519I-387J1451D01*
G03X1009159Y764956I-593J1380D01*
G03X1009489Y765809I-1169J943D01*
G01Y765810D01*
X1009490Y765825D01*
X1009492Y765846D01*
X1009510Y765888D01*
G02X1009548Y765941I179J-89D01*
G01X1011201Y767594D01*
G02X1011804Y767550I282J-283D01*
G02X1011844Y767431I-160J-120D01*
G01Y757468D01*
X1011837Y757455D01*
G03X1011649Y756732I1314J-728D01*
G01Y756696D01*
G03X1014650Y756625I1502J29D01*
G03X1014653Y756714I-1499J95D01*
G01Y756727D01*
G03X1014465Y757455I-1502J0D01*
G01X1014458Y757468D01*
Y769016D01*
Y769021D01*
G02X1014491Y769126I200J-5D01*
G02X1014890Y769289I327J-230D01*
G02X1014990Y769235I-41J-196D01*
G01X1020520Y763705D01*
G02X1020556Y763655I-142J-140D01*
G02X1020578Y763564I-178J-91D01*
G01Y699715D01*
X1020575Y699709D01*
X1020574Y699708D01*
G03X1020383Y698980I1311J-733D01*
G01Y698944D01*
G03X1023384Y698873I1502J29D01*
G03X1023387Y698962I-1499J95D01*
G01Y698975D01*
G03X1023196Y699708I-1502J0D01*
G01X1023195Y699709D01*
X1023192Y699715D01*
Y755076D01*
G02X1023251Y755128I159J-121D01*
G01X1023351Y755180D01*
X1023353D01*
X1023540Y755276D01*
G02X1023572Y755288I86J-180D01*
G01X1023574D01*
G02X1023627Y755296I56J-192D01*
G01X1023703D01*
G02X1023722Y755295I-1J-200D01*
G02X1023763Y755286I-22J-199D01*
G02X1023805Y755266I-64J-189D01*
G01X1023816Y755259D01*
X1023820Y755256D01*
G03X1024684Y754983I864J1231D01*
G03Y757987I0J1502D01*
G03X1023790Y757692I0J-1502D01*
G01X1023767Y757675D01*
X1023719Y757657D01*
X1023673Y757652D01*
G02X1023614Y757659I-6J200D01*
G02X1023576Y757675I58J191D01*
G01X1023392Y757770D01*
X1023353Y757790D01*
X1023351D01*
X1023251Y757841D01*
G02X1023198Y757886I101J173D01*
G02X1023192Y757894I157J124D01*
G01Y764189D01*
G03X1022779Y765142I-1307J-1D01*
G02X1022775Y765146I139J143D01*
G01X1015821Y772100D01*
G02X1015877Y772270I198J29D01*
G01X1023480Y779873D01*
G02X1023586Y779927I140J-143D01*
G01X1023588D01*
G02X1023620Y779930I35J-197D01*
G01X1039848D01*
G02X1039880Y779927I-3J-200D01*
G01X1039882D01*
G02X1039988Y779873I-34J-197D01*
G01X1042157Y777704D01*
G02X1042211Y777598I-143J-140D01*
G01Y777596D01*
G02X1042214Y777564I-197J-35D01*
G01Y776638D01*
G02X1042212Y776616I-200J7D01*
G01X1038949Y759383D01*
X1038712Y758133D01*
G02X1038577Y757980I-196J37D01*
G01X1038546Y757970D01*
X1038499D01*
X1038489Y757971D01*
G03X1038218Y757973I-147J-1495D01*
G03X1037040Y757222I126J-1497D01*
G01X1037028Y757204D01*
G02X1037008Y757180I-163J116D01*
G01X1036976Y757148D01*
G02X1036964Y757137I-141J142D01*
G02X1036896Y757099I-130J153D01*
G01X1036884Y757096D01*
X1036883D01*
X1036836Y757084D01*
X1036834D01*
X1036605Y757029D01*
G02X1036601Y757028I-50J192D01*
G02X1036457Y757056I-36J197D01*
G01X1036453Y757059D01*
G03X1035621Y757311I-833J-1250D01*
G01X1034887D01*
G03X1034688Y757108I1J-200D01*
G01Y757080D01*
G02X1034671Y757000I-200J1D01*
G01X1034654Y756963D01*
X1034622Y756934D01*
X1034620Y756932D01*
G03X1034376Y756654I999J-1123D01*
G03X1034333Y756587I1243J-845D01*
G01X1034321Y756566D01*
G03X1034302Y756532I1302J-750D01*
G01X1034299Y756526D01*
X1034290Y756511D01*
G02X1034132Y756415I-171J104D01*
G01X1034129D01*
X1033808Y756399D01*
X1033777D01*
G02X1033617Y756479I0J200D01*
G01X1033602Y756499D01*
X1033590Y756518D01*
G03X1030635Y758098I-2955J-1973D01*
G03Y750994I0J-3552D01*
G03X1034175Y754249I0J3552D01*
G01Y754253D01*
X1034176Y754261D01*
G02X1034283Y754414I198J-25D01*
G01X1034529Y754535D01*
X1034531D01*
X1034599Y754568D01*
G02X1034685Y754586I83J-182D01*
G01X1034693D01*
X1034723Y754584D01*
X1034772Y754568D01*
X1034795Y754553D01*
G03X1035618Y754307I824J1256D01*
G01X1035619D01*
G03X1035633I7J1502D01*
G01X1035647D01*
G03X1035681Y754308I-27J1502D01*
G03X1035758Y754313I-59J1501D01*
G03X1036073Y754376I-135J1496D01*
G01X1036075Y754377D01*
X1036089Y754382D01*
G03X1036921Y755059I-470J1427D01*
G01X1036922Y755061D01*
X1036928Y755071D01*
X1036938Y755088D01*
X1036969Y755124D01*
G02X1037064Y755184I150J-132D01*
G01X1037209Y755221D01*
X1037211D01*
X1037331Y755251D01*
X1037338Y755252D01*
X1037364Y755258D01*
X1037420Y755255D01*
X1037468Y755239D01*
X1037481Y755235D01*
X1037537Y755208D01*
X1037548Y755202D01*
X1037553Y755199D01*
G03X1037760Y755092I791J1277D01*
G03X1037840Y755061I583J1385D01*
G03X1037912Y755037I511J1413D01*
G01X1037958Y755023D01*
G02X1038054Y754944I-73J-186D01*
G01Y754677D01*
G02X1038051Y754640I-200J-2D01*
G01X1037059Y749407D01*
X1034795Y737452D01*
G02X1034733Y737358I-191J59D01*
G01X1034707Y737336D01*
X1034644Y737312D01*
X1034610Y737311D01*
X1034607D01*
G03X1034026Y734436I31J-1502D01*
G01X1034060Y734421D01*
X1034170Y734311D01*
X1034175Y734302D01*
X1034180Y734268D01*
G02X1034179Y734204I-198J-29D01*
G01X1034149Y734045D01*
X1034039Y733464D01*
G02X1034029Y733435I-194J51D01*
G01X1034022Y733418D01*
G02X1034014Y733404I-178J92D01*
G02X1033953Y733343I-169J108D01*
G01X1033875Y733293D01*
X1033709Y733186D01*
G02X1033635Y733157I-109J168D01*
G01X1033596Y733150D01*
X1033555Y733160D01*
G03X1033203Y733202I-353J-1460D01*
G01X1033200D01*
G03X1031698Y731700I0J-1502D01*
G03X1032996Y730212I1502J0D01*
G01X1033004Y730211D01*
G02X1033016Y730208I-42J-195D01*
G02X1033131Y730131I-47J-194D01*
G01X1033177Y730067D01*
X1033301Y729897D01*
G02X1033315Y729874I-164J-115D01*
G02X1033335Y729741I-177J-95D01*
G01X1031506Y720081D01*
X1031441Y719741D01*
X1031439Y719730D01*
G02X1031307Y719587I-194J47D01*
G01X1031166Y719550D01*
G03X1031142Y719542I51J-193D01*
G01X1031125Y719534D01*
X1031112Y719526D01*
X1031111D01*
X1031054Y719491D01*
X1031039Y719482D01*
G02X1030944Y719453I-104J171D01*
G01X1030919Y719454D01*
G02X1030812Y719496I16J199D01*
G01X1030758Y719541D01*
X1030740Y719559D01*
X1030728Y719573D01*
G03X1029582Y720105I-1146J-968D01*
G03X1028917Y719950I0J-1504D01*
G01X1028916D01*
G02X1028756Y719943I-88J179D01*
G01X1028459Y720073D01*
G02X1028359Y720184I88J180D01*
G01X1028356Y720195D01*
Y720196D01*
G03X1026916Y721271I-1440J-427D01*
G03X1025414Y719769I0J-1502D01*
G03X1026018Y718565I1502J0D01*
G01X1026046Y718544D01*
X1026064Y718518D01*
G02X1026092Y718455I-166J-112D01*
G01X1026121Y718340D01*
X1026130Y718306D01*
X1026124Y718238D01*
X1026122Y718233D01*
X1026119Y718227D01*
G03X1025976Y717587I1361J-640D01*
G03X1027478Y716085I1502J0D01*
G03X1028841Y716955I0J1503D01*
G01X1028855Y716986D01*
X1028925Y717059D01*
X1028953Y717087D01*
X1029026Y717122D01*
X1029028D01*
X1029065Y717140D01*
G02X1029168Y717155I79J-184D01*
G01X1029196Y717151D01*
X1029207Y717148D01*
G03X1029580Y717101I373J1453D01*
G01X1029586D01*
G03X1030313Y717289I-1J1503D01*
G01X1030339Y717303D01*
X1030340Y717304D01*
X1030367Y717310D01*
G02X1030521Y717280I42J-195D01*
G01X1030672Y717170D01*
X1030818Y717064D01*
G02X1030887Y716973I-118J-161D01*
G02X1030899Y716880I-187J-71D01*
G01X1030528Y714921D01*
X1030239Y713401D01*
G02X1030123Y713273I-192J57D01*
G01X1030121Y713272D01*
X1030046Y713258D01*
X1030020Y713260D01*
G03X1029900Y713264I-110J-1499D01*
G01X1029884D01*
G03X1028383Y711762I1J-1502D01*
G03X1029373Y710350I1502J0D01*
G01X1029404Y710339D01*
X1029511Y710254D01*
X1029530Y710223D01*
X1029572Y710156D01*
G02X1029599Y710056I-173J-100D01*
G01Y710013D01*
X1023170Y676064D01*
X1016665Y641710D01*
X1003568Y572557D01*
G03X1003532Y572331I3824J-725D01*
G01X1003205Y569798D01*
X999069Y538349D01*
X993975Y499620D01*
G02X993826Y499462I-197J36D01*
G01X993779Y499450D01*
X993777D01*
X993670Y499424D01*
G02X993551Y499438I-37J196D01*
G01X993497Y499464D01*
X993466Y499481D01*
G02X993439Y499503I112J166D01*
G01X993414Y499528D01*
X993407Y499537D01*
G03X993403Y499542I-1175J-936D01*
G03X993401Y499545I-1251J-832D01*
G01X993400Y499546D01*
X993387Y499563D01*
X993386Y499564D01*
X993379Y499572D01*
X993377Y499575D01*
G03X992206Y500135I-1171J-944D01*
G03X990704Y498652I0J-1502D01*
G01Y498633D01*
G03X990708Y498517I1502J-6D01*
G01X990711Y498474D01*
X990696Y498433D01*
G02X990650Y498361I-188J69D01*
G01X990641Y498352D01*
X990637Y498277D01*
G03X990680Y498143I200J-10D01*
G01X991013Y497720D01*
X991014Y497718D01*
X991015Y497717D01*
G02X991021Y497710I-149J-134D01*
G01X991026Y497703D01*
X991027Y497702D01*
G03X991031Y497697I158J122D01*
G01X991033Y497694D01*
X991046Y497676D01*
X991060Y497645D01*
G02X991074Y497572I-186J-73D01*
G01Y497488D01*
G03X991092Y497405I200J0D01*
G01X991117Y497350D01*
G02X991084Y497133I-181J-83D01*
G01X991048Y497092D01*
G03X990704Y496156I1160J-957D01*
G01Y496133D01*
G03X990708Y496017I1502J-6D01*
G01X990711Y495974D01*
X990687Y495909D01*
X990685Y495904D01*
X990681Y495892D01*
X990650Y495861D01*
G02X990367I-141J141D01*
G01X989303Y496925D01*
G02X989245Y497056I142J141D01*
G01X989243Y497093D01*
X989267Y497164D01*
X989291Y497193D01*
G03X989636Y498151I-1158J958D01*
G03X988134Y499653I-1502J0D01*
G03X987042Y499183I0J-1504D01*
G01X987026Y499167D01*
X986913Y499118D01*
G02X986839Y499103I-76J185D01*
G01X986629D01*
G02X986555Y499118I2J200D01*
G01X986442Y499167D01*
X986426Y499183D01*
G03X985334Y499653I-1092J-1034D01*
G03X983832Y498151I0J-1502D01*
G03X984542Y496874I1503J0D01*
G01X984551Y496868D01*
G02X984635Y496725I-115J-164D01*
G01X984666Y496410D01*
G02X984605Y496245I-199J-20D01*
G01X984604Y496244D01*
G03X984132Y495151I1030J-1093D01*
G03X985634Y493649I1502J0D01*
G03X986569Y493976I0J1500D01*
G01X986570Y493977D01*
G02X986680Y494019I123J-158D01*
G01X986822D01*
Y494063D01*
X987060D01*
G02X987124Y494036I-45J-195D01*
G02X987141Y494024I-107J-169D01*
G01X987147Y494019D01*
G03X988134Y493649I987J1131D01*
G03X989267Y494165I0J1502D01*
G01X989268Y494166D01*
X989279Y494178D01*
G02X989414Y494234I139J-144D01*
G01X989576Y494230D01*
X989578D01*
X989737Y494227D01*
G02X989875Y494161I-11J-200D01*
G01X991013Y492720D01*
X991014Y492718D01*
X991015Y492717D01*
G02X991021Y492710I-149J-134D01*
G01X991026Y492703D01*
X991027Y492702D01*
G03X991031Y492697I158J122D01*
G01X991033Y492694D01*
X991046Y492676D01*
X991060Y492645D01*
G02X991074Y492572I-186J-73D01*
G01Y492488D01*
G03X991092Y492405I200J0D01*
G01X991117Y492350D01*
G02X991084Y492133I-181J-83D01*
G01X991048Y492092D01*
G03X990704Y491135I1160J-957D01*
G01Y491133D01*
G03X992206Y489631I1502J0D01*
G03X992355Y489638I4J1502D01*
G01X992383Y489641D01*
X992429Y489632D01*
G02X992530Y489580I-37J-196D01*
G01X992572Y489536D01*
G02X992628Y489384I-143J-139D01*
G01X992124Y485539D01*
G02X992068Y485425I-198J27D01*
G01X992046Y485403D01*
X991990Y485373D01*
X991958Y485368D01*
G03X990704Y483886I249J-1482D01*
G03X991147Y482821I1502J0D01*
G01X991161Y482807D01*
X991197Y482753D01*
X991198Y482752D01*
X991206Y482739D01*
G02X991215Y482723I-170J-106D01*
G01X991232Y482682D01*
X991243Y482654D01*
G02X991251Y482624I-189J-66D01*
G02X991254Y482590I-197J-35D01*
G01Y482346D01*
G02X991213Y482225I-200J0D01*
G01X991205Y482216D01*
X991198Y482209D01*
G03X991185Y482194I144J-138D01*
G01X991173Y482182D01*
X991161Y482165D01*
X991149Y482153D01*
G03X990704Y481086I1057J-1067D01*
G03X990717Y480886I1502J-3D01*
G03X991029Y480152I1489J200D01*
G01X991045Y480132D01*
X991059Y480101D01*
G02X991074Y480025I-185J-76D01*
G01Y479941D01*
G03X991092Y479858I200J0D01*
G01X991117Y479803D01*
G02X991084Y479586I-181J-83D01*
G01X991048Y479545D01*
G03X990704Y478609I1160J-957D01*
G01Y478586D01*
G03X990708Y478470I1502J-6D01*
G01X990711Y478427D01*
X990696Y478386D01*
G02X990650Y478314I-188J69D01*
G01X990641Y478305D01*
X990637Y478230D01*
G03X990680Y478096I200J-10D01*
G01X991003Y477686D01*
G03X991026Y477654I1232J861D01*
G01X991049Y477625D01*
X991059Y477601D01*
G02X991072Y477552I-185J-75D01*
G01X991003Y477027D01*
G02X990991Y476981I-198J27D01*
G01X990983Y476959D01*
X990969Y476939D01*
G03X990841Y476715I1235J-854D01*
G01X990827Y476682D01*
G03X990755Y476477I1379J-599D01*
G01Y476476D01*
X990749Y476452D01*
G03X990743Y476427I1457J-363D01*
G01X990733Y476426D01*
X990718Y476296D01*
Y476291D01*
G03X990705Y476150I1488J-208D01*
G03X990704Y476117I1500J-62D01*
G01Y476078D01*
G03X990715Y475901I1501J4D01*
G03X990791Y475582I1492J187D01*
G01X990799Y475559D01*
X990804Y475514D01*
X990620Y474117D01*
X990498Y473186D01*
G02X990491Y473154I-198J27D01*
G01X990068Y471758D01*
X988397Y466248D01*
G02X988305Y466132I-192J57D01*
G01X988286Y466121D01*
X988236Y466108D01*
X988176D01*
X988169Y466110D01*
G03X987807Y466154I-361J-1459D01*
G01X987772D01*
G03X987735Y466153I22J-1502D01*
G01X987733D01*
G03X987556Y466134I72J-1501D01*
G03X987502Y466124I247J-1482D01*
G01X987497Y466123D01*
X987486Y466121D01*
X987449Y466113D01*
X987442Y466111D01*
X987439Y466110D01*
G03X986884Y465841I364J-1457D01*
G01X986877Y465836D01*
X986850Y465820D01*
X986792Y465791D01*
G02X986742Y465784I-52J193D01*
G01X986658D01*
G03X986575Y465766I0J-200D01*
G01X986520Y465741D01*
G02X986303Y465774I-83J181D01*
G01X986262Y465810D01*
G03X985313Y466154I-957J-1160D01*
G01X985303D01*
G03X983801Y464671I0J-1502D01*
G01Y464652D01*
G03X983805Y464536I1502J-6D01*
G01X983808Y464493D01*
X983793Y464452D01*
G02X983747Y464380I-188J69D01*
G01X983738Y464371D01*
X983734Y464296D01*
G03X983777Y464162I200J-10D01*
G01X984110Y463739D01*
X984111Y463737D01*
X984112Y463736D01*
G02X984118Y463729I-149J-134D01*
G01X984123Y463722D01*
X984124Y463721D01*
G03X984128Y463716I158J122D01*
G01X984130Y463713D01*
X984143Y463695D01*
X984157Y463664D01*
G02X984171Y463591I-186J-73D01*
G01Y463507D01*
G03X984189Y463424I200J0D01*
G01X984214Y463369D01*
G02X984181Y463152I-181J-83D01*
G01X984145Y463111D01*
G03X983801Y462175I1160J-957D01*
G01Y462152D01*
G03X983805Y462036I1502J-6D01*
G01X983808Y461993D01*
X983793Y461952D01*
G02X983747Y461880I-188J69D01*
G01X983738Y461871D01*
X983734Y461796D01*
G03X983777Y461662I200J-10D01*
G01X984110Y461239D01*
X984111Y461237D01*
X984112Y461236D01*
G02X984118Y461229I-149J-134D01*
G01X984123Y461222D01*
X984124Y461221D01*
G03X984128Y461216I158J122D01*
G01X984130Y461213D01*
X984143Y461195D01*
X984157Y461164D01*
G02X984171Y461091I-186J-73D01*
G01Y461007D01*
G03X984189Y460924I200J0D01*
G01X984214Y460869D01*
G02X984181Y460652I-181J-83D01*
G01X984145Y460611D01*
G03X983801Y459654I1160J-957D01*
G01Y459652D01*
G03X985303Y458150I1502J0D01*
G01X985333D01*
G03X985406Y458153I-25J1502D01*
G01X985408D01*
X985433Y458154D01*
X985475Y458135D01*
G02X985550Y458076I-82J-182D01*
G01X985754Y457818D01*
G02X985760Y457811I-149J-134D01*
G02X985792Y457651I-164J-116D01*
G01X983140Y448905D01*
G02X983059Y448796I-192J58D01*
G01X983002Y448758D01*
X982962Y448762D01*
G03X982793Y448771I-164J-1493D01*
G01X982792D01*
G03X981290Y447269I0J-1502D01*
G01Y447240D01*
X981291Y447186D01*
X981265Y447139D01*
G02X981190Y447063I-175J97D01*
G01X980887Y446888D01*
G02X980785Y446862I-99J174D01*
G01X980731D01*
X980684Y446890D01*
G03X979910Y447105I-774J-1286D01*
G03X981412Y445603I0J-1502D01*
G01Y445632D01*
X981411Y445687D01*
X981437Y445734D01*
G02X981511Y445808I174J-100D01*
G01X981663Y445897D01*
X981814Y445984D01*
G02X981918Y446011I100J-173D01*
G01X981971Y446010D01*
X982017Y445982D01*
G03X982036Y445971I762J1294D01*
G02X982045Y445966I-92J-177D01*
G03X982066Y445954I755J1297D01*
G02X982069Y445952I-109J-167D01*
G03X982078Y445947I733J1309D01*
G01X982079D01*
G02X982168Y445848I-96J-176D01*
G01X982181Y445818D01*
X982184Y445749D01*
X980181Y439139D01*
G02X979987Y439009I-187J70D01*
G01X979986D01*
G03X979936Y439010I-55J-1501D01*
G01X979931D01*
G03X978430Y437508I1J-1502D01*
G03X979104Y436254I1504J0D01*
G01X979124Y436241D01*
X979157Y436206D01*
X979239Y436059D01*
G02X979234Y436015I-200J0D01*
G01X972261Y413013D01*
X971643Y410972D01*
X971107Y409203D01*
G02X971070Y409134I-192J58D01*
G01X971045Y409104D01*
X971010Y409085D01*
G03X970219Y407782I711J-1323D01*
G01Y407761D01*
G03X970395Y407056I1502J1D01*
G01X970414Y407020D01*
X970418Y406983D01*
G02X970410Y406904I-199J-20D01*
G01X970133Y405991D01*
X970130Y405981D01*
G03X970129Y405978I3723J-1243D01*
G03X970125Y405966I3722J-1247D01*
G01X969784Y404840D01*
X969551Y404072D01*
G02X969451Y403964I-186J72D01*
G01X969175Y403838D01*
G02X969092Y403820I-83J182D01*
G01X969050D01*
X969025Y403831D01*
G03X968349Y403980I-677J-1463D01*
G01X968348D01*
G03X966737Y402369I0J-1611D01*
G03X968082Y400780I1611J0D01*
G01X968125Y400773D01*
X968161Y400749D01*
G02X968219Y400689I-112J-166D01*
G01X968281Y400588D01*
X968377Y400433D01*
G02X968402Y400280I-170J-106D01*
G01X958499Y367610D01*
X956925Y362418D01*
X955478Y357644D01*
G02X955411Y357545I-192J58D01*
G03X954846Y356371I937J-1174D01*
G01Y356369D01*
G03X954917Y355915I1502J2D01*
G01Y355797D01*
X954524Y354497D01*
X949651Y338423D01*
G02X949539Y338298I-191J59D01*
G02X949511Y338288I-81J183D01*
G01X949501Y338286D01*
G03X948311Y336817I312J-1469D01*
G03X949301Y335405I1502J0D01*
G01X949312Y335401D01*
G02X949432Y335237I-79J-184D01*
G01X949448Y333352D01*
X949450Y333155D01*
X949457Y332189D01*
G02X949412Y332061I-200J-2D01*
G01X949390Y332035D01*
X949331Y331999D01*
X949295Y331992D01*
G03X948077Y330517I284J-1475D01*
G03X949256Y329050I1502J0D01*
G01X949288Y329043D01*
X949345Y329009D01*
X949438Y328898D01*
G02X949486Y328771I-152J-130D01*
G01X949497Y327382D01*
G02X949429Y327230I-200J-2D01*
G01X949258Y327080D01*
X949214Y327068D01*
X949171Y327056D01*
X949128Y327063D01*
G03X948900Y327080I-225J-1485D01*
G03X947398Y325578I0J-1502D01*
G03X948899Y324076I1502J0D01*
G01X948901D01*
G03X949192Y324106I-8J1501D01*
G01X949206Y324108D01*
X949264Y324092D01*
G02X949322Y324062I-62J-190D01*
G01X949454Y323952D01*
G02X949527Y323809I-127J-155D01*
G01X949551Y320943D01*
G02X949427Y320765I-200J7D01*
G01X949383Y320748D01*
X949073Y320628D01*
G02X948853Y320680I-72J186D01*
G01X948852Y320681D01*
G03X947733Y321182I-1120J-1001D01*
G03Y318178I0J-1502D01*
G03X949173Y319253I0J1502D01*
G01Y319254D01*
G02X949346Y319396I192J-57D01*
G01X949364D01*
G02X949506Y319339I2J-200D01*
G01X949533Y319312D01*
X949564Y319239D01*
X949569Y318700D01*
G02X949561Y318645I-200J1D01*
G01X949555Y318622D01*
X949540Y318597D01*
G03X949372Y317440I1287J-778D01*
G03X949373Y317437I189J61D01*
G03X949501Y317112I1452J384D01*
G03X949554Y317020I1328J704D01*
G01X949568Y316997D01*
X949575Y316971D01*
G02X949583Y316918I-192J-56D01*
G01X949779Y293212D01*
G02X949737Y293087I-200J-2D01*
G01X949717Y293062D01*
X949661Y293026D01*
X949626Y293017D01*
G03X948472Y291554I350J-1463D01*
G03X949650Y290086I1504J0D01*
G01X949651D01*
G02X949763Y290017I-43J-195D01*
G01X949784Y289991D01*
X949807Y289927D01*
X950124Y251616D01*
G02X950113Y251550I-200J-1D01*
G01X950104Y251523D01*
X950082Y251494D01*
G03X950097Y249654I1195J-910D01*
G01X950098Y249653D01*
G02X950140Y249544I-158J-123D01*
G01X950165Y246559D01*
Y246553D01*
G03X950164Y246485I3927J-92D01*
G01Y243753D01*
G02X950044Y243570I-200J0D01*
G01X950001Y243551D01*
G02X949858Y243552I-70J187D01*
G01X949806Y243576D01*
X949788Y243584D01*
X949771Y243598D01*
X949768Y243600D01*
X949765Y243603D01*
G03X948785Y243966I-980J-1142D01*
G03X947283Y242464I0J-1502D01*
G03X948777Y240962I1502J0D01*
G01X948786D01*
G03X949603Y241204I-1J1502D01*
G01X949618Y241214D01*
X949629Y241221D01*
X949669Y241242D01*
X949686Y241247D01*
X949725Y241260D01*
G02X949806Y241266I55J-193D01*
G01X949850Y241260D01*
X949887Y241236D01*
G03X949903Y241227I106J169D01*
G01X949905Y241226D01*
X949935Y241209D01*
X949937D01*
X950089Y241124D01*
X950110Y241112D01*
X950136Y241067D01*
G02X950164Y240966I-172J-102D01*
G01Y238793D01*
Y238781D01*
X950138Y238327D01*
X949959Y235141D01*
Y235136D01*
X949596Y231134D01*
G02X949544Y231028I-198J31D01*
G01X949537Y231021D01*
G02X949517Y231004I-139J144D01*
G01X949392Y230919D01*
G02X949308Y230894I-98J175D01*
G02X949293Y230893I-21J199D01*
G01X949218D01*
X949189Y230902D01*
G03X949145Y230915I-448J-1434D01*
G03X949127Y230920I-411J-1445D01*
G01X949095Y230928D01*
G03X949008Y230947I-364J-1457D01*
G01X949001Y230948D01*
X949000D01*
X948988Y230950D01*
X948985D01*
X948958Y230955D01*
G03X948774Y230971I-222J-1487D01*
G01X948717Y230970D01*
G03X947239Y229468I24J-1502D01*
G03X948741Y227966I1502J0D01*
G01X948744D01*
G03X949058Y227999I1J1502D01*
G01X949094Y228002D01*
G02X949144Y227995I-2J-200D01*
G01X949145D01*
X949154Y227993D01*
G02X949217Y227960I-60J-191D01*
G01X949232Y227947D01*
X949236Y227943D01*
G02X949294Y227790I-142J-141D01*
G01X949111Y225762D01*
G03X949095Y225409I3911J-354D01*
G01Y225408D01*
Y225407D01*
Y225405D01*
G03X949097Y225259I3927J-19D01*
G01Y225257D01*
X949164Y220985D01*
Y220971D01*
X948918Y216601D01*
G02X948899Y216525I-200J10D01*
G01X948885Y216496D01*
X948881Y216489D01*
G03X948878Y216484I1286J-775D01*
G01X948877Y216483D01*
G03X948675Y215732I1300J-752D01*
G01Y215693D01*
G03X948812Y215093I1503J28D01*
G01X948823Y215069D01*
X948832Y215027D01*
X948830Y214991D01*
X948822Y214856D01*
Y214854D01*
X948805Y214556D01*
X948658Y211933D01*
X948519Y209475D01*
G02X948461Y209345I-200J11D01*
G01X948440Y209324D01*
X948435Y209320D01*
G03X948431Y209316I1059J-1063D01*
G03X948422Y209308I993J-1127D01*
G01X948420Y209306D01*
G03X948413Y209300I974J-1143D01*
G03X948411Y209298I140J-142D01*
G03X948375Y209264I1013J-1109D01*
G03X948373Y209261I162J-110D01*
G03X948309Y209192I1069J-1056D01*
G03X947940Y208206I1133J-986D01*
G01Y208184D01*
X947941Y208155D01*
G03X948123Y207488I1502J51D01*
G03X948320Y207207I1321J716D01*
G01X948323Y207204D01*
G03X948325Y207202I142J140D01*
G01X948327Y207200D01*
X948330Y207196D01*
X948331Y207195D01*
X948355Y207163D01*
G02X948384Y207052I-171J-104D01*
G01X948054Y201162D01*
X948008Y200343D01*
X947945Y199220D01*
X947936Y199194D01*
G03X947905Y199089I1425J-478D01*
G01Y199088D01*
X947899Y199064D01*
G03X947862Y198842I1459J-357D01*
G01Y198838D01*
X947861Y198829D01*
X947860Y198821D01*
X947859Y198801D01*
G03X947858Y198772I1500J-66D01*
G01Y198754D01*
X947857Y198746D01*
Y198722D01*
G03Y198710I1502J-6D01*
G01Y198709D01*
G03X947891Y198391I1502J0D01*
G01X947897Y198364D01*
X947666Y194243D01*
X947365Y188888D01*
G02X947283Y188753I-198J28D01*
G01X947262Y188739D01*
X947199Y188705D01*
X947166Y188699D01*
X947165D01*
G03X946170Y188047I259J-1480D01*
G01X946146Y188011D01*
X945999Y187918D01*
X945951Y187914D01*
X945842Y187903D01*
X945840D01*
X945686Y187887D01*
G02X945618Y187892I-20J199D01*
G01X945610Y187894D01*
G02X945605Y187896I72J186D01*
G01X945598Y187898D01*
X945573Y187907D01*
X945533Y187933D01*
X945517Y187950D01*
G03X945397Y188064I-1093J-1030D01*
G03X944526Y188418I-973J-1145D01*
G03X944449Y188421I-97J-1499D01*
G01X944422D01*
G03X944417I-2J-1502D01*
G01X944416D01*
G03X944342Y188419I4J-1502D01*
G01X944328Y188418D01*
X944327D01*
G03X942932Y187095I97J-1499D01*
G01X942928Y187058D01*
G03X942923Y186981I1496J-136D01*
G03X942922Y186919I1501J-55D01*
G03Y186917I1502J-1D01*
G01Y186916D01*
G03X942926Y186803I1502J-3D01*
G01X942929Y186760D01*
X942914Y186719D01*
G02X942868Y186647I-188J69D01*
G01X942859Y186638D01*
X942855Y186563D01*
G03X942898Y186429I200J-10D01*
G01X943231Y186006D01*
X943232Y186004D01*
X943233Y186003D01*
G02X943239Y185996I-149J-134D01*
G01X943244Y185989D01*
X943245Y185988D01*
G03X943249Y185983I158J122D01*
G01X943251Y185980D01*
X943264Y185962D01*
X943278Y185931D01*
G02X943292Y185858I-186J-73D01*
G01Y185774D01*
G03X943310Y185691I200J0D01*
G01X943334Y185638D01*
G02X943309Y185430I-181J-84D01*
G01X943287Y185402D01*
X943273Y185384D01*
X943271Y185381D01*
X943265Y185374D01*
G03X942924Y184496I1159J-955D01*
G03X942922Y184423I1500J-78D01*
G01Y184419D01*
G03X944424Y182917I1502J0D01*
G03X945569Y183447I0J1502D01*
G01X945574Y183453D01*
X945575Y183454D01*
X945599Y183482D01*
X945626Y183501D01*
X945642Y183513D01*
X945735Y183556D01*
X945741Y183559D01*
X945743D01*
G03X945753Y183562I-53J193D01*
G01X945754D01*
G03X945757Y183563I-61J189D01*
G01X945766Y183566D01*
G02X945815Y183573I52J-192D01*
G01X946015D01*
G02X946063Y183567I-1J-200D01*
G01X946127Y183551D01*
X946146Y183542D01*
X946190Y183521D01*
X946209Y183512D01*
X946248Y183482D01*
X946263Y183464D01*
G03X946378Y183341I1153J963D01*
G01X946379Y183340D01*
G03X946476Y183254I1044J1080D01*
G01X946478Y183252D01*
X946492Y183240D01*
X946493Y183239D01*
X946498Y183235D01*
G03X946547Y183198I930J1181D01*
G01X946596Y183165D01*
G03X946845Y183031I834J1251D01*
G01X946873Y183019D01*
X946892Y183004D01*
G02X946926Y182969I-125J-156D01*
G01X947003Y182858D01*
X947012Y182828D01*
X947023Y182793D01*
X947021Y182758D01*
Y182757D01*
X946956Y181593D01*
X946954Y181555D01*
X946921Y181482D01*
X946893Y181456D01*
X946891Y181454D01*
G03X946882Y181446I993J-1127D01*
G03X946880Y181444I140J-142D01*
G03X946867Y181432I1012J-1110D01*
G03X946864Y181429I140J-143D01*
G01X946832Y181397D01*
X946796Y181382D01*
G02X946718Y181366I-78J184D01*
G01X946612D01*
G02X946594Y181367I2J200D01*
G02X946535Y181383I22J199D01*
G01X946451Y181427D01*
X946431Y181446D01*
X946430Y181447D01*
G03X945406Y181849I-1023J-1100D01*
G03X945403I-1J-1502D01*
G01X945344D01*
X945313Y181846D01*
G03X945161Y181829I91J-1499D01*
G01X945159D01*
G03X945155Y181828I46J-194D01*
G01X945153D01*
G03X945142Y181826I263J-1479D01*
G01X945130Y181824D01*
X945128D01*
G03X945120Y181822I360J-1456D01*
G01X945111Y181821D01*
G03X945039Y181804I309J-1470D01*
G01X945037D01*
G03X944474Y181526I369J-1457D01*
G01X944473Y181525D01*
X944455Y181511D01*
X944433Y181500D01*
G02X944344Y181479I-89J179D01*
G01X944261D01*
G03X944178Y181461I0J-200D01*
G01X944125Y181437D01*
G02X943917Y181462I-84J181D01*
G01X943889Y181484D01*
X943871Y181498D01*
X943868Y181500D01*
G03X942907Y181849I-962J-1152D01*
G01X942868D01*
G03X942024Y181563I38J-1502D01*
G01X941990Y181539D01*
X941970Y181522D01*
G02X941941Y181504I-120J161D01*
G01X941933Y181500D01*
G02X941844Y181479I-89J179D01*
G01X941761D01*
G03X941678Y181461I0J-200D01*
G01X941625Y181437D01*
G02X941417Y181462I-84J181D01*
G01X941389Y181484D01*
X941371Y181498D01*
X941368Y181500D01*
G03X940407Y181849I-962J-1152D01*
G01X940406D01*
G03Y178845I0J-1502D01*
G01X940407D01*
G03X941341Y179171I0J1502D01*
G01X941360Y179186D01*
X941389Y179199D01*
G02X941467Y179215I78J-184D01*
G01X941551D01*
G03X941634Y179233I0J200D01*
G01X941687Y179257D01*
G02X941895Y179232I84J-181D01*
G01X941923Y179210D01*
X941941Y179196D01*
X941944Y179194D01*
G03X942905Y178845I962J1152D01*
G01X942944D01*
G03X943840Y179170I-38J1502D01*
G01X943860Y179186D01*
X943891Y179200D01*
G02X943967Y179215I76J-185D01*
G01X944051D01*
G03X944134Y179233I0J200D01*
G01X944187Y179257D01*
G02X944395Y179232I84J-181D01*
G01X944423Y179210D01*
X944441Y179196D01*
X944444Y179194D01*
G03X945405Y178845I962J1152D01*
G01X945406D01*
G03X946184Y179062I0J1503D01*
G01X946192Y179067D01*
G02X946394Y179065I99J-174D01*
G01X946697Y178883D01*
G02X946789Y178754I-104J-171D01*
G01X946795Y178726D01*
X946554Y174446D01*
G02X946553Y174430I-200J4D01*
G01X945411Y165978D01*
X944463Y158959D01*
G03X944428Y158493I3891J-527D01*
G01X944404Y156950D01*
X944396Y156399D01*
G02X944375Y156324I-199J15D01*
G01Y156323D01*
G03X943968Y154641I3519J-1742D01*
G01X943938Y152695D01*
Y152624D01*
G03X944141Y151382I3927J4D01*
G02X944144Y151263I-190J-64D01*
G02X944139Y151249I-191J60D01*
G03X943894Y149942I3681J-1366D01*
G01X943864Y147995D01*
Y147931D01*
G03X943924Y147243I3926J-4D01*
G03X943970Y147020I3867J681D01*
G01X943977Y146994D01*
X943978Y146987D01*
X943956Y146760D01*
X943954Y146737D01*
X943929Y146661D01*
X943919Y146643D01*
G03X943501Y145521I3395J-1904D01*
G01X943494Y145485D01*
X943438Y145396D01*
G02X943426Y145381I-162J118D01*
G02X943411Y145366I-149J134D01*
G01X943363Y145326D01*
X943342Y145309D01*
G02X943286Y145276I-128J153D01*
G01X943257Y145265D01*
X943223Y145263D01*
X943222D01*
G03X941790Y143762I71J-1501D01*
G03X942903Y142311I1502J0D01*
G01X942925Y142305D01*
X942972Y142281D01*
G02X943055Y142201I-91J-178D01*
G01X943123Y142079D01*
Y142077D01*
X943195Y141943D01*
G02X943210Y141822I-181J-84D01*
G01X943207Y141804D01*
X943205Y141791D01*
X943189Y141741D01*
G03X943141Y141573I3717J-1153D01*
G03X943105Y141424I3764J-988D01*
G03X943077Y141286I3799J-843D01*
G03X943042Y141063I3825J-715D01*
G01Y141057D01*
X943040Y141045D01*
G03X943033Y140981I3865J-455D01*
G01X943026Y140912D01*
X943011Y140758D01*
X942933Y139975D01*
G02X942898Y139890I-197J32D01*
G02X942878Y139866I-163J116D01*
G01X942873Y139861D01*
G02X942839Y139833I-144J140D01*
G01X942740Y139838D01*
X942730D01*
G03X942681Y139840I-185J-3923D01*
G03X942581Y139842I-129J-3925D01*
G01X942532D01*
G03X940457Y139230I30J-3927D01*
G01X940449Y139232D01*
X940433Y139235D01*
G03X940163Y139259I-267J-1478D01*
G01X940161D01*
G03X938659Y137757I0J-1502D01*
G01Y137752D01*
G03X938773Y137183I1502J5D01*
G01X938780Y137166D01*
X938806Y137103D01*
X938811Y137081D01*
X938793Y137019D01*
G03X938634Y135946I3768J-1107D01*
G01Y135902D01*
G03X938975Y134315I3927J14D01*
G02X938987Y134277I-184J-79D01*
G01X939001Y134217D01*
G02Y134213I-200J-2D01*
G01X938987Y134153D01*
G02X938975Y134115I-196J41D01*
G03X938634Y132515I3586J-1601D01*
G01Y132513D01*
G03X938667Y132006I3927J1D01*
G03X938740Y131609I3894J511D01*
G03X938811Y131351I3819J912D01*
G01X938804Y131320D01*
X938795Y131298D01*
G03X938661Y130760I1366J-626D01*
G01Y130743D01*
G03X938659Y130670I1500J-78D01*
G01Y130640D01*
G03X940161Y129168I1502J30D01*
G01X940162D01*
G03X940389Y129185I2J1502D01*
G02X940523Y129159I31J-197D01*
G03X942561Y128588I2039J3356D01*
G01X942562D01*
G03X944599Y129158I-1J3927D01*
G02X944732Y129185I104J-171D01*
G03X944965Y129168I225J1485D01*
G01X944968D01*
G03X945428Y129242I-6J1501D01*
G01X945482Y129260D01*
X945527Y129256D01*
G02X945640Y129208I-18J-200D01*
G01X945717Y129152D01*
X945719Y129151D01*
X945888Y129030D01*
G02X945930Y128987I-120J-160D01*
G03X945936Y128979I163J116D01*
G01X945937Y128978D01*
X945935Y128890D01*
Y128889D01*
G03X945934Y128829I3925J-95D01*
G01Y128822D01*
G03X945935Y128728I3927J-5D01*
G03X946276Y127225I3926J100D01*
G01X946283Y127209D01*
X946301Y127130D01*
G02Y127126I-200J-2D01*
G01X946283Y127047D01*
X946276Y127031D01*
G03X945935Y125528I3585J-1603D01*
G03X945934Y125434I3926J-89D01*
G01Y125427D01*
G03X945935Y125367I3926J35D01*
G01Y125356D01*
X945937Y125282D01*
G02X945889Y125227I-172J102D01*
G01X945711Y125097D01*
X945709D01*
X945633Y125042D01*
G02X945538Y125008I-113J165D01*
G01X945536D01*
G02X945520Y125007I-20J199D01*
G01X945443D01*
X945413Y125016D01*
G03X944967Y125086I-453J-1432D01*
G01X944959D01*
G03X944704Y125064I1J-1502D01*
G01X944665Y125057D01*
G03X942561Y125668I-2103J-3315D01*
G03X940512Y125092I-2J-3926D01*
G02X940417Y125068I-95J176D01*
G01X940393D01*
X940379Y125070D01*
X940375Y125071D01*
X940370D01*
G03X940300Y125080I-226J-1485D01*
G03X940279Y125082I-153J-1494D01*
G01X940275D01*
X940267Y125083D01*
X940263D01*
G03X940184Y125086I-96J-1499D01*
G01X940161D01*
G03X938659Y123584I0J-1502D01*
G01Y123579D01*
G03X938773Y123010I1502J5D01*
G01X938780Y122993D01*
X938806Y122930D01*
X938811Y122908D01*
X938793Y122846D01*
G03X938634Y121750I3768J-1106D01*
G01Y121715D01*
G03X938738Y120844I3927J27D01*
G03X938976Y120139I3823J898D01*
G01X938983Y120123D01*
X939001Y120044D01*
G02Y120040I-200J-2D01*
G01X938983Y119961D01*
X938976Y119945D01*
G03X938634Y118342I3585J-1603D01*
G03X938693Y117663I3927J-1D01*
G03X938773Y117307I3867J682D01*
G03X938812Y117175I3785J1046D01*
G01X938805Y117146D01*
G03X938659Y116499I1357J-646D01*
G01Y116497D01*
G03X940161Y114995I1502J0D01*
G01X940164D01*
G03X940441Y115021I-1J1502D01*
G01X940457Y115024D01*
X940460Y115025D01*
G03X942561Y114416I2100J3317D01*
G03X944661Y115024I1J3926D01*
G01X944665Y115023D01*
X944679Y115021D01*
G03X944960Y114995I278J1476D01*
G01X944964D01*
G03X945359Y115048I0J1502D01*
G01X945366Y115050D01*
X945371Y115051D01*
X945386Y115055D01*
X945441Y115073D01*
X945443D01*
X945464Y115081D01*
X945514Y115086D01*
X945537Y115083D01*
G02X945579Y115072I-29J-198D01*
G02X945627Y115046I-70J-187D01*
G01X945875Y114865D01*
G02X945878Y114863I-110J-168D01*
G01X945897Y114849D01*
G02X945923Y114824I-125J-156D01*
G02X945937Y114805I-154J-128D01*
G01X945935Y114716D01*
Y114715D01*
G03X945934Y114656I3925J-96D01*
G01Y114649D01*
G03X945935Y114555I3927J-5D01*
G03X946276Y113052I3926J100D01*
G01X946283Y113036D01*
X946301Y112957D01*
G02Y112953I-200J-2D01*
G01X946283Y112874D01*
X946276Y112858D01*
G03X945934Y111255I3585J-1603D01*
G03X945993Y110576I3927J-1D01*
G03X946073Y110221I3867J685D01*
G01Y110219D01*
G03X946101Y110126I3773J1085D01*
G01Y110124D01*
G03X946112Y110088I3761J1129D01*
G01X946105Y110059D01*
X946096Y110040D01*
G03X945961Y109500I1365J-628D01*
G01Y109483D01*
G03X945959Y109410I1500J-78D01*
G01Y109380D01*
G03X947461Y107908I1502J30D01*
G03X947737Y107932I8J1503D01*
G01X947745Y107934D01*
G03X947762Y107937I-253J1481D01*
G03X947931Y107835I2113J3310D01*
G03X947935Y107833I91J178D01*
G03X947948Y107826I1868J3454D01*
G01X948017Y107787D01*
G02X948022Y107776I-179J-88D01*
G03X948024Y107770I190J60D01*
G02X948026Y107766I-177J-91D01*
G01X948109Y107462D01*
X948108Y107408D01*
X948101Y107382D01*
X948084Y107321D01*
X948072Y107300D01*
G03X947878Y106562I1308J-738D01*
G01Y106526D01*
X947879Y106510D01*
Y106507D01*
G03X947888Y106388I1501J54D01*
G03X948055Y105854I1492J173D01*
G03X948453Y105379I1325J706D01*
G01X948461Y105373D01*
X948489Y105346D01*
X948540Y105284D01*
X948550Y105263D01*
X948560Y105217D01*
X948544Y104911D01*
X948542Y104862D01*
X948483Y104761D01*
G02X948452Y104720I-174J99D01*
G01X948423Y104691D01*
X948391Y104664D01*
X948382Y104658D01*
G03X947718Y103411I839J-1247D01*
G03X950724I1503J0D01*
G03X950129Y104609I-1504J0D01*
G01X950116Y104619D01*
X950101Y104634D01*
X950077Y104665D01*
G02X950044Y104771I167J110D01*
G01X950059Y105105D01*
X950078Y105142D01*
X950082Y105151D01*
X950117Y105210D01*
X950131Y105233D01*
X950193Y105297D01*
X950218Y105314D01*
G03X950882Y106557I-838J1247D01*
G01Y106570D01*
G03X950812Y107015I-1502J-8D01*
G01X950803Y107044D01*
Y107045D01*
X950799Y107057D01*
G02X950793Y107125I193J51D01*
G02X950794Y107132I199J-25D01*
G01X950804Y107175D01*
G02X950813Y107198I190J-61D01*
G01X950884Y107339D01*
Y107341D01*
X950946Y107461D01*
G02X950954Y107474I174J-98D01*
G03X950956Y107476I-138J140D01*
G02X950963Y107486I167J-109D01*
G01X951038Y107509D01*
G03X951882Y107888I-1175J3747D01*
G02X952003Y107916I103J-171D01*
G03X952018Y107914I206J1487D01*
G01X952024D01*
X952036Y107912D01*
X952040D01*
X952043Y107911D01*
G03X952082Y107909I96J1500D01*
G01X952088D01*
G03X952121Y107907I107J1499D01*
G01X952145D01*
G03X952161I8J1503D01*
G03X952237Y107909I-2J1503D01*
G01X952275Y107912D01*
G03X953364Y108510I-114J1498D01*
G01X953372Y108520D01*
G03X955547Y109624I-602J3880D01*
G01X959134Y113211D01*
G03X959623Y113805I-2772J2781D01*
G01X959741Y113982D01*
G02X959764Y114010I165J-112D01*
G01X960765Y115011D01*
G02X960776Y115021I140J-143D01*
G02X960822Y115049I126J-156D01*
G01X960841Y115056D01*
X960851Y115059D01*
G03X960892Y115072I-433J1438D01*
G03X961076Y115147I-474J1426D01*
G03X961078Y115149I-133J135D01*
G03X961115Y115167I-639J1360D01*
G01X961116Y115168D01*
X961160Y115192D01*
G03X961179Y115203I-743J1306D01*
G01X961200Y115216D01*
G03X961914Y116441I-787J1279D01*
G01X961916Y116498D01*
X963497Y118865D01*
X963509Y118883D01*
X963907Y119281D01*
X967905Y123280D01*
G03X968747Y124532I-2776J2776D01*
G01X969946Y127376D01*
X970697Y129158D01*
G02X970742Y129224I184J-77D01*
G01X970771Y129252D01*
X970797Y129262D01*
G03X971770Y130561I-526J1408D01*
G01X971774Y130625D01*
Y130671D01*
G03X971651Y131266I-1503J-1D01*
G01X971635Y131304D01*
Y131341D01*
G02X971650Y131421I200J4D01*
G01X978151Y146854D01*
G03X978398Y147684I-3617J1528D01*
G03X978460Y148377I-3865J695D01*
G01Y148379D01*
G03X978459Y148442I-3927J-31D01*
G01Y148443D01*
X978362Y154275D01*
G03X978279Y155015I-3926J-66D01*
G01X978175Y155514D01*
X977142Y160448D01*
G02X977138Y160482I196J40D01*
G02X977141Y160524I200J7D01*
G01X977146Y160543D01*
G02X977190Y160623I193J-54D01*
G01X977453Y160869D01*
G02X977540Y160917I137J-146D01*
G01X977562Y160922D01*
X977614D01*
X977641Y160914D01*
G03X978048Y160858I408J1456D01*
G01X978051D01*
G03X979073Y161256I0J1511D01*
G01X979077Y161260D01*
X979086Y161267D01*
X979123Y161287D01*
X979179Y161317D01*
X979218Y161326D01*
X979491D01*
G02X979514Y161325I3J-200D01*
G03X980651Y160825I1137J1043D01*
G03Y163911I0J1543D01*
G03X979514Y163411I0J-1543D01*
G02X979491Y163410I-20J199D01*
G01X979241D01*
G02X979194Y163416I2J200D01*
G01X979170Y163422D01*
G02X979122Y163442I52J193D01*
G01X979103Y163453D01*
X979086Y163468D01*
X979083Y163471D01*
G03X978051Y163878I-1032J-1105D01*
G03X977093Y163536I0J-1513D01*
G01X977091Y163534D01*
G02X976998Y163492I-126J155D01*
G01X976950Y163484D01*
X976577Y163615D01*
G02X976448Y163762I67J189D01*
G01X975701Y167328D01*
X974984Y170755D01*
G02X974982Y170765I195J44D01*
G01X972371Y187919D01*
X970990Y196997D01*
X970975Y197095D01*
X970974Y197102D01*
X970971Y197122D01*
X970558Y199837D01*
X970370Y201072D01*
X970243Y201904D01*
Y201907D01*
X970242Y201914D01*
X969751Y205146D01*
G02X969749Y205172I198J28D01*
G01X969730Y206358D01*
X969727Y206566D01*
G02X969748Y206659I200J4D01*
G01X969795Y206753D01*
X969823Y206788D01*
X969840Y206801D01*
G03X970408Y207955I-935J1177D01*
G01Y207979D01*
G03X970136Y208842I-1502J1D01*
G01X970134Y208844D01*
G03X970122Y208861I-1233J-858D01*
G01X970121Y208862D01*
G03X970103Y208886I-1211J-889D01*
G01X970098Y208893D01*
X970084Y208910D01*
G02X970060Y208949I157J124D01*
G01X970047Y208976D01*
X970038Y209016D01*
Y209123D01*
G03X970020Y209206I-200J0D01*
G01X969995Y209261D01*
G02X970028Y209478I181J83D01*
G01X970064Y209519D01*
G03X970408Y210455I-1160J957D01*
G01Y210479D01*
G03X970122Y211360I-1502J-1D01*
G01X970097Y211394D01*
X970082Y211413D01*
G02X970061Y211447I159J122D01*
G01X970059Y211451D01*
G02X970038Y211540I179J89D01*
G01Y211623D01*
G03X970020Y211706I-200J0D01*
G01X969995Y211761D01*
G02X970028Y211978I181J83D01*
G01X970064Y212019D01*
G03X970408Y212955I-1160J957D01*
G01Y212979D01*
G03X970122Y213860I-1502J-1D01*
G01X970097Y213894D01*
X970082Y213913D01*
G02X970061Y213947I159J122D01*
G01X970059Y213951D01*
G02X970038Y214040I179J89D01*
G01Y214123D01*
G03X970020Y214206I-200J0D01*
G01X970001Y214246D01*
G02X969988Y214287I183J81D01*
G01Y214369D01*
G02X969997Y214400I196J-40D01*
G01X970027Y214478D01*
X970050Y214504D01*
G03X970228Y214762I-1141J978D01*
G01X970246Y214797D01*
G03X970369Y215134I-1341J680D01*
G03X970409Y215478I-1463J344D01*
G03X969664Y216776I-1503J0D01*
G01X969649Y216785D01*
G02X969564Y216935I115J164D01*
G01X969483Y222153D01*
G02X969512Y222261I200J4D01*
G01X969563Y222343D01*
G02X969635Y222412I170J-105D01*
G01X969636Y222413D01*
G03X970398Y223550I-730J1313D01*
G01X970402Y223587D01*
G03X970408Y223726I-1496J134D01*
G03Y223729I-1502J1D01*
G03X970084Y224660I-1503J-1D01*
G01X970083Y224661D01*
X970069Y224679D01*
X970047Y224724D01*
X970038Y224764D01*
Y224874D01*
G03X970022Y224952I-200J0D01*
G01X969995Y225014D01*
X969994Y225017D01*
X969984Y225039D01*
X969980Y225069D01*
Y225117D01*
X969985Y225156D01*
X970009Y225204D01*
X970027Y225226D01*
X970030Y225229D01*
G03X970036Y225236I-1137J981D01*
G01X970041Y225242D01*
X970047Y225248D01*
X970056Y225259D01*
X970081Y225290D01*
G03X970098Y225312I-1180J929D01*
G03X970113Y225332I-1194J911D01*
G03X970408Y226226I-1207J894D01*
G03Y226237I-1502J5D01*
G01Y226265D01*
G03X970404Y226341I-1501J-41D01*
G01X970403Y226353D01*
G03X970380Y226515I-1496J-130D01*
G03X970203Y226984I-1474J-288D01*
G03X970169Y227039I-1294J-762D01*
G03X970093Y227147I-1265J-809D01*
G01X970090Y227150D01*
X970068Y227183D01*
G02X970038Y227287I170J105D01*
G01Y227374D01*
G03X970022Y227452I-200J0D01*
G01X969995Y227514D01*
X969994Y227517D01*
X969984Y227539D01*
X969980Y227569D01*
Y227617D01*
X969985Y227656D01*
X970009Y227704D01*
X970027Y227726D01*
X970030Y227729D01*
G03X970036Y227736I-1137J981D01*
G01X970041Y227742D01*
X970047Y227748D01*
X970056Y227759D01*
X970081Y227790D01*
G03X970098Y227812I-1180J929D01*
G03X970113Y227832I-1194J911D01*
G03X970408Y228726I-1207J894D01*
G03Y228737I-1502J5D01*
G01Y228765D01*
G03X970404Y228841I-1501J-41D01*
G01X970403Y228853D01*
G03X970380Y229015I-1496J-130D01*
G03X970203Y229484I-1474J-288D01*
G03X970169Y229539I-1294J-762D01*
G03X970093Y229647I-1265J-809D01*
G01X970090Y229650D01*
X970068Y229683D01*
G02X970038Y229787I170J105D01*
G01Y229871D01*
G03X970020Y229954I-200J0D01*
G01X969995Y230002D01*
G02X969976Y230084I181J85D01*
G01Y230098D01*
G02X969978Y230121I200J-6D01*
G01X969983Y230147D01*
X970010Y230204D01*
X970029Y230225D01*
G03X970409Y231224I-1124J999D01*
G03Y231226I-1504J1D01*
G01Y231251D01*
X970406Y231309D01*
G03X970370Y231562I-1500J-84D01*
G03X970141Y232082I-1464J-334D01*
G01X970128Y232102D01*
X970091Y232216D01*
G02X970092Y232236I200J0D01*
G01X970470Y236071D01*
G03X970483Y236246I-3908J378D01*
G03X970488Y236456I-3921J198D01*
G01Y243540D01*
Y243542D01*
X970464Y246525D01*
X970440Y249509D01*
Y257742D01*
Y257744D01*
X970437Y257968D01*
X970436Y258087D01*
G02X970528Y258255I200J0D01*
G01X970537Y258260D01*
X970550Y258267D01*
G02X970737Y258259I86J-180D01*
G01X970769Y258239D01*
X970834Y258169D01*
X970846Y258148D01*
X970847Y258146D01*
G03X972160Y257378I1313J738D01*
G03Y260382I0J1502D01*
G03X971118Y259962I0J-1503D01*
G01X971091Y259936D01*
X971009Y259900D01*
G02X970942Y259886I-74J186D01*
G01X970892D01*
X970661Y259979D01*
X970659D01*
X970528Y260031D01*
G02X970443Y260101I80J183D01*
G01X970426Y260125D01*
X970409Y260182D01*
Y260214D01*
X970387Y261980D01*
X970385Y262163D01*
G02X970446Y262309I200J2D01*
G01X970633Y262490D01*
X970654Y262511D01*
G02X970723Y262555I140J-143D01*
G01X970761Y262569D01*
X970802Y262567D01*
G03X970865Y262566I55J1501D01*
G03X971565Y262739I0J1502D01*
G01X971583Y262748D01*
X971635Y262761D01*
G02X971718Y262765I51J-193D01*
G01X971742Y262761D01*
X971756Y262756D01*
G03X972233Y262678I478J1425D01*
G01X972241D01*
G03X972584Y262718I-1J1502D01*
G01X972594Y262721D01*
X972641Y262727D01*
X972642D01*
X972726Y262708D01*
X972737Y262703D01*
G03X972903Y262639I623J1369D01*
G01X972905D01*
G03X973188Y262576I467J1430D01*
G01X973215Y262573D01*
G03X973365Y262566I145J1495D01*
G03X973367I1J1502D01*
G03X974061Y262736I0J1502D01*
G02X974104Y262753I95J-176D01*
G01X974135Y262761D01*
G02X974218Y262764I49J-194D01*
G01X974241Y262760D01*
X974255Y262755D01*
G03X974730Y262678I475J1427D01*
G03X974732I1J1504D01*
G01X974735D01*
G03X976237Y264180I0J1502D01*
G03X974747Y265682I-1502J0D01*
G01X974733D01*
G03X974037Y265511I0J-1502D01*
G01X974016Y265500D01*
X973962Y265486D01*
G02X973881Y265482I-50J194D01*
G01X973859Y265486D01*
X973856Y265487D01*
G03X973365Y265570I-492J-1419D01*
G01X973362D01*
G03X973019Y265530I1J-1502D01*
G01X973008Y265527D01*
X972961Y265521D01*
X972960D01*
X972876Y265540D01*
X972865Y265545D01*
G03X972237Y265682I-627J-1367D01*
G01X972187D01*
G03X971533Y265509I47J-1502D01*
G02X971529Y265507I-91J178D01*
G03X971517Y265501I666J-1347D01*
G01X971516D01*
X971463Y265487D01*
G02X971380Y265484I-49J194D01*
G01X971357Y265488D01*
X971343Y265493D01*
G03X970868Y265570I-475J-1426D01*
G03X970866I-1J-1502D01*
G01X970865D01*
G03X970763Y265567I-7J-1502D01*
G01X970721Y265565D01*
X970684Y265578D01*
G02X970616Y265619I67J189D01*
G01X970401Y265817D01*
G02X970337Y265961I136J147D01*
G01X970324Y266975D01*
X970299Y269048D01*
X970251Y272871D01*
X969755Y334070D01*
G02X969756Y334086I200J-4D01*
G01X969808Y334449D01*
X969944Y335398D01*
X969945Y335406D01*
G02X969947Y335414I195J-44D01*
G01X972944Y345303D01*
X973084Y345765D01*
G02X973275Y345907I191J-58D01*
G01X974132D01*
G02X974332Y345707I0J-200D01*
G01Y345487D01*
G02X974311Y345398I-200J0D01*
G01X974307Y345390D01*
G03X974290Y345310I183J-81D01*
G01Y344895D01*
G03X974326Y344598I1243J0D01*
G01X974332Y344574D01*
Y343939D01*
G02X974326Y343891I-200J1D01*
G01X974312Y343839D01*
X974299Y343806D01*
X974293Y343797D01*
X974277Y343764D01*
G03X974129Y343125I1354J-650D01*
G01Y343111D01*
G03X974299Y342417I1502J0D01*
G01X974305Y342406D01*
X974311Y342394D01*
X974326Y342332D01*
X974332Y342308D01*
Y341536D01*
X974326Y341512D01*
G03X974290Y341215I1207J-297D01*
G01Y336741D01*
G03X974326Y336442I1243J-2D01*
G01X974332Y336418D01*
Y334526D01*
X974326Y334502D01*
G03X974290Y334203I1207J-297D01*
G01Y330032D01*
G03X974297Y329980I200J0D01*
G01X974301Y329966D01*
X974463Y329566D01*
G03X974510Y329496I186J74D01*
G01X974686Y329326D01*
X974688Y329324D01*
X975436Y328575D01*
G03X975484Y328539I143J140D01*
G03X975515Y328526I93J177D01*
G02X975592Y328478I-65J-189D01*
G01X975628Y328442D01*
G02X975647Y328420I-141J-141D01*
G01X975650Y328386D01*
X975653Y328350D01*
G03X975669Y328221I1497J120D01*
G01Y328220D01*
X975671Y328208D01*
G03X976974Y326980I1479J264D01*
G01X977011Y326976D01*
G03X977150Y326970I134J1496D01*
G03X978529Y327875I0J1503D01*
G01Y327876D01*
G02X978603Y327964I184J-79D01*
G01X978627Y327980D01*
X978655Y327988D01*
G02X978711Y327996I56J-192D01*
G01X985892D01*
G02X985924Y327993I-3J-200D01*
G01X985926D01*
G02X986032Y327939I-34J-197D01*
G01X987899Y326073D01*
X989765Y324207D01*
G02X989819Y324101I-143J-140D01*
G01Y324099D01*
G02X989822Y324067I-197J-35D01*
G01Y308158D01*
G02X989781Y308037I-200J0D01*
G01X989773Y308028D01*
X989766Y308021D01*
G03X989753Y308006I144J-138D01*
G01X986369Y304622D01*
G02X986302Y304578I-141J142D01*
G01X986268Y304564D01*
X975533D01*
G03X974290Y303321I0J-1243D01*
G01Y295066D01*
G03X974326Y294952I200J1D01*
G01X974694Y294427D01*
X974696Y294424D01*
X974699Y294420D01*
X974703Y294414D01*
G03X974797Y294341I164J114D01*
G01X975107Y294228D01*
X975109Y294227D01*
G02X975407Y293858I-157J-431D01*
G01Y293854D01*
X975427Y293686D01*
G03X975446Y293621I199J23D01*
G01X975600Y293308D01*
G03X975638Y293255I179J89D01*
G01X979387Y289505D01*
G03X979529Y289446I142J141D01*
G01X985871D01*
G02X986013Y289387I0J-200D01*
G01X986641Y288759D01*
G02X986700Y288617I-141J-142D01*
G01Y285283D01*
G03X986759Y285141I200J0D01*
G01X987687Y284213D01*
G03X987829Y284154I142J141D01*
G01X1038518D01*
G02X1038550Y284151I-3J-200D01*
G01X1038552D01*
G02X1038658Y284097I-34J-197D01*
G01X1038829Y283926D01*
G03X1038971Y283867I142J141D01*
G01X1053911D01*
G02X1053943Y283864I-3J-200D01*
G01X1053945D01*
G02X1054051Y283810I-34J-197D01*
G01X1055096Y282765D01*
X1055097Y282764D01*
G02X1055155Y282628I-142J-141D01*
G02X1055154Y282608I-200J0D01*
G01X1053120Y257272D01*
G03X1053118Y257245I3915J-304D01*
G03X1053111Y257115I3917J-276D01*
G01X1052438Y240321D01*
G02X1052318Y240157I-199J20D01*
G01X1052297Y240151D01*
G03X1051234Y238714I440J-1437D01*
G03X1052184Y237317I1502J0D01*
G01X1052186Y237316D01*
G02X1052280Y237240I-73J-186D01*
G01X1052295Y237216D01*
X1052312Y237157D01*
X1052147Y233024D01*
X1052089Y231595D01*
G02X1052060Y231499I-200J8D01*
G01X1052047Y231477D01*
X1052010Y231442D01*
X1051987Y231429D01*
G03X1051218Y230117I735J-1312D01*
G03X1051884Y228868I1504J0D01*
G01X1051886Y228867D01*
G02X1051953Y228792I-111J-167D01*
G01X1051963Y228771D01*
X1051974Y228722D01*
X1051953Y228189D01*
X1051569Y218595D01*
G03X1051566Y218438I3923J-153D01*
G01Y218377D01*
Y218373D01*
X1051592Y216716D01*
X1051735Y207584D01*
Y207574D01*
X1051348Y196491D01*
G02X1051211Y196321I-199J20D01*
G01X1051006Y196239D01*
X1051004D01*
X1050917Y196204D01*
G02X1050899Y196200I-52J193D01*
G01X1050870Y196195D01*
G02X1050709Y196252I-20J199D01*
G01X1050702Y196259D01*
G03X1049602Y196720I-1100J-1082D01*
G03X1048606Y196356I0J-1545D01*
G01X1048605Y196355D01*
X1048594Y196346D01*
G02X1048477Y196308I-117J162D01*
G01X1048457D01*
G03X1048374Y196290I0J-200D01*
G01X1048334Y196271D01*
G02X1048293Y196258I-81J183D01*
G01X1048211D01*
G02X1048180Y196267I40J196D01*
G01X1048102Y196297D01*
X1048076Y196320D01*
G03X1047818Y196498I-978J-1141D01*
G01X1047783Y196516D01*
G03X1047125Y196678I-679J-1342D01*
G01X1047100D01*
G03X1046219Y196392I1J-1502D01*
G01X1046186Y196367D01*
X1046167Y196352D01*
G02X1046133Y196331I-122J159D01*
G01X1046129Y196329D01*
G02X1046040Y196308I-89J179D01*
G01X1045957D01*
G03X1045874Y196290I0J-200D01*
G01X1045834Y196271D01*
G02X1045793Y196258I-81J183D01*
G01X1045711D01*
G02X1045680Y196267I40J196D01*
G01X1045602Y196297D01*
X1045576Y196320D01*
G03X1045318Y196498I-978J-1141D01*
G01X1045283Y196516D01*
G03X1044625Y196678I-679J-1342D01*
G01X1044600D01*
G03X1043719Y196392I1J-1502D01*
G01X1043686Y196367D01*
X1043667Y196352D01*
G02X1043633Y196331I-122J159D01*
G01X1043629Y196329D01*
G02X1043540Y196308I-89J179D01*
G01X1043457D01*
G03X1043374Y196290I0J-200D01*
G01X1043319Y196265D01*
G02X1043102Y196298I-83J181D01*
G01X1043061Y196334D01*
G03X1042104Y196678I-957J-1160D01*
G01X1042102D01*
G03Y193674I0J-1502D01*
G01X1042103D01*
G03X1043037Y194000I0J1502D01*
G01X1043056Y194015D01*
X1043085Y194028D01*
G02X1043163Y194044I78J-184D01*
G01X1043247D01*
G03X1043330Y194062I0J200D01*
G01X1043370Y194081D01*
G02X1043411Y194094I81J-183D01*
G01X1043493D01*
G02X1043524Y194085I-40J-196D01*
G01X1043602Y194055D01*
X1043628Y194032D01*
G03X1043886Y193854I978J1141D01*
G01X1043921Y193836D01*
G03X1044579Y193674I679J1342D01*
G01X1044603D01*
G03X1045537Y194000I0J1502D01*
G01X1045556Y194015D01*
X1045585Y194028D01*
G02X1045663Y194044I78J-184D01*
G01X1045747D01*
G03X1045830Y194062I0J200D01*
G01X1045870Y194081D01*
G02X1045911Y194094I81J-183D01*
G01X1045993D01*
G02X1046024Y194085I-40J-196D01*
G01X1046102Y194055D01*
X1046128Y194032D01*
G03X1046386Y193854I978J1141D01*
G01X1046421Y193836D01*
G03X1047079Y193674I679J1342D01*
G01X1047103D01*
G03X1048037Y194000I0J1502D01*
G01X1048056Y194015D01*
X1048085Y194028D01*
G02X1048163Y194044I78J-184D01*
G01X1048543D01*
G02X1048658Y194007I-1J-200D01*
G01X1048671Y193997D01*
X1048683Y193988D01*
X1048702Y193969D01*
G02X1048734Y193926I-143J-140D01*
G01X1048756Y193884D01*
G03X1049602Y193632I846J1294D01*
G01X1049604D01*
G03X1050606Y194004I-2J1541D01*
G01X1050628Y194022D01*
X1050691Y194051D01*
G02X1050864Y194048I83J-182D01*
G01X1050890Y194035D01*
X1050892D01*
X1051163Y193905D01*
G02X1051254Y193800I-97J-176D01*
G01X1051249Y193646D01*
X1051248Y193633D01*
G02X1051246Y193617I-199J17D01*
G01X1051233Y193558D01*
G03X1051228Y193525I195J-46D01*
G01Y193051D01*
Y193043D01*
X1051082Y188889D01*
G02X1051081Y188874I-199J6D01*
G01X1046797Y157164D01*
G03X1046762Y156699I3891J-527D01*
G01X1046720Y153984D01*
X1046710Y153941D01*
X1046700Y153921D01*
X1046699Y153920D01*
Y153919D01*
G03X1046490Y153410I3519J-1742D01*
G03X1046292Y152236I3728J-1232D01*
G01X1046262Y150290D01*
Y150226D01*
G03X1046291Y149745I3926J-5D01*
G01X1046292Y149740D01*
X1046293Y149722D01*
G03X1046292Y149667I3891J-98D01*
G01Y149658D01*
G03X1046293Y149578I3892J9D01*
G01X1046318Y148356D01*
X1046313Y148332D01*
G03X1046219Y147537I3832J-856D01*
G01X1046189Y145583D01*
X1046178Y145550D01*
X1046162Y145507D01*
X1046152Y145480D01*
G03X1046141Y145451I3633J-1395D01*
G01Y145449D01*
X1046128Y145416D01*
G03X1046113Y145375I3647J-1358D01*
G01X1046103Y145352D01*
G02X1046025Y145270I-178J91D01*
G03X1045656Y145315I-371J-1508D01*
G01X1045654D01*
G03Y142209I0J-1553D01*
G03X1045795Y142216I-6J1553D01*
G02X1045806Y142207I-121J-159D01*
G01X1045864Y142157D01*
X1045895Y142131D01*
X1045944Y142033D01*
X1045949Y142016D01*
X1045965Y141964D01*
X1045967Y141945D01*
G03X1046392Y140563I3868J433D01*
G01X1046401Y140546D01*
X1046422Y140481D01*
X1046423Y140425D01*
X1046416Y140398D01*
X1046410Y140373D01*
X1046400Y140334D01*
X1046370Y140225D01*
Y140223D01*
X1046299Y139966D01*
G02X1046230Y139874I-187J69D01*
G01X1046033Y139756D01*
X1046031D01*
X1045985Y139729D01*
G02X1045955Y139714I-104J171D01*
G01X1045953D01*
G02X1045940Y139709I-78J184D01*
G01X1045869Y139726D01*
X1045845Y139732D01*
G03X1045512Y139797I-918J-3818D01*
G01X1045510D01*
G03X1045376Y139816I-618J-3878D01*
G01X1045374D01*
G03X1044944Y139842I-452J-3901D01*
G01X1044894D01*
G03X1042819Y139230I30J-3927D01*
G01X1042811Y139232D01*
X1042795Y139235D01*
G03X1042525Y139259I-267J-1478D01*
G01X1042523D01*
G03X1041021Y137757I0J-1502D01*
G01Y137752D01*
G03X1041135Y137183I1502J5D01*
G01X1041142Y137166D01*
X1041168Y137103D01*
X1041173Y137081D01*
X1041155Y137019D01*
G03X1040996Y135946I3768J-1107D01*
G01Y135902D01*
G03X1041337Y134315I3927J14D01*
G02X1041349Y134277I-184J-79D01*
G01X1041363Y134217D01*
G02Y134213I-200J-2D01*
G01X1041349Y134153D01*
G02X1041337Y134115I-196J41D01*
G03X1040996Y132515I3586J-1601D01*
G01Y132513D01*
G03X1041029Y132006I3927J1D01*
G03X1041102Y131609I3894J511D01*
G03X1041173Y131351I3819J912D01*
G01X1041166Y131320D01*
X1041157Y131298D01*
G03X1041023Y130760I1366J-626D01*
G01Y130743D01*
G03X1041021Y130670I1500J-78D01*
G01Y130640D01*
G03X1042523Y129168I1502J30D01*
G01X1042524D01*
G03X1042751Y129185I2J1502D01*
G02X1042885Y129159I31J-197D01*
G03X1044923Y128588I2039J3356D01*
G01X1044924D01*
G03X1046961Y129158I-1J3927D01*
G02X1047094Y129185I104J-171D01*
G03X1047327Y129168I225J1485D01*
G01X1047330D01*
G03X1047790Y129242I-6J1501D01*
G01X1047844Y129260D01*
X1047889Y129256D01*
G02X1048002Y129208I-18J-200D01*
G01X1048079Y129152D01*
X1048081Y129151D01*
X1048250Y129030D01*
G02X1048292Y128987I-120J-160D01*
G03X1048298Y128979I163J116D01*
G01X1048299Y128978D01*
X1048297Y128890D01*
Y128889D01*
G03X1048296Y128829I3925J-95D01*
G01Y128774D01*
G03X1048637Y127228I3926J55D01*
G02X1048649Y127190I-184J-79D01*
G01X1048663Y127130D01*
G02Y127126I-200J-2D01*
G01X1048645Y127047D01*
X1048638Y127031D01*
G03X1048296Y125428I3585J-1603D01*
G01Y125397D01*
G03X1048299Y125282I3927J45D01*
G03X1048302Y125223I3923J170D01*
G01Y125218D01*
G02X1048256Y125085I-200J-5D01*
G01X1048141Y124960D01*
G02X1048139Y124958I-142J140D01*
G01X1048108Y124925D01*
X1048068D01*
X1048024Y124930D01*
X1047962Y124944D01*
X1047944Y124952D01*
G03X1047324Y125086I-620J-1368D01*
G01X1047288D01*
G03X1047059Y125064I29J-1502D01*
G03X1047037Y125060I258J-1480D01*
G01X1047026Y125058D01*
G03X1044923Y125668I-2102J-3316D01*
G03X1042819Y125057I-1J-3926D01*
G01X1042815Y125058D01*
X1042788Y125063D01*
G03X1042560Y125086I-264J-1479D01*
G01X1042517D01*
G03X1041021Y123584I6J-1502D01*
G01Y123579D01*
G03X1041135Y123010I1502J5D01*
G01X1041142Y122993D01*
X1041168Y122930D01*
X1041173Y122908D01*
X1041155Y122846D01*
G03X1040996Y121750I3768J-1106D01*
G01Y121715D01*
G03X1041100Y120844I3927J27D01*
G03X1041338Y120139I3823J898D01*
G01X1041345Y120123D01*
X1041363Y120044D01*
G02Y120040I-200J-2D01*
G01X1041345Y119961D01*
X1041338Y119945D01*
G03X1040996Y118342I3585J-1603D01*
G03X1041055Y117663I3927J-1D01*
G03X1041135Y117307I3867J682D01*
G03X1041174Y117175I3785J1046D01*
G01X1041167Y117146D01*
G03X1041021Y116499I1357J-646D01*
G01Y116497D01*
G03X1042523Y114995I1502J0D01*
G01X1042526D01*
G03X1042803Y115021I-1J1502D01*
G01X1042819Y115024D01*
X1042822Y115025D01*
G03X1044923Y114416I2100J3317D01*
G03X1044925I1J3926D01*
G03X1047018Y115021I-1J3926D01*
G01X1047062Y115017D01*
X1047070Y115016D01*
G03X1047322Y114995I250J1481D01*
G01X1047326D01*
G03X1047721Y115048I0J1502D01*
G01X1047728Y115050D01*
X1047733Y115051D01*
X1047748Y115055D01*
X1047803Y115073D01*
X1047805D01*
X1047826Y115081D01*
X1047876Y115086D01*
X1047899Y115083D01*
G02X1047941Y115072I-29J-198D01*
G02X1047989Y115046I-70J-187D01*
G01X1048237Y114865D01*
G02X1048240Y114863I-110J-168D01*
G01X1048259Y114849D01*
G02X1048285Y114824I-125J-156D01*
G02X1048299Y114805I-154J-128D01*
G01X1048297Y114716D01*
Y114715D01*
G03X1048296Y114656I3925J-96D01*
G01Y114601D01*
G03X1048637Y113055I3926J55D01*
G02X1048649Y113017I-184J-79D01*
G01X1048663Y112957D01*
G02Y112953I-200J-2D01*
G01X1048645Y112874D01*
X1048638Y112858D01*
G03X1048296Y111255I3585J-1603D01*
G03X1048315Y110872I3927J3D01*
G03X1048356Y110573I3908J384D01*
G03X1048474Y110089I3866J686D01*
G01X1048467Y110059D01*
X1048458Y110040D01*
G03X1048323Y109500I1365J-628D01*
G01Y109483D01*
G03X1048321Y109410I1500J-78D01*
G01Y109380D01*
G03X1049823Y107908I1502J30D01*
G03X1050085Y107931I0J1502D01*
G01X1050123Y107937D01*
G03X1050327Y107816I2104J3315D01*
G01X1050329D01*
X1050378Y107788D01*
G02X1050393Y107751I-177J-93D01*
G01X1050471Y107462D01*
X1050470Y107408D01*
X1050463Y107382D01*
X1050446Y107321D01*
X1050434Y107300D01*
G03X1050240Y106562I1308J-738D01*
G01Y106526D01*
X1050241Y106510D01*
Y106507D01*
G03X1050250Y106388I1501J54D01*
G03X1050417Y105854I1492J173D01*
G03X1050815Y105379I1325J706D01*
G01X1050823Y105373D01*
X1050851Y105346D01*
X1050902Y105284D01*
X1050912Y105263D01*
X1050922Y105217D01*
X1050906Y104911D01*
X1050904Y104862D01*
X1050832Y104738D01*
X1050814Y104720D01*
X1050770Y104675D01*
X1050745Y104658D01*
G03X1050081Y103411I839J-1247D01*
G03X1053085I1502J0D01*
G03X1052497Y104603I-1502J0D01*
G01X1052486Y104611D01*
X1052460Y104637D01*
X1052442Y104660D01*
G02X1052406Y104771I164J114D01*
G01X1052421Y105105D01*
X1052440Y105142D01*
X1052444Y105151D01*
X1052494Y105235D01*
X1052511Y105252D01*
X1052555Y105297D01*
X1052580Y105314D01*
G03X1053244Y106557I-838J1247D01*
G01Y106570D01*
G03X1053174Y107015I-1502J-8D01*
G01X1053165Y107044D01*
G02X1053176Y107196I190J63D01*
G01X1053290Y107425D01*
X1053302Y107444D01*
G02X1053333Y107477I160J-120D01*
G01X1053353Y107494D01*
X1053400Y107509D01*
G03X1054295Y107920I-1178J3745D01*
G01X1054327D01*
X1054342Y107918D01*
X1054343D01*
G03X1054391Y107913I180J1492D01*
G01X1054397D01*
X1054411Y107911D01*
G03X1054523Y107907I110J1499D01*
G03X1054599Y107909I-2J1503D01*
G01X1054637Y107912D01*
G03X1055726Y108510I-114J1498D01*
G01X1055734Y108520D01*
G03X1057909Y109624I-602J3880D01*
G01X1063429Y115143D01*
X1063441Y115149D01*
G03X1063453Y115155I-666J1347D01*
G01X1063457Y115157D01*
G03X1064114Y115814I-682J1339D01*
G01X1064116Y115818D01*
G03X1064122Y115830I-1341J678D01*
G01X1064128Y115842D01*
X1064598Y116312D01*
X1069322Y121037D01*
G03X1069685Y121454I-2773J2780D01*
G03X1069909Y121785I-3136J2363D01*
G01X1069913Y121792D01*
X1069937Y121825D01*
G03X1070146Y122072I-2864J2635D01*
G03X1070342Y122346I-3064J2399D01*
G03X1070407Y122450I-3267J2114D01*
G01X1070411Y122458D01*
X1070417Y122467D01*
G03X1070441Y122507I-3325J2022D01*
G03X1070473Y122562I-3348J1985D01*
G01Y122563D01*
X1070497Y122607D01*
X1070501Y122615D01*
G03X1070673Y122977I-3424J1849D01*
G01X1073108Y128855D01*
X1073173Y129011D01*
X1073279Y129264D01*
G02X1073311Y129317I185J-76D01*
G01X1073331Y129339D01*
X1073365Y129358D01*
X1073367Y129359D01*
G03X1074135Y130649I-734J1311D01*
G01Y130676D01*
G03X1074079Y131081I-1503J-1D01*
G01Y131083D01*
G02X1074087Y131212I193J53D01*
G01X1077960Y140565D01*
X1078878Y142783D01*
X1079013Y143108D01*
X1079652Y144651D01*
X1080221Y146026D01*
G03X1080408Y146596I-3593J1495D01*
G01X1080410Y146606D01*
X1080411Y146610D01*
X1080513Y146854D01*
G03X1080760Y147684I-3617J1528D01*
G03X1080822Y148377I-3865J695D01*
G01Y148379D01*
G03X1080821Y148442I-3927J-31D01*
G01Y148443D01*
X1080813Y148939D01*
X1080782Y150807D01*
X1080763Y151942D01*
G03X1080680Y152682I-3926J-66D01*
G01X1080483Y153623D01*
X1079006Y160680D01*
X1079005Y160683D01*
G02X1079088Y160884I197J36D01*
G01X1079390Y161093D01*
G02X1079611Y161098I114J-164D01*
G03X1080413Y160866I802J1270D01*
G03X1081440Y161272I0J1502D01*
G01X1081441Y161273D01*
G02X1081512Y161315I135J-147D01*
G02X1081577Y161326I65J-189D01*
G01X1081849D01*
G02X1081914Y161315I0J-200D01*
G02X1081985Y161273I-64J-189D01*
G01X1081986Y161272D01*
G03X1083013Y160866I1027J1096D01*
G03Y163870I0J1502D01*
G03X1081986Y163464I0J-1502D01*
G01X1081985Y163463D01*
G02X1081914Y163421I-135J147D01*
G02X1081849Y163410I-65J189D01*
G01X1081577D01*
G02X1081512Y163421I0J200D01*
G02X1081441Y163463I64J189D01*
G01X1081440Y163464D01*
G03X1080413Y163870I-1027J-1096D01*
G03X1080213Y163857I-3J-1502D01*
G03X1079169Y163210I200J-1489D01*
G01Y163209D01*
G02X1079080Y163137I-165J113D01*
G02X1078965Y163126I-76J185D01*
G01X1078604Y163196D01*
G02X1078570Y163206I39J196D01*
G02X1078446Y163352I72J187D01*
G01X1077328Y168694D01*
X1076292Y173639D01*
Y173643D01*
X1073946Y186051D01*
X1072534Y193521D01*
X1072273Y194902D01*
G02X1072270Y194936I197J35D01*
G01X1072112Y205087D01*
X1072089Y206564D01*
G02X1072110Y206657I200J4D01*
G01X1072157Y206751D01*
X1072185Y206786D01*
X1072202Y206799D01*
G03X1072484Y208860I-936J1178D01*
G01X1072459Y208894D01*
X1072444Y208913D01*
G02X1072423Y208947I159J122D01*
G01X1072421Y208951D01*
G02X1072400Y209040I179J89D01*
G01Y209123D01*
G03X1072382Y209206I-200J0D01*
G01X1072357Y209261D01*
G02X1072390Y209478I181J83D01*
G01X1072426Y209519D01*
G03X1072770Y210455I-1160J957D01*
G01Y210479D01*
G03X1072484Y211360I-1502J-1D01*
G01X1072459Y211394D01*
X1072444Y211413D01*
G02X1072423Y211447I159J122D01*
G01X1072421Y211451D01*
G02X1072400Y211540I179J89D01*
G01Y211623D01*
G03X1072382Y211706I-200J0D01*
G01X1072357Y211761D01*
G02X1072390Y211978I181J83D01*
G01X1072426Y212019D01*
G03X1072770Y212955I-1160J957D01*
G01Y212979D01*
G03X1072484Y213860I-1502J-1D01*
G01X1072459Y213894D01*
X1072444Y213913D01*
G02X1072423Y213947I159J122D01*
G01X1072421Y213951D01*
G02X1072400Y214040I179J89D01*
G01Y214123D01*
G03X1072382Y214206I-200J0D01*
G01X1072360Y214250D01*
G02X1072391Y214471I180J87D01*
G01Y214472D01*
G03X1072775Y215477I-1123J1005D01*
G01Y215478D01*
G03X1072193Y216668I-1508J0D01*
G01X1072171Y216685D01*
X1072147Y216716D01*
X1072084Y216842D01*
X1072086Y216893D01*
X1072154Y218860D01*
X1072188Y219838D01*
X1072211Y220501D01*
X1072213Y220548D01*
X1072215Y220612D01*
X1072265Y222038D01*
X1072276Y222339D01*
Y222341D01*
X1072285Y222554D01*
G02X1072287Y222569I199J-19D01*
G01X1072293Y222590D01*
G02X1072314Y222639I193J-54D01*
G01X1072325Y222658D01*
X1072343Y222677D01*
X1072347Y222681D01*
G03X1072770Y223715I-1079J1045D01*
G01Y223732D01*
G03X1072432Y224677I-1502J-4D01*
G01X1072411Y224703D01*
X1072362Y224833D01*
X1072364Y224874D01*
X1072374Y225138D01*
G02X1072385Y225196I200J-8D01*
G01X1072399Y225236D01*
X1072422Y225264D01*
X1072423Y225265D01*
G03X1072441Y225287I-1154J962D01*
G01X1072797Y225720D01*
G03X1072784Y225988I-155J127D01*
G01X1072758Y226014D01*
X1072762Y226069D01*
Y226075D01*
G03X1072770Y226225I-1494J155D01*
G01Y226262D01*
G03X1072500Y227086I-1502J-36D01*
G01X1072494Y227094D01*
X1072484Y227111D01*
X1072465Y227137D01*
X1072455Y227171D01*
X1072445Y227204D01*
X1072450Y227333D01*
Y227335D01*
X1072461Y227641D01*
X1072464Y227727D01*
X1072465Y227756D01*
X1072502Y227870D01*
X1072519Y227894D01*
G03X1072527Y227906I-1246J839D01*
G01X1072529Y227909D01*
X1072536Y227919D01*
X1072545Y227933D01*
G03X1072770Y228712I-1278J791D01*
G01Y228727D01*
G03X1072570Y229476I-1502J0D01*
G01X1072557Y229498D01*
X1072529Y229598D01*
X1072530Y229630D01*
X1072543Y230002D01*
X1072557Y230405D01*
G02X1072566Y230456I200J-9D01*
G01X1072572Y230477D01*
X1072582Y230497D01*
X1072584Y230500D01*
X1072585Y230502D01*
X1072587Y230505D01*
G03X1072770Y231200I-1321J719D01*
G01Y231231D01*
G03X1072635Y231850I-1502J-3D01*
G01X1072634Y231852D01*
X1072629Y231863D01*
X1072622Y231885D01*
X1072610Y231920D01*
X1072712Y234847D01*
X1072971Y242259D01*
X1073156Y247561D01*
X1073303Y251757D01*
X1073443Y255266D01*
X1073480Y256183D01*
Y256187D01*
X1073562Y257208D01*
G02X1073572Y257244I197J-35D01*
G02X1073650Y257339I186J-73D01*
G01X1073683Y257361D01*
X1073830Y257457D01*
X1073845Y257463D01*
X1073873Y257476D01*
X1073923Y257481D01*
G02X1073956Y257480I10J-200D01*
G01X1073999Y257471D01*
X1074013Y257466D01*
G03X1074520Y257378I507J1414D01*
G01X1074533D01*
G03X1076024Y258880I-11J1502D01*
G03X1074522Y260382I-1502J0D01*
G03X1074230Y260354I-3J-1502D01*
G01X1074183Y260345D01*
X1074139Y260357D01*
G02X1074057Y260401I51J193D01*
G01X1073941Y260506D01*
X1073908Y260536D01*
G02X1073843Y260700I134J148D01*
G01X1073931Y261802D01*
X1073943Y261953D01*
X1073981Y262426D01*
G02X1074046Y262549I198J-26D01*
G01X1074076Y262574D01*
X1074130Y262616D01*
X1074191Y262663D01*
G02X1074271Y262695I113J-165D01*
G01X1074339D01*
X1074355Y262692D01*
G03X1074596Y262673I239J1488D01*
G01X1074597D01*
G03X1075538Y263003I0J1507D01*
G01X1075539Y263004D01*
X1075566Y263025D01*
X1075597Y263036D01*
G02X1075665Y263048I68J-188D01*
G01X1075742D01*
G03X1075825Y263066I0J200D01*
G01X1075880Y263091D01*
G02X1076097Y263058I83J-181D01*
G01X1076138Y263022D01*
G03X1077095Y262678I957J1160D01*
G01X1077097D01*
G03Y265682I0J1502D01*
G03X1076165Y265358I0J-1502D01*
G01X1076146Y265343D01*
X1076124Y265333D01*
X1076103Y265322D01*
X1076059Y265312D01*
X1075952D01*
G03X1075869Y265294I0J-200D01*
G01X1075826Y265272D01*
G02X1075771Y265254I-89J179D01*
G02X1075717Y265252I-34J197D01*
G01X1075679Y265257D01*
X1075627Y265282D01*
X1075603Y265302D01*
G03X1074597Y265687I-1006J-1122D01*
G03X1074589I-4J-1507D01*
G01X1074536D01*
X1074451Y265736D01*
G02X1074410Y265768I101J172D01*
G01X1074371Y265809D01*
G02X1074369Y265811I140J142D01*
G01X1074297Y265888D01*
X1074292Y265893D01*
X1074279Y265932D01*
G02X1074269Y266012I189J64D01*
G01X1077769Y309618D01*
G02X1077799Y309709I199J-15D01*
G01X1077804Y309716D01*
G03X1078073Y310559I-1233J858D01*
G01Y310587D01*
G03X1078065Y310736I-1502J-6D01*
G01X1078063Y310748D01*
G03X1078056Y310800I-1492J-174D01*
G01Y310802D01*
G03X1078034Y310912I-1482J-239D01*
G01Y310914D01*
G03X1078023Y310958I-1462J-342D01*
G03X1077925Y311224I-1452J-384D01*
G01Y311225D01*
G02X1077906Y311317I181J85D01*
G01X1078000Y312483D01*
G02X1078039Y312586I200J-17D01*
G01X1078073Y312631D01*
X1078112Y312646D01*
G03X1079045Y314481I-510J1414D01*
G03X1078346Y315366I-1443J-421D01*
G01X1078345D01*
G02X1078337Y315371I102J172D01*
G02X1078245Y315556I107J169D01*
G01X1078403Y317519D01*
X1078406Y317553D01*
G02X1078446Y317652I199J-23D01*
G01X1078450Y317657D01*
G03X1078464Y317674I-1152J963D01*
G01X1078475Y317688D01*
X1078495Y317706D01*
G02X1078528Y317727I123J-158D01*
G01X1078591Y317757D01*
X1078602Y317762D01*
X1078631Y317773D01*
G02X1078674Y317782I62J-190D01*
G02X1078693Y317783I20J-199D01*
G01X1078782D01*
G02X1078799Y317782I-3J-200D01*
G01X1078843Y317774D01*
G02X1078885Y317759I-46J-194D01*
G01X1078896Y317753D01*
X1078930Y317735D01*
G03X1079311Y317593I816J1607D01*
G03X1079673Y317541I436J1749D01*
G01X1079681D01*
X1079690Y317540D01*
X1079744D01*
G03X1079748I2J1803D01*
G03X1081550Y319342I0J1802D01*
G01Y322742D01*
G03X1079748Y324544I-1802J0D01*
G03X1079551Y324534I-7J-1802D01*
G03X1079426Y324516I194J-1792D01*
G01X1079424D01*
G03X1079328Y324495I337J-1771D01*
G01X1079303Y324489D01*
X1079255Y324490D01*
X1079224Y324498D01*
G02X1079151Y324535I52J193D01*
G01X1079048Y324624D01*
G02X1078986Y324750I137J146D01*
G01Y324785D01*
X1079070Y325828D01*
X1079119Y326433D01*
G02X1079196Y326567I198J-25D01*
G01X1079215Y326580D01*
X1079379Y326673D01*
X1079430Y326674D01*
X1079480Y326675D01*
X1079526Y326652D01*
X1079527Y326651D01*
G03X1080350Y326452I823J1604D01*
G01X1080351D01*
G03X1082154Y328255I0J1803D01*
G01Y331655D01*
G03X1080351Y333458I-1803J0D01*
G01X1080347D01*
G03X1080343I-2J-1803D01*
G01X1080342D01*
G03X1080009Y333427I0J-1804D01*
G01X1080001Y333426D01*
X1079953Y333421D01*
G02X1079771Y333504I-19J199D01*
G01X1079757Y333525D01*
X1079741Y333551D01*
X1079736Y333560D01*
X1079728Y333571D01*
G03X1079726Y333574I-168J-110D01*
G01X1079715Y333589D01*
X1079707Y333621D01*
G02X1079701Y333688I193J51D01*
G01X1080542Y344172D01*
G02X1080571Y344261I200J-16D01*
G01X1080629Y344354D01*
X1080660Y344386D01*
X1080679Y344398D01*
G03X1080843Y346799I-817J1262D01*
G01X1080837Y346804D01*
X1080836Y346805D01*
G02X1080767Y346963I131J151D01*
G01X1080810Y347489D01*
G02X1080946Y347651I198J-28D01*
G01X1081331Y347751D01*
G02X1081531Y347676I41J-196D01*
G03X1082787Y346999I1256J827D01*
G03Y350003I0J1502D01*
G03X1081687Y349524I0J-1503D01*
G01X1081671Y349507D01*
G02X1081602Y349469I-129J153D01*
G02X1081462Y349477I-59J191D01*
G01X1081115Y349630D01*
G02X1080995Y349817I80J183D01*
G01X1082263Y365609D01*
X1085851Y410316D01*
G03X1085862Y410511I-3914J319D01*
G01X1087684Y470607D01*
G03X1087686Y470724I-3925J126D01*
G01Y470728D01*
G03X1087685Y470766I-3925J-84D01*
G01Y470768D01*
X1087472Y490564D01*
X1087382Y498941D01*
X1086934Y540537D01*
G02X1087006Y540693I200J2D01*
G02X1087070Y540729I128J-153D01*
G01X1087249Y540790D01*
X1087438Y540854D01*
G02X1087653Y540781I55J-193D01*
G03X1089094Y540060I1442J1081D01*
G01X1089096D01*
G03X1090898Y541862I0J1802D01*
G01Y545262D01*
G03X1087294I-1802J0D01*
G01Y544427D01*
G02X1087095Y544227I-200J0D01*
G01X1087091D01*
G02X1086892Y544425I1J200D01*
G01X1086883Y545269D01*
X1086859Y547465D01*
X1086839Y549254D01*
X1086847Y549261D01*
X1086961Y549363D01*
G02X1087095Y549415I134J-148D01*
G01X1087115D01*
X1087125Y549414D01*
G03X1087288Y549405I164J1493D01*
G03X1088220Y549729I0J1502D01*
G01X1088239Y549744D01*
X1088263Y549756D01*
G02X1088309Y549771I85J-181D01*
G02X1088348Y549775I40J-196D01*
G01X1088433D01*
G03X1088516Y549793I0J200D01*
G01X1088571Y549818D01*
G02X1088788Y549785I83J-181D01*
G01X1088829Y549749D01*
G03X1089782Y549405I957J1160D01*
G01X1089788D01*
G03X1091290Y550892I0J1502D01*
G01Y550909D01*
G03X1091004Y551790I-1502J-1D01*
G01X1090979Y551823D01*
X1090964Y551842D01*
G02X1090943Y551876I159J122D01*
G01X1090941Y551880D01*
G02X1090920Y551969I179J89D01*
G01Y552052D01*
G03X1090902Y552135I-200J0D01*
G01X1090877Y552190D01*
G02X1090910Y552407I181J83D01*
G01X1090946Y552448D01*
G03X1091290Y553405I-1160J957D01*
G01Y553407D01*
G03X1089788Y554909I-1502J0D01*
G03X1088856Y554585I0J-1502D01*
G01X1088837Y554570D01*
X1088815Y554560D01*
X1088794Y554549D01*
X1088750Y554539D01*
X1088643D01*
G03X1088560Y554521I0J-200D01*
G01X1088516Y554499D01*
G02X1088295Y554530I-87J180D01*
G01X1088294D01*
G03X1087289Y554914I-1005J-1123D01*
G01X1087287D01*
G03X1087069Y554898I1J-1507D01*
G01X1087017Y554891D01*
X1086920Y554928D01*
G02X1086879Y554952I80J183D01*
G01X1086869Y554960D01*
X1086862Y554966D01*
X1086822Y555000D01*
X1086813Y555008D01*
X1086796Y555044D01*
G02X1086777Y555128I181J85D01*
G01X1086641Y567662D01*
X1086640Y567765D01*
X1086637Y568030D01*
G02X1086682Y568159I200J3D01*
G01X1086879Y568377D01*
G02X1086997Y568433I140J-143D01*
G01X1087000D01*
G03X1087047Y568438I-135J1496D01*
G01X1087048D01*
G02X1087179Y568408I23J-199D01*
G01X1087412Y568245D01*
G02X1087484Y568145I-118J-161D01*
G01X1087487Y568131D01*
G03X1088949Y566973I1462J344D01*
G01X1088950D01*
G03X1089668Y567156I-1J1502D01*
G01X1089670Y567157D01*
G02X1089769Y567181I95J-176D01*
G01X1089818Y567180D01*
X1089979Y567085D01*
G02X1090056Y566987I-111J-166D01*
G01Y566926D01*
G03X1091558Y565427I1502J3D01*
G01X1091570D01*
G03X1093072Y566928I0J1502D01*
G01Y566930D01*
G03X1093066Y567058I-1502J-6D01*
G01X1093065Y567072D01*
G02Y567080I200J4D01*
G01X1093066Y567094D01*
G03X1093072Y567227I-1496J134D01*
G01Y567229D01*
G03X1092573Y568348I-1504J0D01*
G01X1092541Y568377D01*
X1092524Y568415D01*
X1092511Y568443D01*
X1092498Y568548D01*
X1092497Y568554D01*
X1092536Y568615D01*
G03X1092774Y569426I-1263J811D01*
G03X1092772Y569512I-1502J8D01*
G02X1092773Y569540I200J7D01*
G03X1092784Y569723I-1502J182D01*
G01Y569726D01*
G03X1091273Y571238I-1512J0D01*
G01X1091272D01*
G03X1091109Y571228I11J-1511D01*
G01X1091108D01*
G02X1090967Y571266I-22J199D01*
G01X1090845Y571357D01*
X1090843D01*
X1090760Y571418D01*
X1090749Y571430D01*
X1090721Y571458D01*
X1090688Y571516D01*
X1090682Y571548D01*
G03X1089206Y572765I-1476J-287D01*
G03X1089072Y572759I0J-1503D01*
G01X1089029Y572754D01*
G03X1087843Y571894I178J-1493D01*
G01X1087840Y571887D01*
X1087832Y571871D01*
X1087819Y571838D01*
X1087793Y571811D01*
G02X1087741Y571772I-144J138D01*
G01X1087597Y571711D01*
X1087595Y571709D01*
X1087518Y571678D01*
G02X1087477Y571668I-68J188D01*
G01X1087448Y571664D01*
X1087385Y571676D01*
X1087369Y571682D01*
G03X1087285Y571709I-513J-1453D01*
G01X1087251Y571719D01*
X1087136Y571803D01*
X1087116Y571834D01*
X1087115Y571835D01*
X1087022Y571981D01*
Y571983D01*
X1087014Y571995D01*
Y572070D01*
G03X1087009Y572198I-1502J5D01*
G01X1087008Y572203D01*
G03X1087007Y572218I-1499J-92D01*
G03X1087009Y572235I-1491J184D01*
G01Y572237D01*
X1087010Y572245D01*
G03X1087015Y572370I-1498J123D01*
G01Y572371D01*
G03X1086619Y573387I-1503J-1D01*
G02X1086617Y573389I140J142D01*
G01X1086604Y573404D01*
X1086579Y573470D01*
X1086558Y575364D01*
X1086533Y577660D01*
Y577674D01*
X1086689Y580200D01*
X1088066Y602590D01*
Y602594D01*
X1108496Y864509D01*
X1109352Y875486D01*
X1110334Y887632D01*
X1110693Y892072D01*
X1110900Y894632D01*
X1110968Y895458D01*
X1110971Y895477D01*
G02X1111123Y895629I195J-43D01*
G01X1111125D01*
G02X1111166Y895634I45J-195D01*
G01X1120298D01*
G02X1120478Y895520I0J-200D01*
G01X1120480Y895515D01*
Y895514D01*
X1120488Y895496D01*
G02X1120489Y895493I-189J-65D01*
G01X1120495Y895471D01*
X1121372Y878659D01*
X1123700Y833936D01*
X1126095Y787911D01*
X1128290Y745743D01*
X1128598Y739833D01*
X1128896Y734109D01*
Y734089D01*
G02X1128891Y734045I-200J0D01*
G03X1127887Y732571I580J-1474D01*
G03X1129038Y731048I1583J0D01*
G02X1129059Y730975I-178J-91D01*
G01X1137011Y578196D01*
X1137337Y571942D01*
X1137455Y569670D01*
Y569652D01*
G02X1137413Y569530I-200J1D01*
G01X1137392Y569504D01*
X1137339Y569469D01*
X1137304Y569459D01*
G03X1136168Y568000I369J-1459D01*
G03X1137411Y566518I1505J0D01*
G01X1137428Y566515D01*
X1137458Y566505D01*
X1137493Y566492D01*
G02X1137507Y566485I-82J-182D01*
G01X1137533Y566471D01*
G02X1137592Y566417I-103J-172D01*
G02X1137600Y566405I-162J-117D01*
G01X1137626Y566363D01*
X1137629Y566310D01*
X1137644Y566032D01*
X1137652Y565881D01*
X1137653Y565869D01*
Y565868D01*
X1137660Y565729D01*
X1137701Y564939D01*
X1137724Y564499D01*
X1137728Y564420D01*
X1137732Y564348D01*
Y564332D01*
G02X1137642Y564165I-200J0D01*
G01X1137620Y564151D01*
X1137610Y564146D01*
G03X1137749Y561392I667J-1347D01*
G01X1137750D01*
X1137763Y561387D01*
X1137787Y561374D01*
G02X1137895Y561208I-91J-178D01*
G01X1137901Y561100D01*
Y561098D01*
X1137933Y560444D01*
Y560433D01*
G02X1137812Y560250I-200J1D01*
G01X1137795Y560244D01*
X1137785Y560241D01*
G03X1136709Y558800I427J-1441D01*
G03X1137942Y557319I1506J0D01*
G01X1137943D01*
X1137958Y557316D01*
G02X1138057Y557255I-51J-194D01*
G01X1138080Y557229D01*
X1138092Y557201D01*
G02X1138107Y557143I-184J-79D01*
G01Y557135D01*
X1138120Y556890D01*
X1138121Y556874D01*
X1138124Y556815D01*
X1138128Y556736D01*
X1138137Y556563D01*
G02X1138079Y556410I-199J-12D01*
G01X1138025Y556356D01*
X1137996Y556341D01*
G03X1137859Y556263I674J-1342D01*
G03X1137170Y555000I813J-1263D01*
G03X1138118Y553603I1503J0D01*
G01X1138144Y553592D01*
X1138164Y553577D01*
G02X1138204Y553537I-120J-160D01*
G01X1138249Y553477D01*
Y553475D01*
X1138264Y553455D01*
G02X1138304Y553346I-160J-120D01*
G01X1138326Y552936D01*
X1138336Y552743D01*
X1138348Y552507D01*
X1138358Y552312D01*
X1138390Y551703D01*
X1138393Y551640D01*
X1138396Y551591D01*
Y551572D01*
G02X1138371Y551476I-200J1D01*
G01X1138358Y551453D01*
X1138289Y551375D01*
G02X1138249Y551341I-148J134D01*
G01X1138227Y551328D01*
X1138147Y551286D01*
X1138125Y551282D01*
X1138121Y551281D01*
X1138115Y551280D01*
G03X1136871Y549800I258J-1480D01*
G01Y549762D01*
G03X1136877Y549662I1502J40D01*
G01X1136878Y549653D01*
Y549647D01*
X1136880Y549632D01*
Y549629D01*
G03X1137161Y548912I1494J172D01*
G03X1137237Y548817I1211J891D01*
G01X1137239Y548815D01*
X1137281Y548765D01*
X1137293Y548730D01*
G02X1137302Y548648I-190J-62D01*
G01X1137298Y548604D01*
Y548602D01*
X1137280Y548362D01*
G02X1137265Y548307I-198J25D01*
G01X1137248Y548272D01*
X1137222Y548238D01*
X1137206Y548225D01*
G03X1136671Y547076I967J-1149D01*
G01Y547075D01*
G03X1138173Y545573I1502J0D01*
G01X1138181D01*
G03X1138304Y545577I13J1503D01*
G01X1138327Y545579D01*
X1138339Y545580D01*
X1138376Y545568D01*
G02X1138444Y545529I-64J-190D01*
G01X1138660Y545341D01*
G02X1138726Y545223I-131J-151D01*
G02X1138728Y545201I-198J-29D01*
G01X1138802Y543789D01*
X1138854Y542787D01*
X1138887Y542141D01*
G02X1138863Y542036I-200J-10D01*
G02X1138764Y541946I-176J95D01*
G01X1138744Y541940D01*
G03X1138543Y541864I430J-1440D01*
G03X1137671Y540500I631J-1364D01*
G03X1138811Y539042I1502J0D01*
G01X1138835Y539036D01*
X1138917Y538992D01*
X1138940Y538973D01*
X1138958Y538955D01*
X1139015Y538889D01*
G02X1139020Y538883I-151J-131D01*
G01X1139021Y538882D01*
Y538881D01*
G02X1139050Y538833I-155J-126D01*
G02X1139063Y538786I-185J-77D01*
G01X1139078Y538482D01*
X1139119Y537693D01*
X1139146Y537177D01*
X1139158Y536950D01*
X1139261Y534966D01*
X1139433Y531636D01*
G02X1139395Y531527I-200J8D01*
G02X1139298Y531455I-162J117D01*
G01X1139285Y531451D01*
G03X1138171Y530000I388J-1451D01*
G03X1138184Y529800I1502J-3D01*
G03X1139407Y528521I1489J200D01*
G01X1139441Y528515D01*
X1139517Y528473D01*
G02X1139607Y528323I-110J-168D01*
G01X1139608Y528306D01*
Y528304D01*
X1146920Y387822D01*
X1153890Y253880D01*
Y253868D01*
X1153861Y245880D01*
G02X1153760Y245707I-200J1D01*
G01X1153572Y245600D01*
X1153567Y245597D01*
X1153472Y245643D01*
G03X1153467Y245645I-77J-185D01*
G01X1153426Y245662D01*
X1153425Y245663D01*
X1153423Y245664D01*
X1153414Y245668D01*
G03X1153175Y245752I-616J-1370D01*
G01X1153159Y245756D01*
G03X1152809Y245799I-357J-1459D01*
G01X1152794D01*
G03X1152441Y245756I4J-1502D01*
G01X1152430Y245753D01*
X1152406Y245750D01*
G02X1152229Y245819I-24J199D01*
G01X1152047Y246031D01*
X1152044Y246034D01*
X1152011Y246070D01*
G02X1151965Y246197I154J128D01*
G01Y246255D01*
X1151976Y246313D01*
X1151985Y246345D01*
X1151988Y246353D01*
G03X1152081Y246863I-1409J520D01*
G01Y246883D01*
G03X1150579Y248376I-1502J-9D01*
G03X1149077Y246874I0J-1502D01*
G03X1150572Y245372I1502J0D01*
G01X1150582D01*
G03X1150911Y245409I-2J1502D01*
G01X1150913D01*
X1150943Y245416D01*
X1150956Y245419D01*
X1150976Y245421D01*
X1150978D01*
G02X1151110Y245388I20J-199D01*
G02X1151136Y245367I-112J-166D01*
G01X1151377Y245087D01*
G02X1151421Y244913I-151J-131D01*
G01X1151411Y244876D01*
Y244875D01*
X1151407Y244867D01*
G03X1151296Y244300I1392J-567D01*
G01Y244297D01*
G03X1151301Y244178I1503J4D01*
G01X1151304Y244147D01*
G03X1152779Y242795I1495J150D01*
G01X1152801D01*
G03X1153312Y242885I-1J1502D01*
G02X1153359Y242896I69J-188D01*
G02X1153496Y242861I22J-199D01*
G01X1153770Y242667D01*
G02X1153796Y242644I-119J-161D01*
G01X1153808Y242630D01*
G02X1153849Y242516I-159J-122D01*
G01X1153848Y242317D01*
X1153841Y240152D01*
Y240146D01*
G03X1153840Y240130I199J-20D01*
G03X1153841Y240077I3926J48D01*
G01X1153849Y239551D01*
X1153830Y239520D01*
G03X1153792Y237972I1269J-806D01*
G03X1153847Y237882I1309J738D01*
G01X1153860Y237862D01*
X1153868Y237836D01*
G02X1153876Y237781I-192J-56D01*
G01X1153978Y231214D01*
G02X1153968Y231146I-200J-5D01*
G01X1153956Y231112D01*
X1153932Y231084D01*
G03X1153580Y230118I1150J-966D01*
G01Y230117D01*
G03X1153586Y229976I1502J-7D01*
G01X1153590Y229940D01*
G03X1153629Y229733I1494J174D01*
G01X1153665Y229597D01*
G03X1153672Y229575I194J50D01*
G01X1153674Y229570D01*
X1153678Y229564D01*
G03X1153681Y229557I185J75D01*
G01X1153748Y229426D01*
G03X1153754Y229415I1321J714D01*
G01X1153756Y229411D01*
G03X1153772Y229382I1323J711D01*
G01Y229381D01*
G03X1153922Y229161I1312J733D01*
G01X1153924Y229159D01*
X1153930Y229151D01*
X1153932Y229148D01*
G03X1153942Y229138I146J136D01*
G03X1153944Y229136I1063J1061D01*
G03X1153951Y229128I1134J985D01*
G01X1153954Y229125D01*
X1153959Y229119D01*
G03X1153964Y229113I1158J960D01*
G01X1153988Y229086D01*
X1154014Y229020D01*
X1154019Y228678D01*
X1154178Y218486D01*
Y218476D01*
X1153988Y213631D01*
X1153329Y196799D01*
G02X1153276Y196671I-200J8D01*
G01X1153249Y196644D01*
X1152937Y196476D01*
G02X1152934Y196475I-64J187D01*
G01X1152923Y196469D01*
G02X1152783Y196454I-90J179D01*
G01X1152743Y196465D01*
X1152719Y196479D01*
G03X1151964Y196683I-757J-1301D01*
G03X1151022Y196353I0J-1509D01*
G01X1151021Y196352D01*
X1150994Y196331D01*
X1150963Y196320D01*
G02X1150895Y196308I-68J188D01*
G01X1150819D01*
G03X1150736Y196290I0J-200D01*
G01X1150696Y196271D01*
G02X1150596Y196254I-82J182D01*
G02X1150540Y196268I20J199D01*
G01X1150515Y196278D01*
G03X1149464Y196699I-1051J-1101D01*
G01X1149463D01*
G03X1148478Y196337I1J-1523D01*
G01X1148448Y196313D01*
X1148426Y196308D01*
X1148319D01*
G03X1148236Y196290I0J-200D01*
G01X1148196Y196271D01*
G02X1148096Y196254I-82J182D01*
G02X1148040Y196268I20J199D01*
G01X1148015Y196278D01*
G03X1146964Y196699I-1051J-1101D01*
G01X1146963D01*
G03X1145978Y196337I1J-1523D01*
G01X1145948Y196313D01*
X1145926Y196308D01*
X1145819D01*
G03X1145736Y196290I0J-200D01*
G01X1145681Y196265D01*
G02X1145464Y196298I-83J181D01*
G01X1145423Y196334D01*
G03X1144466Y196678I-957J-1160D01*
G01X1144464D01*
G03Y193674I0J-1502D01*
G01X1144465D01*
G03X1145396Y193997I0J1504D01*
G01X1145417Y194014D01*
X1145450Y194028D01*
X1145460Y194032D01*
G02X1145527Y194044I68J-188D01*
G01X1145609D01*
G03X1145692Y194062I0J200D01*
G01X1145747Y194087D01*
G02X1145848Y194104I82J-182D01*
G02X1145886Y194097I-17J-199D01*
G01X1145923Y194064D01*
X1145926Y194062D01*
X1145927Y194061D01*
G03X1145932Y194056I144J139D01*
G03X1146964Y193653I1032J1120D01*
G03X1147947Y194014I0J1519D01*
G01X1147968Y194030D01*
X1147976Y194037D01*
G02X1148026Y194044I52J-193D01*
G01X1148109D01*
G03X1148192Y194062I0J200D01*
G01X1148247Y194087D01*
G02X1148348Y194104I82J-182D01*
G02X1148386Y194097I-17J-199D01*
G01X1148423Y194064D01*
X1148426Y194062D01*
X1148427Y194061D01*
G03X1148432Y194056I144J139D01*
G03X1149464Y193653I1032J1120D01*
G03X1150447Y194014I0J1519D01*
G01X1150468Y194030D01*
X1150476Y194037D01*
G02X1150526Y194044I52J-193D01*
G01X1150611D01*
G03X1150651Y194048I0J200D01*
G01X1150675Y194053D01*
X1150884D01*
G02X1150952Y194041I0J-200D01*
G01X1150983Y194030D01*
X1150988Y194026D01*
X1151010Y194008D01*
G03X1151963Y193669I952J1168D01*
G01X1151966D01*
G03X1152621Y193819I0J1507D01*
G01X1152641Y193829D01*
X1152668Y193836D01*
G02X1152824Y193809I47J-195D01*
G01X1152978Y193709D01*
X1152980D01*
X1153084Y193640D01*
X1153094Y193633D01*
G02X1153174Y193474I-120J-160D01*
G01Y192852D01*
Y192844D01*
X1152846Y184460D01*
Y184450D01*
X1149159Y157164D01*
G03X1149124Y156699I3891J-527D01*
G01X1149103Y155394D01*
X1149093Y155350D01*
X1149083Y155331D01*
G03X1148676Y153648I3519J-1742D01*
G01X1148650Y151961D01*
Y151955D01*
G03X1148646Y151777I3887J-176D01*
G03Y151766I3891J-6D01*
G01Y151637D01*
G03X1148757Y150706I3926J-4D01*
G01X1148767Y150667D01*
X1148751Y150566D01*
X1148744Y150523D01*
X1148705Y150284D01*
G03X1148654Y149658I3816J-626D01*
G03X1148655Y149578I3892J9D01*
G01X1148656Y149534D01*
X1148653Y149516D01*
G03X1148603Y148948I3876J-627D01*
G01Y148942D01*
X1148602Y148892D01*
X1148573Y146997D01*
Y146996D01*
G03X1148572Y146938I3925J-97D01*
G01Y146932D01*
G03X1148726Y145849I3927J6D01*
G01X1148733Y145824D01*
X1148739Y145514D01*
X1148721Y145474D01*
G03X1148704Y145434I3572J-1542D01*
G01X1148691Y145403D01*
X1148608Y145308D01*
X1148576Y145286D01*
X1148498Y145247D01*
G02X1148409Y145226I-89J179D01*
G01X1148352D01*
X1148333Y145230D01*
G03X1148329Y145231I-366J-1457D01*
G01X1148323Y145233D01*
G03X1148207Y145252I-301J-1472D01*
G01X1148203D01*
G03X1148041Y145264I-192J-1490D01*
G01X1148016D01*
G03X1146514Y143762I0J-1502D01*
G03X1148015Y142260I1502J0D01*
G01X1148059D01*
X1148101Y142263D01*
X1148175Y142234D01*
X1148205Y142207D01*
X1148214Y142199D01*
X1148216Y142197D01*
X1148410Y142021D01*
G02X1148449Y141970I-137J-145D01*
G01X1148465Y141941D01*
X1148466Y141931D01*
X1148469Y141908D01*
X1148470Y141900D01*
G03X1148474Y141869I3861J482D01*
G01X1148475Y141856D01*
X1148476Y141853D01*
X1148477Y141845D01*
X1148481Y141811D01*
Y141810D01*
G03X1148497Y141684I3868J427D01*
G03X1148555Y141368I3853J544D01*
G03X1148680Y140939I3793J872D01*
G03X1148794Y140651I3673J1287D01*
G01X1148798Y140642D01*
X1148811Y140602D01*
X1148821Y140557D01*
X1148777Y140389D01*
X1148764Y140340D01*
X1148710Y140138D01*
X1148669Y139985D01*
G02X1148578Y139865I-193J52D01*
G01X1148347Y139728D01*
G02X1148302Y139708I-103J171D01*
G01X1148231Y139726D01*
G03X1147307Y139842I-948J-3811D01*
G01X1147256D01*
G03X1145181Y139230I30J-3927D01*
G01X1145173Y139232D01*
X1145157Y139235D01*
G03X1144887Y139259I-267J-1478D01*
G01X1144885D01*
G03X1143383Y137757I0J-1502D01*
G01Y137752D01*
G03X1143497Y137183I1502J5D01*
G01X1143504Y137166D01*
X1143530Y137103D01*
X1143535Y137081D01*
X1143517Y137019D01*
G03X1143358Y135946I3768J-1107D01*
G01Y135902D01*
G03X1143699Y134315I3927J14D01*
G02X1143711Y134277I-184J-79D01*
G01X1143725Y134217D01*
G02Y134213I-200J-2D01*
G01X1143711Y134153D01*
G02X1143699Y134115I-196J41D01*
G03X1143358Y132515I3586J-1601D01*
G01Y132513D01*
G03X1143391Y132006I3927J1D01*
G03X1143464Y131609I3894J511D01*
G03X1143535Y131351I3819J912D01*
G01X1143528Y131320D01*
X1143519Y131298D01*
G03X1143385Y130760I1366J-626D01*
G01Y130743D01*
G03X1143383Y130670I1500J-78D01*
G01Y130640D01*
G03X1144885Y129168I1502J30D01*
G01X1144886D01*
G03X1145113Y129185I2J1502D01*
G02X1145247Y129159I31J-197D01*
G03X1147285Y128588I2039J3356D01*
G01X1147286D01*
G03X1149323Y129158I-1J3927D01*
G02X1149456Y129185I104J-171D01*
G03X1149689Y129168I225J1485D01*
G01X1149692D01*
G03X1150163Y129246I-7J1502D01*
G01X1150205Y129260D01*
X1150251Y129256D01*
G02X1150352Y129216I-20J-199D01*
G01X1150441Y129152D01*
X1150614Y129028D01*
G02X1150660Y128978I-122J-158D01*
G01X1150661Y128977D01*
X1150659Y128902D01*
Y128889D01*
G03X1150658Y128829I3925J-95D01*
G01Y128774D01*
G03X1150999Y127228I3926J55D01*
G02X1151011Y127190I-184J-79D01*
G01X1151025Y127130D01*
G02Y127126I-200J-2D01*
G01X1151011Y127066D01*
G02X1150999Y127028I-196J41D01*
G03X1150658Y125428I3586J-1601D01*
G03X1150664Y125215I3927J4D01*
G01X1150668Y125138D01*
G02X1150665Y125133I-173J101D01*
G01X1150599Y125053D01*
X1150574Y125022D01*
G02X1150495Y124969I-148J135D01*
G01X1150464Y124958D01*
X1150428Y124950D01*
X1150342D01*
X1150322Y124954D01*
X1150310Y124956D01*
X1150283Y124962D01*
X1150266Y124969D01*
G03X1149709Y125086I-582J-1385D01*
G01X1149683D01*
G03X1149428Y125064I1J-1502D01*
G01X1149389Y125057D01*
G03X1147285Y125668I-2103J-3315D01*
G03X1145245Y125097I-1J-3926D01*
G01X1145244D01*
G02X1145142Y125068I-104J171D01*
G01X1145117D01*
X1145103Y125070D01*
X1145099Y125071D01*
X1145091Y125072D01*
X1145090D01*
X1145077Y125074D01*
G03X1145027Y125080I-204J-1488D01*
G01X1145026D01*
G03X1144909Y125086I-135J-1496D01*
G01X1144885D01*
G03X1143383Y123584I0J-1502D01*
G01Y123579D01*
G03X1143497Y123010I1502J5D01*
G01X1143504Y122993D01*
X1143530Y122930D01*
X1143535Y122908D01*
X1143517Y122846D01*
G03X1143358Y121750I3768J-1106D01*
G01Y121715D01*
G03X1143462Y120844I3927J27D01*
G03X1143700Y120139I3823J898D01*
G01X1143707Y120123D01*
X1143725Y120044D01*
G02Y120040I-200J-2D01*
G01X1143707Y119961D01*
X1143700Y119945D01*
G03X1143358Y118342I3585J-1603D01*
G03X1143417Y117663I3927J-1D01*
G03X1143497Y117308I3867J685D01*
G01Y117306D01*
G03X1143525Y117213I3773J1085D01*
G01Y117211D01*
G03X1143536Y117175I3761J1129D01*
G01X1143534Y117168D01*
X1143529Y117146D01*
G03X1143383Y116499I1357J-646D01*
G01Y116497D01*
G03X1144885Y114995I1502J0D01*
G01X1144886D01*
G03X1145180Y115024I0J1502D01*
G01X1145181D01*
X1145184Y115025D01*
G03X1147284Y114416I2100J3317D01*
G01X1147286D01*
G03X1149385Y115024I0J3926D01*
G01X1149386D01*
X1149388Y115023D01*
X1149410Y115019D01*
G03X1149684Y114995I268J1478D01*
G01X1149688D01*
G03X1150083Y115048I0J1502D01*
G01X1150090Y115050D01*
X1150095Y115051D01*
X1150110Y115055D01*
X1150165Y115073D01*
X1150167D01*
X1150188Y115081D01*
X1150238Y115086D01*
X1150261Y115083D01*
G02X1150303Y115072I-29J-198D01*
G02X1150351Y115046I-70J-187D01*
G01X1150599Y114865D01*
G02X1150602Y114863I-110J-168D01*
G01X1150621Y114849D01*
G02X1150647Y114824I-125J-156D01*
G02X1150661Y114805I-154J-128D01*
G01X1150659Y114716D01*
Y114715D01*
G03X1150658Y114656I3925J-96D01*
G01Y114601D01*
G03X1150999Y113055I3926J55D01*
G02X1151011Y113017I-184J-79D01*
G01X1151025Y112957D01*
G02Y112953I-200J-2D01*
G01X1151007Y112874D01*
X1151000Y112858D01*
G03X1150658Y111255I3585J-1603D01*
G03X1150717Y110576I3927J-1D01*
G03X1150797Y110221I3867J685D01*
G01Y110219D01*
G03X1150825Y110126I3773J1085D01*
G01Y110124D01*
G03X1150836Y110088I3761J1129D01*
G01X1150829Y110059D01*
X1150820Y110040D01*
G03X1150685Y109500I1365J-628D01*
G01Y109483D01*
G03X1150683Y109410I1500J-78D01*
G01Y109380D01*
G03X1152185Y107908I1502J30D01*
G03X1152447Y107931I0J1502D01*
G01X1152485Y107937D01*
G03X1152689Y107816I2104J3315D01*
G01X1152691D01*
X1152740Y107788D01*
G02X1152755Y107751I-177J-93D01*
G01X1152833Y107462D01*
X1152832Y107408D01*
X1152825Y107382D01*
X1152808Y107321D01*
X1152796Y107300D01*
G03X1152602Y106562I1308J-738D01*
G01Y106526D01*
X1152603Y106510D01*
Y106507D01*
G03X1152612Y106388I1501J54D01*
G03X1152779Y105854I1492J173D01*
G03X1153177Y105379I1325J706D01*
G01X1153185Y105373D01*
X1153213Y105346D01*
X1153264Y105284D01*
X1153274Y105263D01*
X1153284Y105217D01*
X1153268Y104911D01*
X1153266Y104862D01*
X1153194Y104738D01*
X1153176Y104720D01*
X1153132Y104675D01*
X1153107Y104658D01*
G03X1152443Y103411I839J-1247D01*
G03X1155447I1502J0D01*
G03X1154859Y104603I-1502J0D01*
G01X1154848Y104611D01*
X1154822Y104637D01*
X1154804Y104660D01*
G02X1154768Y104771I164J114D01*
G01X1154783Y105105D01*
X1154802Y105142D01*
X1154806Y105151D01*
X1154841Y105210D01*
X1154855Y105233D01*
X1154917Y105297D01*
X1154942Y105314D01*
G03X1155606Y106557I-838J1247D01*
G01Y106583D01*
G03X1155530Y107036I-1502J-19D01*
G01X1155524Y107054D01*
X1155519Y107098D01*
G02X1155525Y107162I199J14D01*
G02X1155535Y107190I192J-53D01*
G01X1155539Y107198D01*
X1155615Y107351D01*
X1155648Y107417D01*
X1155651Y107424D01*
G02X1155689Y107472I174J-99D01*
G01X1155714Y107494D01*
X1155762Y107509D01*
G03X1156657Y107920I-1178J3745D01*
G01X1156689D01*
X1156704Y107918D01*
X1156705D01*
G03X1156753Y107913I180J1492D01*
G01X1156759D01*
X1156773Y107911D01*
G03X1156885Y107907I110J1499D01*
G03X1156961Y107909I-2J1503D01*
G01X1156999Y107912D01*
G03X1158088Y108510I-114J1498D01*
G01X1158096Y108520D01*
G03X1160271Y109624I-602J3880D01*
G01X1165791Y115143D01*
X1165803Y115149D01*
G03X1165815Y115155I-666J1347D01*
G01X1165819Y115157D01*
G03X1166476Y115814I-682J1339D01*
G01X1166478Y115818D01*
G03X1166484Y115830I-1341J678D01*
G01X1166490Y115842D01*
X1166960Y116312D01*
X1171684Y121037D01*
G03X1172047Y121454I-2773J2780D01*
G03X1172271Y121785I-3136J2363D01*
G01X1172275Y121792D01*
X1172299Y121825D01*
G03X1172508Y122072I-2864J2635D01*
G03X1172704Y122346I-3064J2399D01*
G03X1172769Y122450I-3267J2114D01*
G01X1172773Y122458D01*
X1172779Y122467D01*
G03X1172803Y122507I-3325J2022D01*
G03X1172835Y122562I-3348J1985D01*
G01Y122563D01*
X1172859Y122607D01*
X1172863Y122615D01*
G03X1173035Y122977I-3424J1849D01*
G01X1175470Y128855D01*
X1175535Y129011D01*
X1175641Y129264D01*
G02X1175673Y129317I185J-76D01*
G01X1175693Y129339D01*
X1175727Y129358D01*
X1175729Y129359D01*
G03X1176497Y130649I-734J1311D01*
G01Y130676D01*
G03X1176441Y131081I-1503J-1D01*
G01Y131083D01*
G02X1176449Y131212I193J53D01*
G01X1180322Y140565D01*
X1181240Y142783D01*
X1181375Y143108D01*
X1182014Y144651D01*
X1182583Y146026D01*
G03X1182770Y146596I-3593J1495D01*
G01X1182772Y146606D01*
X1182773Y146610D01*
X1182875Y146854D01*
G03X1183122Y147684I-3617J1528D01*
G03X1183184Y148377I-3865J695D01*
G01Y148379D01*
G03X1183183Y148442I-3927J-31D01*
G01Y148443D01*
X1183086Y154276D01*
G03X1183003Y155016I-3926J-66D01*
G01X1182815Y155915D01*
X1182485Y157489D01*
X1181864Y160457D01*
G02X1181908Y160628I196J41D01*
G02X1181923Y160644I153J-129D01*
G01X1182173Y160877D01*
G02X1182365Y160923I137J-146D01*
G03X1182775Y160866I410J1446D01*
G03X1183802Y161272I0J1502D01*
G01X1183803Y161273D01*
G02X1183874Y161315I135J-147D01*
G02X1183939Y161326I65J-189D01*
G01X1184211D01*
G02X1184276Y161315I0J-200D01*
G02X1184347Y161273I-64J-189D01*
G01X1184348Y161272D01*
G03X1185375Y160866I1027J1096D01*
G03Y163870I0J1502D01*
G03X1184348Y163464I0J-1502D01*
G01X1184347Y163463D01*
G02X1184276Y163421I-135J147D01*
G02X1184211Y163410I-65J189D01*
G01X1183939D01*
G02X1183874Y163421I0J200D01*
G02X1183803Y163463I64J189D01*
G01X1183802Y163464D01*
G03X1182775Y163870I-1027J-1096D01*
G03X1181844Y163547I0J-1503D01*
G01X1181818Y163526D01*
X1181691Y163481D01*
G02X1181634Y163489I-1J200D01*
G01X1181476Y163545D01*
X1181303Y163606D01*
G02X1181174Y163753I67J188D01*
G01X1179980Y169453D01*
X1179350Y172464D01*
X1177471Y181439D01*
X1175119Y192670D01*
G02X1175115Y192709I196J40D01*
G01X1174969Y207090D01*
G02X1175012Y207215I200J1D01*
G01X1175021Y207226D01*
X1175093Y207318D01*
G02X1175161Y207370I153J-129D01*
G03X1175226Y207418I-84J182D01*
G03X1175275Y207586I-148J134D01*
G01Y207588D01*
G03X1175272Y207600I-196J-43D01*
G01Y207601D01*
X1175269Y207614D01*
X1175144Y207964D01*
Y207997D01*
G03X1174974Y208675I-1514J-19D01*
G01X1174967Y208688D01*
G02X1174952Y208751I185J77D01*
G01X1174941Y209742D01*
X1174950Y209760D01*
G03X1175133Y210477I-1319J718D01*
G01Y210480D01*
X1175132Y210500D01*
Y210508D01*
G03X1175085Y210853I-1502J-29D01*
G03X1174950Y211198I-1458J-371D01*
G01X1174938Y211221D01*
X1174926Y211266D01*
X1174922Y211631D01*
Y211638D01*
X1174917Y212073D01*
G02X1174925Y212132I200J3D01*
G01X1174932Y212154D01*
X1174947Y212179D01*
G03X1175170Y212978I-1317J798D01*
G01Y212980D01*
G03X1174941Y213788I-1542J-1D01*
G01X1174930Y213806D01*
X1174907Y213879D01*
G02X1174899Y213936I192J56D01*
G01X1174891Y214658D01*
X1174908Y214687D01*
G03X1175133Y215478I-1278J791D01*
G03X1175129Y215596I-1503J8D01*
G01X1175122Y215655D01*
G03X1174932Y216227I-1493J-178D01*
G03X1174904Y216274I-1304J-745D01*
G01X1174884Y216305D01*
X1174874Y216322D01*
X1174872Y216511D01*
X1174808Y222724D01*
G02X1174818Y222788I200J2D01*
G01X1174827Y222815D01*
X1174840Y222834D01*
X1174842Y222836D01*
G03X1175132Y223723I-1213J887D01*
G01Y223763D01*
G03X1175131Y223797I-1502J-27D01*
G01Y223799D01*
G03X1175059Y224189I-1500J-75D01*
G03X1175024Y224287I-1431J-456D01*
G03X1175022Y224291I-179J-87D01*
G01X1175021Y224295D01*
G02X1175019Y224297I130J132D01*
G03X1174876Y224565I-1390J-569D01*
G03X1174856Y224594I-1246J-838D01*
G03X1174829Y224630I-1215J-883D01*
G01Y224631D01*
G02X1174788Y224742I159J122D01*
G01Y224799D01*
X1174784Y225178D01*
Y225194D01*
X1174815Y225285D01*
G02X1174843Y225339I189J-64D01*
G03X1175132Y226225I-1213J886D01*
G01Y226265D01*
G03X1174809Y227157I-1502J-39D01*
G01X1174799Y227170D01*
X1174772Y227221D01*
X1174763Y227261D01*
X1174762Y227317D01*
Y227384D01*
X1174761Y227386D01*
Y227391D01*
X1174758Y227656D01*
G02X1174771Y227727I200J0D01*
G01X1174782Y227758D01*
X1174787Y227765D01*
X1174788Y227766D01*
X1174790Y227770D01*
G03X1175132Y228703I-1161J955D01*
G01Y228727D01*
G03X1174846Y229608I-1502J-1D01*
G01X1174821Y229642D01*
X1174806Y229661D01*
G02X1174785Y229695I159J122D01*
G01X1174783Y229699D01*
G02X1174762Y229788I179J89D01*
G01Y229872D01*
G03X1174745Y229952I-200J-1D01*
G01X1174744Y229955D01*
X1174735Y229978D01*
X1174733Y230129D01*
G02X1174746Y230201I200J1D01*
G01X1174757Y230231D01*
X1174780Y230259D01*
G03X1175129Y231127I-1150J967D01*
G03X1175058Y231692I-1499J99D01*
G03X1174760Y232218I-1430J-463D01*
G01X1174739Y232242D01*
X1174736Y232245D01*
X1174724Y232278D01*
G02X1174711Y232347I187J71D01*
G01X1174494Y253607D01*
X1174488Y254167D01*
Y269165D01*
G03X1174482Y269367I-3892J-15D01*
G01X1172902Y299733D01*
X1172846Y300810D01*
X1172768Y302309D01*
X1172746Y302736D01*
X1172728Y303082D01*
G02X1172769Y303204I200J1D01*
G01X1172783Y303222D01*
X1172866Y303291D01*
X1172871Y303295D01*
X1173053Y303446D01*
G02X1173162Y303487I122J-159D01*
G01X1173205D01*
X1173227Y303482D01*
G03X1173519Y303446I329J1466D01*
G01X1173568D01*
G03X1175061Y304948I-9J1502D01*
G03X1173559Y306450I-1502J0D01*
G01X1173556D01*
G03X1173081Y306373I0J-1502D01*
G01X1173066Y306368D01*
X1173011Y306357D01*
X1172961Y306361D01*
X1172909Y306381D01*
G02X1172900Y306385I76J184D01*
G01X1172736Y306495D01*
X1172627Y306568D01*
G02X1172538Y306717I110J167D01*
G01Y306725D01*
X1171394Y328702D01*
X1169576Y363637D01*
X1165559Y440810D01*
Y441307D01*
G02X1165640Y441464I200J-4D01*
G01X1165926Y441642D01*
X1165928D01*
X1165945Y441653D01*
X1165989Y441668D01*
X1166011Y441670D01*
X1166017D01*
X1166021Y441671D01*
X1166022D01*
G02X1166115Y441654I12J-200D01*
G01X1166139Y441642D01*
X1166152Y441635D01*
X1166158Y441631D01*
G03X1166865Y441454I707J1325D01*
G01X1166892D01*
G03X1167108Y441473I-23J1502D01*
G03X1167835Y444106I-240J1483D01*
G03X1166926Y444457I-966J-1150D01*
G01X1166925D01*
X1166881Y444459D01*
X1166868D01*
G03X1166008Y444188I1J-1502D01*
G01X1166006Y444187D01*
X1165994Y444179D01*
X1165968Y444166D01*
G02X1165868Y444147I-86J180D01*
G01X1165860Y444148D01*
X1165817Y444157D01*
G02X1165798Y444165I68J188D01*
G01X1165797D01*
X1165720Y444202D01*
X1165718D01*
X1165447Y444335D01*
X1165436Y444347D01*
X1165408Y444381D01*
G02X1165390Y444410I160J120D01*
G01X1165381Y444429D01*
X1165373Y444471D01*
G02X1165369Y444499I195J42D01*
G01X1164990Y451776D01*
X1164320Y464642D01*
Y464644D01*
X1164318Y464689D01*
X1164329Y464716D01*
X1164363Y464767D01*
G02X1164387Y464796I165J-112D01*
G03X1164830Y465873I-1088J1077D01*
G01Y465874D01*
G03X1164260Y467066I-1531J0D01*
G01X1164200Y467115D01*
G02X1164189Y467160I187J70D01*
G01X1164162Y467673D01*
X1164134Y468211D01*
X1164101Y468844D01*
X1163637Y477762D01*
X1163377Y482755D01*
X1163221Y485742D01*
X1160596Y536175D01*
X1160476Y538492D01*
X1160384Y540259D01*
X1160335Y541203D01*
X1160332Y541260D01*
X1160331Y541272D01*
Y541299D01*
G02X1160352Y541376I200J-13D01*
G01X1160386Y541442D01*
G02X1160422Y541491I177J-93D01*
G01X1160443Y541512D01*
G03X1161037Y542675I-910J1198D01*
G01Y542710D01*
G03X1160281Y544017I-1503J3D01*
G01X1160268Y544024D01*
G02X1160239Y544048I113J166D01*
G02X1160181Y544171I141J142D01*
G01X1160157Y544610D01*
X1160127Y545192D01*
Y545201D01*
G02X1160155Y545303I200J0D01*
G01X1160171Y545330D01*
X1160210Y545367D01*
X1160235Y545381D01*
X1160237Y545382D01*
G03X1161039Y546712I-702J1330D01*
G03X1160116Y548098I-1502J0D01*
G01X1160114Y548099D01*
X1160089Y548110D01*
X1160039Y548149D01*
G02X1159967Y548283I127J155D01*
G01X1158920Y568387D01*
X1158282Y580641D01*
X1158240Y581451D01*
X1157426Y597096D01*
X1157043Y604466D01*
X1156826Y608632D01*
X1156769Y609724D01*
X1156587Y613226D01*
X1156484Y615206D01*
X1156423Y616371D01*
X1156422Y616394D01*
X1156418Y616466D01*
Y616486D01*
G02X1156494Y616642I200J-1D01*
G01X1156507Y616652D01*
X1156759Y616840D01*
X1156776Y616848D01*
X1156782Y616851D01*
G02X1156871Y616872I89J-179D01*
G01X1156949D01*
X1156980Y616862D01*
G03X1157451Y616786I472J1426D01*
G03X1158953Y618288I0J1502D01*
G03X1157488Y619790I-1502J0D01*
G01X1157413D01*
G03X1156824Y619653I39J-1502D01*
G01X1156809Y619646D01*
X1156806Y619645D01*
X1156757Y619633D01*
G02X1156615Y619657I-40J196D01*
G01X1156437Y619761D01*
X1156332Y619823D01*
G02X1156247Y619923I102J172D01*
G01X1156236Y619953D01*
X1153823Y666315D01*
X1153794Y666872D01*
X1153182Y678640D01*
X1152935Y683381D01*
X1152673Y688422D01*
X1151048Y719637D01*
X1151045Y719695D01*
X1151035Y719895D01*
X1150963Y721262D01*
X1150742Y725529D01*
X1150636Y727570D01*
X1150647Y727604D01*
X1150671Y727683D01*
X1150687Y727707D01*
G03X1150763Y727835I-1252J830D01*
G01X1150768Y727846D01*
X1150783Y727869D01*
X1150804Y727894D01*
X1150808Y727897D01*
X1150866Y727942D01*
G02X1150950Y727974I111J-166D01*
G01X1150996Y727980D01*
X1151044Y727963D01*
X1151067Y727955D01*
X1151110Y727927D01*
G02X1151151Y727891I-110J-167D01*
G01X1151166Y727874D01*
X1151178Y727851D01*
G03X1152512Y727041I1334J693D01*
G03Y730045I0J1502D01*
G03X1151305Y729437I0J-1502D01*
G01X1151296Y729425D01*
X1151275Y729404D01*
X1151267Y729398D01*
X1151264Y729395D01*
X1151253Y729385D01*
G02X1151132Y729344I-121J159D01*
G01X1150860D01*
G02X1150771Y729365I0J200D01*
G01X1150769Y729366D01*
X1150698Y729402D01*
G02X1150647Y729439I90J178D01*
G01X1150625Y729461D01*
X1150616Y729473D01*
G03X1150603Y729489I-1172J-939D01*
G03X1150601Y729491I-142J-140D01*
G03X1150579Y729518I-1176J-936D01*
G01X1150554Y729546D01*
X1150540Y729585D01*
X1150529Y729615D01*
X1150504Y730097D01*
X1150418Y731749D01*
X1149692Y745692D01*
Y745699D01*
X1149689Y745749D01*
X1149686Y745807D01*
Y745825D01*
G02X1149710Y745919I200J-1D01*
G01X1149722Y745940D01*
X1149754Y745975D01*
X1149777Y745990D01*
G03X1150465Y747253I-815J1263D01*
G03X1150460Y747373I-1503J-3D01*
G01X1150454Y747429D01*
G03X1149668Y748579I-1492J-176D01*
G01X1149641Y748593D01*
X1149589Y748645D01*
G02X1149564Y748676I142J140D01*
G02X1149531Y748775I167J111D01*
G01Y748776D01*
X1149214Y754871D01*
X1148750Y763793D01*
X1148709Y764593D01*
X1148682Y765148D01*
G02X1148688Y765197I200J0D01*
G01X1148697Y765228D01*
X1148715Y765255D01*
G03X1148970Y766092I-1246J837D01*
G01Y766096D01*
G03X1148622Y767056I-1502J-1D01*
G01X1148621Y767057D01*
X1148599Y767084D01*
X1148589Y767108D01*
G02X1148575Y767157I184J79D01*
G01X1148564Y767373D01*
X1148527Y768090D01*
X1148375Y771004D01*
X1148222Y773942D01*
X1147212Y793382D01*
G02X1147217Y793440I199J12D01*
G01X1147233Y793505D01*
X1147241Y793521D01*
G03X1147274Y793586I-1322J712D01*
G01Y793587D01*
X1147279Y793599D01*
G03X1147302Y793652I-1366J624D01*
G01X1147304Y793654D01*
G03X1147372Y793866I-1393J564D01*
G01Y793868D01*
G03X1147376Y793885I-1459J352D01*
G01Y793888D01*
X1147378Y793899D01*
G03X1147398Y794007I-1466J327D01*
G01Y794009D01*
G03X1147412Y794192I-1488J206D01*
G01Y794227D01*
G03X1147406Y794352I-1502J-9D01*
G03X1147253Y794890I-1496J-135D01*
G03X1147224Y794945I-1343J-673D01*
G01X1147205Y794979D01*
X1147180Y795021D01*
X1147164Y795045D01*
X1147153Y795061D01*
X1147138Y795084D01*
X1147128Y795113D01*
G02X1147117Y795167I189J67D01*
G01X1147101Y795474D01*
X1147000Y797404D01*
X1146947Y798437D01*
X1146931Y798736D01*
X1146778Y801685D01*
X1146747Y802278D01*
Y802335D01*
X1146768Y802377D01*
X1146783Y802408D01*
X1146822Y802447D01*
X1146832Y802455D01*
G03X1147329Y804135I-922J1186D01*
G01X1147313Y804180D01*
G03X1146732Y804900I-1403J-538D01*
G01X1146711Y804914D01*
X1146677Y804951D01*
X1146662Y804979D01*
X1146625Y805044D01*
G02X1146598Y805133I172J101D01*
G01X1142277Y888148D01*
X1141909Y895226D01*
Y895231D01*
G02X1142308Y895634I400J3D01*
G01X1155661D01*
X1155670D01*
G02X1155858Y895468I-9J-200D01*
G01X1157293Y887227D01*
X1158124Y882457D01*
X1158988Y877499D01*
X1160147Y870842D01*
G02X1160099Y870675I-197J-34D01*
G01Y870674D01*
G02X1159986Y870611I-149J134D01*
G01X1159982Y870610D01*
G02X1159945Y870608I-29J198D01*
G01X1159881D01*
G03X1158385Y869106I6J-1502D01*
G03X1159885Y867604I1502J0D01*
G01X1159906D01*
G03X1159969Y867606I-16J1502D01*
G01X1159971D01*
G03X1159986Y867607I-92J1499D01*
G03X1160124Y867623I-104J1498D01*
G01X1160132Y867624D01*
X1160134D01*
G03X1160270Y867654I-255J1480D01*
G01X1160274D01*
X1160289Y867657D01*
G02X1160390Y867644I26J-199D01*
G02X1160424Y867626I-76J-185D01*
G01X1160669Y867467D01*
G02X1160756Y867342I-108J-168D01*
G01X1163381Y852276D01*
X1163380Y852275D01*
X1163375Y852273D01*
X1163287Y852250D01*
X1163202Y852228D01*
G03X1162077Y850774I377J-1454D01*
G03X1163579Y849272I1502J0D01*
G03X1163716Y849278I3J1502D01*
G01X1163893Y849294D01*
X1163896D01*
X1163900Y849293D01*
X1170151Y813396D01*
X1171849Y803650D01*
G02X1171848Y803578I-197J-33D01*
G01X1171842Y803546D01*
X1171824Y803515D01*
G03X1171620Y802759I1298J-756D01*
G03X1172154Y801611I1502J0D01*
G01X1172158Y801607D01*
X1172207Y801522D01*
G02X1172231Y801456I-173J-100D01*
G01X1174800Y786704D01*
X1175044Y785304D01*
X1175035Y785265D01*
G03X1174998Y784944I1465J-332D01*
G01Y784913D01*
G03X1175003Y784814I1501J26D01*
G03X1175233Y784126I1497J118D01*
G01X1175255Y784092D01*
X1175407Y783218D01*
X1176134Y779041D01*
G02X1176128Y778975I-199J-15D01*
G01X1176126Y778969D01*
G03X1176064Y778541I1440J-427D01*
G01Y778539D01*
G03X1176070Y778398I1502J-7D01*
G01X1176074Y778363D01*
Y778362D01*
G03X1176178Y777966I1491J180D01*
G03X1176312Y777713I1388J573D01*
G01Y777712D01*
G03X1176344Y777665I1257J822D01*
G02X1176365Y777629I-161J-118D01*
G01X1176392Y777567D01*
Y777565D01*
X1176587Y776444D01*
X1176826Y775071D01*
X1177000Y774074D01*
X1177138Y773281D01*
G02X1177121Y773159I-197J-35D01*
G01X1177107Y773131D01*
X1177065Y773087D01*
X1177036Y773071D01*
G03X1176682Y772806I714J-1323D01*
G03X1176529Y772628I1060J-1066D01*
G01X1176512Y772605D01*
X1176427Y772539D01*
X1176400Y772519D01*
X1176368Y772508D01*
G02X1176306Y772498I-62J190D01*
G01X1176006D01*
G02X1175955Y772505I1J200D01*
G02X1175850Y772573I51J193D01*
G01X1175836Y772591D01*
X1175829Y772601D01*
G03X1174595Y773246I-1234J-858D01*
G03X1173093Y771744I0J-1502D01*
G03X1174579Y770242I1502J0D01*
G01X1174602D01*
G03X1175812Y770863I-7J1502D01*
G01X1175826Y770883D01*
X1175846Y770900D01*
X1175865Y770917D01*
X1175969Y770969D01*
G02X1176058Y770990I89J-179D01*
G01X1176310D01*
X1176357Y770978D01*
X1176379Y770967D01*
X1176446Y770932D01*
G02X1176495Y770896I-93J-177D01*
G01X1176524Y770867D01*
X1176533Y770855D01*
G03X1177517Y770259I1211J889D01*
G01X1177525Y770258D01*
X1177527D01*
G02X1177636Y770204I-30J-198D01*
G01X1177658Y770182D01*
X1177688Y770126D01*
X1194554Y673278D01*
X1205502Y610412D01*
X1205497Y610405D01*
X1205429Y610337D01*
G03X1205485Y608154I1061J-1065D01*
G03X1205852Y607909I1009J1114D01*
G01X1205914Y607880D01*
X1205945Y607861D01*
X1205947Y607859D01*
X1205958Y607796D01*
X1206067Y607169D01*
X1206068Y607168D01*
X1206069Y607160D01*
G02X1206070Y607155I-195J-42D01*
G01X1208588Y587580D01*
X1210796Y570416D01*
X1211106Y568008D01*
G02X1211108Y567984I-198J-29D01*
G01X1211155Y563030D01*
X1211172Y561260D01*
X1211189Y559448D01*
X1211411Y535936D01*
X1211887Y485503D01*
X1212125Y460244D01*
G03X1212152Y459816I3891J31D01*
G03X1212200Y459517I3864J467D01*
G01X1222015Y410472D01*
X1222012Y410423D01*
X1222005Y410399D01*
X1222001Y410386D01*
G03X1221928Y409924I1430J-463D01*
G01Y409922D01*
G03X1222295Y408939I1503J1D01*
G01X1222316Y408915D01*
X1222335Y408875D01*
X1222338Y408860D01*
X1222339Y408858D01*
X1222341Y408844D01*
X1222348Y408807D01*
X1222638Y407347D01*
G02X1222611Y407209I-197J-33D01*
G01X1222585Y407174D01*
X1222558Y407147D01*
X1222545Y407138D01*
G03X1221929Y405924I888J-1214D01*
G03X1223068Y404466I1503J0D01*
G01X1223090Y404461D01*
X1223097Y404459D01*
X1223123Y404454D01*
X1223173Y404427D01*
X1223196Y404404D01*
G02X1223250Y404303I-142J-141D01*
G01X1223258Y404262D01*
Y404261D01*
X1223439Y403357D01*
X1223536Y402871D01*
X1224137Y399866D01*
G02X1224110Y399720I-196J-39D01*
G01X1224098Y399701D01*
X1223971Y399571D01*
X1223969Y399569D01*
X1223855Y399451D01*
G02X1223714Y399393I-141J142D01*
G01X1223682D01*
X1223666Y399395D01*
G03X1223431Y399414I-238J-1483D01*
G03X1221929Y397912I0J-1502D01*
G03X1223255Y396420I1502J0D01*
G01X1223339Y396410D01*
G03X1223359Y396409I20J199D01*
G01X1223431D01*
G03X1224060Y396548I-2J1503D01*
G03X1224223Y396635I-624J1366D01*
G01X1224231Y396640D01*
X1224250Y396650D01*
G02X1224420Y396654I89J-179D01*
G01X1224679Y396540D01*
G03X1224697Y396533I81J183D01*
G01X1224736Y396521D01*
X1224766Y396496D01*
G02X1224813Y396438I-129J-153D01*
G01X1224817Y396430D01*
G02X1224835Y396383I-176J-94D01*
G01X1224837Y396371D01*
X1224844Y396333D01*
Y396332D01*
X1225097Y395073D01*
X1226779Y386666D01*
X1228434Y378324D01*
X1229517Y372864D01*
X1229847Y371203D01*
G02X1229826Y371158I-190J61D01*
G02X1229802Y371128I-167J109D01*
G01X1229685Y371008D01*
X1229567Y370888D01*
G02X1229426Y370830I-141J142D01*
G01X1229407D01*
X1229389Y370833D01*
G03X1229123Y370857I-267J-1478D01*
G01X1229122D01*
G03X1227835Y370133I0J-1506D01*
G01X1227834Y370131D01*
X1227821Y370110D01*
X1227769Y370058D01*
X1227757Y370049D01*
G03X1227745Y370039I122J-158D01*
G01X1227729Y370026D01*
X1227705Y370012D01*
X1227651Y369982D01*
G02X1227582Y369964I-84J182D01*
G01X1227448Y369965D01*
X1227275Y369967D01*
G02X1227143Y370025I9J200D01*
G01X1227114Y370054D01*
X1227083Y370095D01*
X1227076Y370108D01*
G03X1225755Y370893I-1321J-719D01*
G03X1224483Y370191I0J-1503D01*
G01X1224471Y370172D01*
X1224434Y370135D01*
G02X1224302Y370077I-141J142D01*
G01X1224144Y370070D01*
X1223984Y370063D01*
X1223983D01*
G02X1223860Y370099I-8J200D01*
G01X1223841Y370113D01*
X1223816Y370138D01*
X1223814Y370141D01*
X1223813Y370142D01*
X1223809Y370147D01*
X1223804Y370154D01*
G03X1222602Y370753I-1203J-908D01*
G01X1222601D01*
G03Y367749I0J-1502D01*
G03X1223873Y368451I0J1503D01*
G01X1223885Y368470D01*
X1223922Y368507D01*
G02X1224054Y368565I141J-142D01*
G01X1224212Y368572D01*
X1224375Y368579D01*
X1224382D01*
G02X1224489Y368548I0J-200D01*
G01X1224508Y368536D01*
X1224540Y368504D01*
X1224542Y368501D01*
X1224543Y368500D01*
X1224550Y368491D01*
G03X1224706Y368314I1205J905D01*
G03X1225078Y368050I1048J1083D01*
G03X1225427Y367925I677J1341D01*
G01X1225433Y367924D01*
X1225508Y367907D01*
X1225555Y367902D01*
X1225563Y367901D01*
X1225567D01*
G03X1225609Y367896I199J1493D01*
G01X1225610D01*
X1225619Y367895D01*
G03X1225755Y367889I134J1496D01*
G03X1227042Y368613I0J1506D01*
G01X1227043Y368615D01*
X1227056Y368636D01*
X1227108Y368688D01*
X1227120Y368697D01*
G03X1227132Y368707I-122J158D01*
G01X1227148Y368720D01*
X1227172Y368734D01*
X1227226Y368764D01*
G02X1227295Y368782I84J-182D01*
G01X1227429Y368781D01*
X1227603Y368779D01*
G02X1227730Y368725I-10J-200D01*
G01X1227763Y368692D01*
X1227772Y368680D01*
X1227794Y368651D01*
X1227802Y368637D01*
X1227804Y368633D01*
G03X1229122Y367853I1318J724D01*
G01X1229123D01*
G03X1229937Y368093I0J1501D01*
G01X1229939Y368094D01*
G02X1229957Y368104I106J-169D01*
G01X1229981Y368114D01*
X1229983Y368115D01*
X1229986Y368116D01*
G02X1230028Y368125I63J-190D01*
G01X1230039Y368126D01*
G02X1230121Y368113I10J-200D01*
G01X1230288Y368041D01*
X1230446Y367973D01*
G02X1230453Y367970I-75J-185D01*
G02X1230494Y367937I-104J-171D01*
G01X1231295Y363900D01*
X1232219Y359244D01*
X1233088Y354868D01*
G02X1233020Y354800I-171J103D01*
G01X1232984Y354779D01*
X1232982Y354777D01*
X1232696Y354606D01*
G02X1232465Y354627I-101J173D01*
G01X1232453Y354637D01*
G03X1231507Y354972I-946J-1167D01*
G01X1231502D01*
G03X1231416Y354970I-8J-1502D01*
G01X1231398Y354969D01*
G03X1230004Y353470I109J-1499D01*
G03X1231506Y351968I1502J0D01*
G03X1232824Y352749I0J1503D01*
G01X1232840Y352778D01*
G02X1233041Y352879I175J-97D01*
G01X1233092Y352872D01*
X1233093D01*
X1233145Y352865D01*
X1233216Y352855D01*
G02X1233263Y352840I-37J-197D01*
G02X1233337Y352782I-83J-182D01*
G01X1233346Y352770D01*
G02X1233350Y352764I-165J-114D01*
G01X1233360Y352746D01*
G03X1233425Y352645I1295J762D01*
G03X1233526Y352516I1231J860D01*
G01X1233531Y352510D01*
X1233533Y352508D01*
X1233548Y352488D01*
X1233567Y352449D01*
X1234294Y348785D01*
G02X1234285Y348763I-189J64D01*
G01X1234261Y348719D01*
G03X1234160Y348480I1328J-702D01*
G01Y348478D01*
G03X1234145Y348431I1423J-480D01*
G01X1234141Y348417D01*
X1234136Y348397D01*
G03X1234087Y348017I1453J-381D01*
G01Y347997D01*
G03X1234095Y347856I1501J14D01*
G03X1234148Y347591I1493J161D01*
G03X1234162Y347547I1438J433D01*
G02X1234164Y347539I-193J-52D01*
G01X1234165Y347536D01*
X1234187Y347472D01*
G03X1234195Y347452I189J64D01*
G01X1234215Y347408D01*
G02X1234217Y347404I-178J-91D01*
G03X1234276Y347285I1374J607D01*
G03X1234369Y347139I1311J733D01*
G01Y347137D01*
G03X1234403Y347093I1206J897D01*
G03X1234631Y346858I1186J922D01*
G01X1234658Y346836D01*
X1234659Y346835D01*
X1234675Y346808D01*
G02X1234700Y346744I-171J-104D01*
G01X1235452Y342953D01*
X1242684Y306495D01*
G02X1242589Y306283I-196J-40D01*
G02X1242105Y306346I-201J346D01*
G01X1238620Y309831D01*
G03X1237205Y310418I-1416J-1415D01*
G01X1233264D01*
G02X1233123Y310476I0J200D01*
G01X1230445Y313154D01*
G03X1230433Y313166I-147J-135D01*
G02X1230429Y313170I139J143D01*
G03X1230426Y313173I-143J-140D01*
G01X1230423Y313176D01*
G03X1230420Y313179I-1417J-1414D01*
G03X1230418Y313181I-142J-140D01*
G03X1230371Y313225I-1391J-1439D01*
G01X1230342Y313251D01*
X1230286Y313368D01*
G02X1230275Y313402I184J78D01*
G02X1230272Y313422I196J40D01*
G01X1230262Y313684D01*
Y313692D01*
G02X1230293Y313799I200J0D01*
G01X1230305Y313818D01*
X1230343Y313856D01*
X1230371Y313885D01*
X1230383Y313899D01*
X1230384Y313900D01*
G03X1230595Y314216I-1134J986D01*
G03X1230598Y314221I-1283J773D01*
G01X1230627Y314279D01*
G03X1230636Y314301I-180J87D01*
G01X1230649Y314338D01*
X1230651Y314342D01*
G03X1230694Y314466I-1397J554D01*
G01Y314467D01*
X1230701Y314492D01*
G03X1230754Y314878I-1449J396D01*
G01Y314912D01*
G03X1229252Y316392I-1502J-22D01*
G03X1227750Y314901I0J-1502D01*
G01Y314888D01*
G03X1227864Y314314I1502J0D01*
G01X1227871Y314297D01*
X1227879Y314260D01*
X1227888Y314221D01*
X1227881Y314180D01*
X1227874Y314136D01*
X1227774Y313989D01*
X1227667Y313830D01*
G02X1227502Y313742I-166J112D01*
G01X1225441D01*
G02X1225320Y313783I0J200D01*
G01X1225311Y313791D01*
X1225304Y313798D01*
G03X1225289Y313811I-138J-144D01*
G01X1209782Y329318D01*
G02X1209738Y329385I142J141D01*
G01X1209724Y329419D01*
Y365220D01*
G02X1209727Y365252I200J-3D01*
G01Y365254D01*
G02X1209781Y365360I197J-34D01*
G01X1218126Y373705D01*
G02X1218232Y373759I140J-143D01*
G01X1218234D01*
G02X1218266Y373762I35J-197D01*
G01X1221284D01*
G03X1222699Y374349I-1J2002D01*
G01X1223011Y374661D01*
X1224846Y376497D01*
G03X1225432Y377912I-1415J1415D01*
G01Y381912D01*
G03X1221430I-2001J0D01*
G01Y378824D01*
G02X1221428Y378799I-200J3D01*
G02X1221388Y378701I-198J24D01*
G01X1221374Y378687D01*
G03X1221365Y378677I143J-138D01*
G01X1220512Y377824D01*
G02X1220445Y377780I-141J142D01*
G01X1220411Y377766D01*
X1217353D01*
G03X1215938Y377179I1J-2002D01*
G01X1206307Y367548D01*
G03X1205720Y366133I1415J-1416D01*
G01Y328546D01*
G03X1206307Y327131I2002J1D01*
G01X1223113Y310325D01*
G03X1224528Y309738I1416J1415D01*
G01X1228116D01*
G02X1228256Y309681I0J-200D01*
G01X1230936Y307001D01*
G03X1232351Y306414I1416J1415D01*
G01X1236292D01*
G02X1236324Y306411I-3J-200D01*
G01X1236326D01*
G02X1236432Y306357I-34J-197D01*
G01X1239204Y303585D01*
X1239215Y303570D01*
X1239216Y303568D01*
G03X1239222Y303560I158J112D01*
G02X1239224Y303558I-140J-142D01*
G03X1239236Y303544I153J119D01*
G03X1239238Y303542I138J136D01*
G02X1239240Y303538I-178J-91D01*
G01X1239252Y303516D01*
X1239259Y303491D01*
Y303488D01*
G03X1241205Y301960I1946J475D01*
G03X1242862Y302839I0J2001D01*
G01X1242869Y302849D01*
G02X1242952Y302913I159J-121D01*
G01X1242978Y302923D01*
X1243007Y302926D01*
G02X1243031Y302927I20J-199D01*
G02X1243068Y302923I-3J-200D01*
G01X1243154Y302905D01*
X1243156D01*
X1243277Y302880D01*
G02X1243427Y302746I-40J-196D01*
G02X1243431Y302732I-190J-62D01*
G01X1248723Y276059D01*
X1254216Y248370D01*
G02X1254217Y248362I-197J-29D01*
G02X1254165Y248194I-198J-31D01*
G02X1254126Y248162I-145J137D01*
G01X1254090Y248139D01*
X1254028Y248099D01*
G02X1254000Y248085I-103J171D01*
G02X1253871Y248082I-69J188D01*
G01X1253861Y248085D01*
X1253801Y248107D01*
X1253780Y248120D01*
G03X1252941Y248377I-840J-1246D01*
G03X1252884Y248376I-2J-1503D01*
G01X1252830Y248372D01*
G03X1251439Y246874I111J-1498D01*
G03X1252906Y245372I1502J0D01*
G01X1252944D01*
G03X1253273Y245409I-2J1502D01*
G01X1253275D01*
X1253305Y245416D01*
X1253318Y245419D01*
X1253338Y245421D01*
X1253340D01*
G02X1253472Y245388I20J-199D01*
G02X1253498Y245367I-112J-166D01*
G01X1253739Y245087D01*
G02X1253783Y244913I-151J-131D01*
G01X1253773Y244876D01*
Y244875D01*
X1253769Y244867D01*
G03X1253658Y244300I1392J-567D01*
G01Y244297D01*
G03X1253663Y244178I1503J4D01*
G01X1253665Y244162D01*
Y244158D01*
G03X1255158Y242795I1496J139D01*
G01X1255159D01*
G02X1255353Y242638I-1J-200D01*
G01X1255406Y242370D01*
X1255955Y239604D01*
G02X1255959Y239568I-196J-40D01*
G01X1255969Y238899D01*
X1255968Y238889D01*
G03X1255958Y238714I1492J-173D01*
G01Y238688D01*
G03X1255963Y238588I1502J25D01*
G01X1255964Y238580D01*
Y238574D01*
X1255965Y238564D01*
G03X1255970Y238521I1495J152D01*
G01Y238519D01*
G03X1255976Y238480I1488J209D01*
G01X1255982Y238114D01*
X1256096Y230803D01*
X1256087Y230764D01*
X1256077Y230742D01*
G03X1255941Y230117I1368J-625D01*
G01Y229978D01*
G03X1255951Y229916I200J0D01*
G01X1255958Y229894D01*
X1255961Y229877D01*
G03X1256097Y229452I1483J240D01*
G01Y229451D01*
G02X1256118Y229376I-178J-90D01*
G01X1256652Y195152D01*
G02X1256651Y195137I-200J6D01*
G01X1256650Y195130D01*
X1251425Y156450D01*
G03X1251390Y155981I3891J-526D01*
G01X1251389Y155928D01*
X1251387Y155787D01*
X1251384Y155603D01*
G02X1251382Y155577I-200J2D01*
G01X1251046Y153273D01*
G03X1251006Y152711I3851J-557D01*
G01Y151569D01*
G02X1251002Y151527I-200J-2D01*
G01X1250999Y151518D01*
G03X1250860Y150539I3787J-1037D01*
G01X1250831Y148588D01*
Y148587D01*
G03X1250830Y148531I3925J-98D01*
G01Y148529D01*
G03X1250936Y147627I3927J4D01*
G03X1250997Y147399I3822J900D01*
G01X1251006Y147368D01*
Y147343D01*
G02X1251003Y147310I-200J2D01*
G02X1251002Y147305I-196J37D01*
G01X1250995Y147273D01*
X1250986Y147250D01*
G03X1250654Y145678I3561J-1573D01*
G01Y145653D01*
X1250649Y145624D01*
G02X1250598Y145520I-197J32D01*
G01X1250415Y145324D01*
X1250380Y145308D01*
X1250281Y145261D01*
X1250264Y145260D01*
X1250245Y145258D01*
G03X1248876Y143762I133J-1496D01*
G03X1250267Y142264I1502J0D01*
G01X1250302Y142261D01*
X1250368Y142232D01*
X1250397Y142219D01*
G02X1250457Y142178I-81J-183D01*
G01X1250479Y142156D01*
G02X1250536Y142030I-142J-140D01*
G01X1250535Y141933D01*
G02X1250518Y141913I-161J119D01*
G01X1250483Y141880D01*
X1250447Y141846D01*
G02X1250409Y141821I-128J154D01*
G01X1250356Y141798D01*
X1250317D01*
G03X1250308I-5J-1502D01*
G01X1250307D01*
G03X1248805Y140296I0J-1502D01*
G01Y140288D01*
G03X1248831Y140005I1503J-5D01*
G01X1248834Y139991D01*
X1248837Y139932D01*
X1248839Y139894D01*
G02Y139884I-200J-5D01*
G02X1248775Y139744I-200J7D01*
G01X1248686Y139722D01*
G03X1247543Y139230I961J-3807D01*
G01X1247539Y139231D01*
X1247512Y139236D01*
G03X1247284Y139259I-264J-1479D01*
G01X1247241D01*
G03X1245745Y137757I6J-1502D01*
G01Y137752D01*
G03X1245859Y137183I1502J5D01*
G01X1245866Y137166D01*
X1245892Y137103D01*
X1245897Y137081D01*
X1245879Y137019D01*
G03X1245720Y135946I3768J-1107D01*
G01Y135902D01*
G03X1246061Y134315I3927J14D01*
G02X1246073Y134277I-184J-79D01*
G01X1246087Y134217D01*
G02Y134213I-200J-2D01*
G01X1246073Y134153D01*
G02X1246061Y134115I-196J41D01*
G03X1245720Y132515I3586J-1601D01*
G01Y132513D01*
G03X1245746Y132063I3927J1D01*
G03X1245859Y131480I3901J454D01*
G03X1245889Y131377I3785J1046D01*
G03X1245898Y131348I3755J1149D01*
G01X1245896Y131339D01*
X1245888Y131318D01*
G03X1245745Y130679I1360J-640D01*
G03Y130675I1503J-2D01*
G01Y130670D01*
G03X1247247Y129168I1502J0D01*
G01X1247248D01*
G03X1247475Y129185I2J1502D01*
G02X1247609Y129159I31J-197D01*
G03X1249647Y128588I2039J3356D01*
G01X1249648D01*
G03X1251685Y129158I-1J3927D01*
G02X1251818Y129185I104J-171D01*
G03X1252051Y129168I225J1485D01*
G01X1252054D01*
G03X1252525Y129246I-7J1502D01*
G01X1252567Y129260D01*
X1252613Y129256D01*
G02X1252714Y129216I-20J-199D01*
G01X1252803Y129152D01*
X1252976Y129028D01*
G02X1253022Y128978I-122J-158D01*
G01X1253023Y128977D01*
X1253021Y128902D01*
Y128889D01*
G03X1253020Y128829I3925J-95D01*
G01Y128774D01*
G03X1253361Y127228I3926J55D01*
G02X1253373Y127190I-184J-79D01*
G01X1253387Y127130D01*
G02Y127126I-200J-2D01*
G01X1253373Y127066D01*
G02X1253361Y127028I-196J41D01*
G03X1253020Y125482I3585J-1601D01*
G01Y125427D01*
G03X1253021Y125367I3926J35D01*
G01Y125356D01*
X1253023Y125282D01*
G02X1252975Y125227I-172J102D01*
G01X1252797Y125097D01*
X1252795D01*
X1252719Y125042D01*
G02X1252624Y125008I-113J165D01*
G01X1252622D01*
G02X1252606Y125007I-20J199D01*
G01X1252529D01*
X1252499Y125016D01*
G03X1252053Y125086I-453J-1432D01*
G01X1252045D01*
G03X1251790Y125064I1J-1502D01*
G01X1251751Y125057D01*
G03X1249647Y125668I-2103J-3315D01*
G03X1247607Y125097I-1J-3926D01*
G01X1247606D01*
G02X1247504Y125068I-104J171D01*
G01X1247479D01*
X1247465Y125070D01*
X1247461Y125071D01*
X1247453Y125072D01*
X1247452D01*
X1247439Y125074D01*
G03X1247389Y125080I-204J-1488D01*
G01X1247388D01*
G03X1247271Y125086I-135J-1496D01*
G01X1247247D01*
G03X1245745Y123584I0J-1502D01*
G01Y123579D01*
G03X1245859Y123010I1502J5D01*
G01X1245866Y122993D01*
X1245892Y122930D01*
X1245897Y122908D01*
X1245879Y122846D01*
G03X1245720Y121750I3768J-1106D01*
G01Y121715D01*
G03X1245824Y120844I3927J27D01*
G03X1246062Y120139I3823J898D01*
G01X1246069Y120123D01*
X1246087Y120044D01*
G02Y120040I-200J-2D01*
G01X1246069Y119961D01*
X1246062Y119945D01*
G03X1245720Y118342I3585J-1603D01*
G03X1245779Y117663I3927J-1D01*
G03X1245859Y117308I3867J685D01*
G01Y117306D01*
G03X1245887Y117213I3773J1085D01*
G01Y117211D01*
G03X1245898Y117175I3761J1129D01*
G01X1245896Y117168D01*
X1245891Y117146D01*
G03X1245745Y116499I1357J-646D01*
G01Y116497D01*
G03X1247247Y114995I1502J0D01*
G01X1247248D01*
G03X1247542Y115024I0J1502D01*
G01X1247543D01*
X1247546Y115025D01*
G03X1249646Y114416I2100J3317D01*
G01X1249648D01*
G03X1251747Y115024I0J3926D01*
G01X1251748D01*
X1251750Y115023D01*
X1251772Y115019D01*
G03X1252046Y114995I268J1478D01*
G01X1252048D01*
G03X1252507Y115067I0J1502D01*
G01X1252527Y115074D01*
X1252542Y115079D01*
G02X1252646Y115077I48J-195D01*
G01X1252689Y115062D01*
X1252974Y114854D01*
G02X1253023Y114802I-119J-161D01*
G01X1253021Y114715D01*
Y114714D01*
G03X1253020Y114656I3925J-97D01*
G01Y114601D01*
G03X1253361Y113055I3926J55D01*
G02X1253373Y113017I-184J-79D01*
G01X1253387Y112957D01*
G02Y112953I-200J-2D01*
G01X1253369Y112874D01*
X1253362Y112858D01*
G03X1253020Y111255I3585J-1603D01*
G03X1253079Y110576I3927J-1D01*
G03X1253159Y110220I3867J682D01*
G03X1253189Y110117I3785J1046D01*
G03X1253198Y110088I3755J1149D01*
G01X1253196Y110079D01*
X1253186Y110053D01*
X1253183Y110047D01*
G03X1253045Y109415I1365J-629D01*
G01Y109410D01*
G03X1254547Y107908I1502J0D01*
G03X1254809Y107931I0J1502D01*
G01X1254847Y107937D01*
G03X1255051Y107816I2104J3315D01*
G01X1255053D01*
X1255102Y107788D01*
X1255117Y107751D01*
X1255195Y107462D01*
X1255194Y107408D01*
X1255187Y107382D01*
X1255170Y107321D01*
X1255158Y107300D01*
G03X1254964Y106562I1308J-738D01*
G01Y106526D01*
X1254965Y106510D01*
Y106507D01*
G03X1254974Y106388I1501J54D01*
G03X1255141Y105854I1492J173D01*
G03X1255539Y105379I1325J706D01*
G01X1255547Y105373D01*
X1255575Y105346D01*
X1255626Y105284D01*
X1255636Y105263D01*
X1255646Y105217D01*
X1255630Y104911D01*
X1255628Y104862D01*
X1255556Y104738D01*
X1255538Y104720D01*
X1255494Y104675D01*
X1255469Y104658D01*
G03X1254805Y103411I839J-1247D01*
G03X1257809I1502J0D01*
G03X1257221Y104603I-1502J0D01*
G01X1257210Y104611D01*
X1257184Y104637D01*
X1257166Y104660D01*
G02X1257130Y104771I164J114D01*
G01X1257145Y105105D01*
X1257164Y105142D01*
X1257168Y105151D01*
X1257203Y105210D01*
X1257217Y105233D01*
X1257279Y105297D01*
X1257304Y105314D01*
G03X1257968Y106557I-838J1247D01*
G01Y106575D01*
G03X1257892Y107036I-1502J-11D01*
G01X1257886Y107054D01*
X1257881Y107094D01*
G02X1257887Y107161I199J16D01*
G01Y107163D01*
G02X1257897Y107192I194J-51D01*
G01X1258008Y107414D01*
G02X1258054Y107474I179J-89D01*
G01X1258078Y107494D01*
X1258110Y107505D01*
X1258124Y107509D01*
X1258125D01*
G03X1259019Y107920I-1180J3745D01*
G01X1259051D01*
X1259066Y107918D01*
X1259067D01*
G03X1259115Y107913I180J1492D01*
G01X1259121D01*
X1259135Y107911D01*
G03X1259247Y107907I110J1499D01*
G03X1259323Y107909I-2J1503D01*
G01X1259361Y107912D01*
G03X1260366Y108407I-113J1498D01*
G01X1260367Y108408D01*
G02X1260515Y108474I148J-134D01*
G01X1260673D01*
G03X1263449Y109624I0J3926D01*
G01X1273452Y119627D01*
G03X1274294Y120879I-2776J2776D01*
G01X1274790Y122054D01*
X1274800Y122069D01*
G03X1275150Y122728I-3247J2147D01*
G01X1277809Y129145D01*
G02X1277819Y129163I179J-88D01*
G01X1277835Y129182D01*
G03X1277842Y129190I-144J133D01*
G01X1277848Y129199D01*
X1277851Y129203D01*
X1277892Y129244D01*
G02X1277920Y129267I140J-142D01*
G01X1277959Y129293D01*
X1277976Y129301D01*
G03X1278860Y130697I-618J1369D01*
G01X1278859Y130717D01*
Y130718D01*
G03X1278858Y130741I-1501J-54D01*
G03X1278796Y131102I-1501J-72D01*
G01Y131104D01*
G03X1278790Y131123I-1435J-443D01*
G01Y131125D01*
G03X1278757Y131215I-1427J-472D01*
G01X1278743Y131250D01*
X1278734Y131289D01*
G02X1278746Y131410I196J42D01*
G01X1279014Y132057D01*
X1279613Y133501D01*
Y133503D01*
X1284894Y146040D01*
G03X1285131Y146820I-3618J1525D01*
G01X1285565Y149068D01*
G03X1285636Y149812I-3855J743D01*
G03X1285613Y150245I-3926J9D01*
G01X1285612Y150250D01*
X1285361Y152484D01*
X1285243Y153534D01*
G02X1285242Y153556I199J20D01*
G01Y154606D01*
G03X1285212Y155086I-3892J-2D01*
G03X1285195Y155208I-3862J-476D01*
G03X1285179Y155301I-3843J-613D01*
G03X1285162Y155387I-3826J-712D01*
G01X1284885Y156743D01*
G02X1284882Y156760I195J43D01*
G01X1284864Y156915D01*
X1284767Y157783D01*
G03X1284708Y158150I-3902J-439D01*
G01X1284687Y158251D01*
X1284487Y159208D01*
X1284203Y160566D01*
G02X1284267Y160757I196J41D01*
G01X1284413Y160885D01*
X1284431Y160901D01*
G02X1284532Y160949I133J-150D01*
G03X1285136Y160825I606J1419D01*
G01X1285137D01*
G03X1286274Y161325I0J1543D01*
G02X1286297Y161326I20J-199D01*
G01X1286577D01*
G02X1286600Y161325I3J-200D01*
G03X1287737Y160825I1137J1043D01*
G03Y163911I0J1543D01*
G03X1286600Y163411I0J-1543D01*
G02X1286577Y163410I-20J199D01*
G01X1286297D01*
G02X1286274Y163411I-3J200D01*
G03X1285137Y163911I-1137J-1043D01*
G03X1284028Y163441I0J-1543D01*
G01X1284005Y163437D01*
G02X1283938Y163436I-36J197D01*
G01X1283892Y163445D01*
X1283766Y163486D01*
X1283695Y163509D01*
X1283585Y163545D01*
G02X1283578Y163548I75J185D01*
G01X1283433Y164243D01*
X1283157Y165561D01*
X1279305Y183960D01*
X1278534Y187720D01*
X1277125Y194595D01*
G02X1277122Y194627I197J35D01*
G01Y206880D01*
G02X1277131Y206940I200J1D01*
G01X1277166Y207040D01*
X1277186Y207066D01*
G03X1277362Y207361I-1195J913D01*
G03X1277494Y207964I-1369J616D01*
G01Y207979D01*
G03X1277177Y208902I-1502J0D01*
G01X1277163Y208919D01*
X1277143Y208959D01*
G02X1277122Y209048I179J89D01*
G01Y209380D01*
G02X1277131Y209440I200J1D01*
G01X1277166Y209540D01*
X1277186Y209566D01*
G03X1277494Y210478I-1194J911D01*
G01Y210496D01*
G03X1277177Y211402I-1503J-18D01*
G01X1277176Y211403D01*
X1277163Y211420D01*
X1277133Y211480D01*
X1277122Y211525D01*
Y211880D01*
G02X1277131Y211940I200J1D01*
G01X1277166Y212040D01*
X1277186Y212066D01*
G03X1277494Y212978I-1194J911D01*
G01Y212996D01*
G03X1277177Y213902I-1503J-18D01*
G01X1277176Y213903D01*
X1277163Y213920D01*
X1277133Y213980D01*
X1277122Y214025D01*
Y214380D01*
G02X1277131Y214440I200J1D01*
G01X1277166Y214540D01*
X1277186Y214566D01*
G03X1277494Y215478I-1194J911D01*
G01Y215496D01*
G03X1277362Y216095I-1501J-17D01*
G03X1277349Y216123I-1370J-619D01*
G01X1277325Y216172D01*
X1277319Y216184D01*
G03X1277188Y216388I-1326J-707D01*
G01X1277166Y216416D01*
X1277131Y216516D01*
G02X1277122Y216576I191J59D01*
G01Y220171D01*
X1277123Y220186D01*
Y220210D01*
G03X1277124Y220274I-3892J93D01*
G01Y220276D01*
G03Y220279I-200J1D01*
G03X1277123Y220347I-3892J-23D01*
G01Y220357D01*
X1277122Y220368D01*
X1277101Y221291D01*
X1277080Y222199D01*
X1277071Y222568D01*
Y222609D01*
X1277107Y222701D01*
G02X1277141Y222758I186J-73D01*
G01X1277153Y222772D01*
X1277156Y222776D01*
G03X1277160Y222781I-1171J941D01*
G01X1277161Y222782D01*
G03X1277491Y223624I-1169J944D01*
G03X1277494Y223710I-1499J95D01*
G01Y223730D01*
G03X1277095Y224746I-1503J-4D01*
G01X1277071Y224772D01*
X1277023Y224885D01*
X1277019Y224907D01*
G02X1277015Y224942I196J40D01*
G01X1277013Y225035D01*
X1277012Y225076D01*
X1277041Y225150D01*
X1277069Y225179D01*
G03X1277494Y226225I-1077J1047D01*
G01Y226230D01*
G03X1277493Y226293I-1502J8D01*
G01X1277492Y226310D01*
Y226312D01*
G03X1277344Y226881I-1500J-86D01*
G01X1277319Y226933D01*
X1277301Y226964D01*
X1277300Y226965D01*
X1277287Y226988D01*
G03X1277028Y227316I-1298J-758D01*
G01X1276998Y227345D01*
X1276966Y227419D01*
Y227471D01*
G02X1276978Y227539I200J0D01*
G01X1277016Y227625D01*
X1277043Y227652D01*
G03X1277494Y228716I-1051J1073D01*
G01Y228726D01*
G03X1277492Y228812I-1502J8D01*
G01X1277491Y228823D01*
Y228826D01*
G03X1277486Y228879I-1498J-115D01*
G01Y228883D01*
G03X1277482Y228920I-1495J-143D01*
G01Y228921D01*
X1277481Y228926D01*
X1277480Y228936D01*
Y228937D01*
G03X1277242Y229560I-1488J-211D01*
G01X1277220Y229592D01*
X1277208Y229609D01*
X1277184Y229642D01*
X1277167Y229662D01*
G02X1277149Y229691I161J120D01*
G01X1277145Y229699D01*
G02X1277124Y229788I179J89D01*
G01Y229871D01*
G03X1277106Y229954I-200J0D01*
G01X1277081Y230002D01*
G02X1277062Y230084I181J85D01*
G01Y230098D01*
G02X1277064Y230121I200J-6D01*
G01X1277069Y230147D01*
X1277096Y230204D01*
X1277115Y230225D01*
G03X1277495Y231224I-1124J999D01*
G03Y231226I-1504J1D01*
G01Y231251D01*
X1277492Y231310D01*
G03X1277437Y231638I-1500J-83D01*
G03X1276913Y232413I-1444J-412D01*
G01X1276912D01*
G02X1276857Y232481I124J157D01*
G01X1276847Y232501D01*
X1276836Y232543D01*
X1276675Y239405D01*
G03X1276599Y240088I-3892J-87D01*
G01X1275887Y243645D01*
X1275747Y244344D01*
X1268456Y280772D01*
X1267450Y285802D01*
X1265373Y296180D01*
X1264887Y298630D01*
X1264898Y298666D01*
G02X1264928Y298728I192J-55D01*
G02X1264946Y298749I161J-119D01*
G01X1265014Y298817D01*
X1265051Y298832D01*
G03X1265983Y300223I-572J1391D01*
G03X1265980Y300325I-1502J7D01*
G01X1265979Y300347D01*
Y300358D01*
G02X1265983Y300385I200J-16D01*
G01X1265997Y300425D01*
G02X1266032Y300478I182J-82D01*
G02X1266048Y300493I145J-138D01*
G01X1266055Y300498D01*
X1266056Y300499D01*
X1266255Y300656D01*
X1266267Y300665D01*
G02X1266269Y300666I89J-175D01*
G01X1266327Y300710D01*
G02X1266413Y300743I113J-165D01*
G01X1266468Y300748D01*
X1266511Y300734D01*
X1266528Y300729D01*
X1266555Y300721D01*
G03X1266957Y300665I406J1446D01*
G01X1266970D01*
G03X1268464Y302167I-8J1502D01*
G03X1266962Y303669I-1502J0D01*
G03X1265460Y302168I0J-1502D01*
G01Y302146D01*
G03X1265463Y302076I1502J29D01*
G01Y302070D01*
X1265464Y302048D01*
G02X1265401Y301900I-200J-2D01*
G01X1265119Y301680D01*
X1265103Y301672D01*
X1265076Y301654D01*
X1264988Y301640D01*
G02X1264986Y301639I-88J174D01*
G01X1264984D01*
X1264938Y301654D01*
G03X1264502Y301725I-457J-1431D01*
G01X1264446D01*
X1264432Y301724D01*
X1264428D01*
G02X1264359Y301736I-1J200D01*
G02X1264253Y301826I68J188D01*
G01X1264136Y302414D01*
X1264137Y302425D01*
X1264139Y302437D01*
G03X1264156Y302547I-1475J284D01*
G01Y302548D01*
X1264157Y302560D01*
G03X1264160Y302588I-1492J174D01*
G01X1264161Y302594D01*
Y302596D01*
G03X1264167Y302701I-1496J138D01*
G01Y302707D01*
X1264168Y302723D01*
Y302730D01*
G03X1263911Y303571I-1503J0D01*
G01X1263904Y303582D01*
X1263201Y307124D01*
G02X1263233Y307196I195J-44D01*
G01X1263399Y307432D01*
X1263435Y307454D01*
X1263531Y307513D01*
X1263570Y307520D01*
G03X1264830Y309003I-243J1483D01*
G03X1263328Y310505I-1502J0D01*
G01X1263327D01*
G03X1262949Y310456I3J-1502D01*
G01X1262922Y310449D01*
X1262893Y310450D01*
X1262837Y310451D01*
X1262563Y310623D01*
G02X1262533Y310646I106J170D01*
G02X1262528Y310651I139J144D01*
G01X1262517Y310662D01*
X1262503Y310688D01*
G02X1262483Y310744I176J95D01*
G01X1262284Y311750D01*
X1261779Y314295D01*
X1261363Y316392D01*
G02X1261386Y316436I188J-70D01*
G01X1261417Y316476D01*
X1261420Y316480D01*
X1261493Y316574D01*
X1261553Y316651D01*
G02X1261626Y316709I157J-123D01*
G01X1261662Y316726D01*
X1261728Y316756D01*
X1261765Y316759D01*
X1261766D01*
G03X1261840Y316766I-104J1499D01*
G03X1262266Y316883I-181J1492D01*
G01X1262274Y316887D01*
G03X1262680Y317156I-616J1370D01*
G01X1262681Y317157D01*
X1262685Y317160D01*
G03X1262834Y317322I-1028J1095D01*
G01X1262886Y317388D01*
G03X1262889Y317392I-158J122D01*
G01X1262925Y317448D01*
G03X1262961Y317508I-1270J803D01*
G01X1262980Y317542D01*
X1262991Y317563D01*
G03X1263161Y318247I-1332J694D01*
G01Y318296D01*
G03X1263154Y318408I-1502J-38D01*
G01X1263151Y318435D01*
Y318541D01*
G02X1263216Y318688I200J-1D01*
G01X1263276Y318740D01*
X1263464Y318903D01*
X1263469Y318907D01*
G02X1263591Y318949I123J-158D01*
G01X1263613D01*
X1263652Y318945D01*
X1263670Y318939D01*
G03X1263776Y318912I424J1441D01*
G01X1263777D01*
X1263797Y318908D01*
G03X1263912Y318890I290J1474D01*
G01X1263965Y318884D01*
X1263985D01*
G03X1264088Y318880I110J1498D01*
G03X1264288Y318893I3J1502D01*
G03X1264814Y319066I-198J1490D01*
G01X1264833Y319076D01*
X1267384D01*
G03X1268306Y319458I-1J1306D01*
G01X1269924Y321076D01*
G03X1270306Y321998I-924J923D01*
G01Y325502D01*
G03X1269924Y326424I-1306J-1D01*
G01X1269498Y326850D01*
G02X1269462Y326900I142J140D01*
G02X1269440Y326991I178J91D01*
G01Y341220D01*
G03X1269057Y342144I-1306J0D01*
G01X1267070Y344130D01*
G02X1267016Y344231I142J141D01*
G02X1267014Y344243I196J39D01*
G01Y370073D01*
G02X1267029Y370090I157J-124D01*
G01X1267050Y370111D01*
X1267330Y370313D01*
G02X1267335Y370316I105J-170D01*
G01X1267406Y370292D01*
G02X1267410Y370290I-87J-178D01*
G03X1267943Y370197I533J1478D01*
G01X1267944D01*
G03X1269514Y371767I0J1570D01*
G01Y371768D01*
G03X1268945Y372978I-1570J1D01*
G01X1268921Y372997D01*
X1268853Y373106D01*
X1268846Y373136D01*
X1268827Y373176D01*
X1268807Y373200D01*
G03X1268656Y373269I-151J-131D01*
G01X1268444D01*
G02X1268419Y373271I3J200D01*
G01X1268375Y373277D01*
G03X1267946Y373337I-430J-1510D01*
G01X1267944D01*
G03X1266884Y372925I0J-1570D01*
G02X1266882Y372923I-142J140D01*
G01X1266855Y372898D01*
X1266820Y372885D01*
G02X1266744Y372874I-66J189D01*
G01X1266710Y372875D01*
G02X1266699Y372876I13J200D01*
G01X1266670Y372905D01*
G02X1266664Y372911I138J144D01*
G03X1266631Y372946I-968J-879D01*
G01X1264468Y375108D01*
G02X1264472Y375188I198J30D01*
G01X1264528Y375341D01*
Y375343D01*
X1264586Y375497D01*
X1264591Y375508D01*
G02X1264604Y375531I180J-87D01*
G01X1264619Y375548D01*
X1264620Y375549D01*
X1264628Y375560D01*
X1264635Y375568D01*
G02X1264640Y375573I144J-139D01*
G02X1264643Y375575I112J-165D01*
G01X1264728Y375640D01*
X1264731Y375642D01*
X1264751Y375657D01*
X1264774Y375667D01*
G02X1264829Y375681I76J-185D01*
G01X1264830D01*
G03X1266161Y377173I-171J1492D01*
G03X1264659Y378675I-1502J0D01*
G03X1263167Y377346I0J-1502D01*
G01Y377345D01*
X1263164Y377323D01*
X1263155Y377296D01*
X1263145Y377267D01*
X1263052Y377145D01*
X1263051Y377144D01*
X1263043Y377134D01*
X1263022Y377108D01*
X1262993Y377091D01*
G02X1262927Y377067I-100J173D01*
G01X1262899Y377062D01*
X1262898D01*
X1262889Y377060D01*
G03X1262850Y377050I30J-198D01*
G01X1262775Y377022D01*
G02X1262771Y377020I-91J177D01*
G01X1262689Y376991D01*
G02X1262631Y376982I-59J191D01*
G01X1262624D01*
X1262527Y377051D01*
G02X1262518Y377058I118J161D01*
G01X1256330Y383247D01*
G02X1256290Y383367I160J120D01*
G01Y401541D01*
G02X1256291Y401564I200J3D01*
G02X1256347Y401681I199J-23D01*
G01X1258242Y403575D01*
G03X1258624Y404497I-924J923D01*
G01Y452567D01*
G02X1258652Y452597I159J-121D01*
G01X1258822Y452746D01*
X1258869Y452787D01*
G02X1258903Y452812I135J-148D01*
G01X1258911Y452817D01*
G02X1259011Y452844I100J-173D01*
G01X1259033D01*
X1259045Y452843D01*
G03X1259223Y452832I181J1491D01*
G03Y455836I0J1502D01*
G03X1259035Y455824I1J-1502D01*
G01X1259025Y455823D01*
G02X1258890Y455863I-14J200D01*
G02X1258879Y455872I121J159D01*
G01X1258652Y456071D01*
G02X1258624Y456101I131J151D01*
G01Y463317D01*
G02X1258626Y463343I200J-2D01*
G02X1258681Y463457I198J-25D01*
G01X1261594Y466369D01*
G03X1261976Y467291I-924J923D01*
G01Y513264D01*
G02X1261987Y513328I200J-1D01*
G02X1262034Y513405I190J-63D01*
G01X1284099Y535469D01*
G02X1284198Y535522I140J-143D01*
G02X1284239Y535526I40J-196D01*
G01X1323445D01*
G03X1324369Y535909I0J1306D01*
G01X1340924Y552464D01*
G03X1341306Y553386I-924J923D01*
G01Y555379D01*
G02X1341466Y555459I160J-120D01*
G01X1345870D01*
G02X1345902Y555456I-3J-200D01*
G01X1345904D01*
G02X1346010Y555402I-34J-197D01*
G01X1349336Y552076D01*
G02X1349372Y552026I-142J-140D01*
G02X1349394Y551935I-178J-91D01*
G01Y495854D01*
G03X1349776Y494932I1306J1D01*
G01X1350710Y493998D01*
G02X1350712Y493970I-198J-28D01*
G01Y493782D01*
G03X1350771Y493640I200J0D01*
G01X1376437Y467974D01*
G02X1376439Y467972I-140J-142D01*
G02X1376456Y467952I-144J-139D01*
G01Y436842D01*
G02X1376409Y436797I-160J120D01*
G01X1376137Y436611D01*
X1376135D01*
X1376105Y436590D01*
X1375950D01*
X1375917Y436602D01*
G03X1375400Y436694I-518J-1410D01*
G03X1373908Y435368I0J-1502D01*
G01X1373901Y435308D01*
G03X1373897Y435192I1499J-110D01*
G01Y435191D01*
G03X1374398Y434071I1503J0D01*
G01X1374414Y434057D01*
X1374447Y434012D01*
X1374460Y433995D01*
X1374500Y433907D01*
G02X1374510Y433868I-187J-69D01*
G01Y433864D01*
G02X1374512Y433853I-195J-41D01*
G01X1374511Y433731D01*
Y433729D01*
X1374508Y433611D01*
G02X1374487Y433527I-200J5D01*
G01X1374449Y433449D01*
G02X1374416Y433405I-175J97D01*
G01X1374406Y433395D01*
X1374399Y433389D01*
G03X1373858Y432235I961J-1154D01*
G01Y432205D01*
G03X1375360Y430732I1502J29D01*
G01X1375361D01*
G03X1375907Y430835I0J1501D01*
G01X1375939Y430848D01*
X1375956Y430854D01*
G02X1376117Y430839I64J-190D01*
G01X1376132Y430831D01*
X1376267Y430738D01*
X1376269D01*
X1376407Y430646D01*
G02X1376456Y430599I-112J-166D01*
G01Y427956D01*
G02X1376455Y427932I-200J-4D01*
G02X1376398Y427815I-199J24D01*
G01X1374824Y426242D01*
G02X1374786Y426212I-142J141D01*
G01X1374727Y426177D01*
G02X1374725Y426176I-89J176D01*
G03X1373669Y424741I447J-1435D01*
G03X1373684Y424526I1502J-3D01*
G01X1373685Y424519D01*
X1373688Y424505D01*
G03X1374614Y423346I1483J236D01*
G03X1374826Y423279I557J1395D01*
G01X1374839Y423276D01*
X1374884Y423259D01*
G02X1374907Y423249I-68J-188D01*
G01X1374951Y423226D01*
X1374961Y423221D01*
X1375011Y423162D01*
X1375023Y423123D01*
X1375024Y423121D01*
X1375055Y423022D01*
Y423021D01*
X1375065Y422992D01*
X1375103Y422862D01*
Y422860D01*
X1375125Y422780D01*
G02X1375128Y422705I-195J-45D01*
G01X1374848Y422426D01*
X1374710Y422288D01*
X1374672Y422276D01*
G03X1373606Y420838I437J-1438D01*
G03X1375108Y419336I1502J0D01*
G03X1376035Y419656I0J1503D01*
G01X1376055Y419671D01*
G02X1376135Y419698I103J-172D01*
G01X1376177D01*
G02X1376233Y419684I-20J-198D01*
G01X1376545Y419534D01*
X1376580Y419517D01*
G02X1376683Y419346I-97J-175D01*
G01Y399327D01*
G02X1376645Y399210I-200J0D01*
G01Y399209D01*
G02X1376593Y399159I-163J117D01*
G01X1376551Y399145D01*
G03X1375516Y397713I473J-1432D01*
G01Y397711D01*
G03X1375530Y397505I1508J-1D01*
G01X1375531Y397498D01*
X1375533Y397471D01*
G02X1375489Y397347I-200J1D01*
G01X1375462Y397316D01*
X1375464Y397237D01*
G03X1375521Y397103I200J6D01*
G01X1375847Y396769D01*
X1375858Y396756D01*
G03X1376168Y396471I1166J957D01*
G03X1376546Y396283I854J1243D01*
G01X1376574Y396274D01*
X1376579Y396272D01*
G02X1376631Y396231I-96J-175D01*
G02X1376635Y396226I-154J-127D01*
G03X1376637Y396224I142J140D01*
G02X1376683Y396096I-154J-128D01*
G01Y392706D01*
G03X1376883Y392506I200J0D01*
G01X1381486D01*
G02X1381646Y392426I0J-200D01*
G01Y377106D01*
G02X1381644Y377080I-200J2D01*
G02X1381589Y376966I-198J25D01*
G01X1378528Y373906D01*
G03X1378146Y372984I924J-923D01*
G01Y333327D01*
G02X1378134Y333258I-200J-1D01*
G02X1378088Y333186I-188J69D01*
G01X1347495Y302594D01*
G03X1347112Y301670I923J-924D01*
G01Y265964D01*
X1347105Y265951D01*
G03X1346917Y265228I1314J-728D01*
G01Y265213D01*
G03X1348405Y263720I1502J9D01*
G01X1348428D01*
G03X1348776Y263762I-5J1502D01*
G01X1348779Y263763D01*
X1348793Y263766D01*
X1348820Y263769D01*
G02X1348956Y263733I20J-199D01*
G01X1348972Y263721D01*
X1349147Y263585D01*
X1349212Y263535D01*
X1349214Y263533D01*
X1349217Y263531D01*
X1349218Y263530D01*
G02X1349248Y263498I-130J-152D01*
G01Y231211D01*
G02X1349238Y231148I-200J-1D01*
G02X1349190Y231070I-190J63D01*
G01X1328484Y210365D01*
G02X1328446Y210335I-142J141D01*
G01X1328387Y210300D01*
G02X1328385Y210299I-89J176D01*
G03X1327329Y208864I447J-1435D01*
G03X1328831Y207362I1502J0D01*
G03X1330265Y208418I0J1502D01*
G01X1330270Y208433D01*
G02X1330285Y208462I185J-77D01*
G02X1330314Y208499I171J-104D01*
G01X1351478Y229663D01*
G03X1351860Y230585I-924J923D01*
G01Y300734D01*
G02X1351872Y300803I200J1D01*
G02X1351918Y300875I188J-69D01*
G01X1382106Y331062D01*
G03X1382488Y331984I-924J923D01*
G01Y333221D01*
G02X1382576Y333288I160J-119D01*
G01X1382819Y333382D01*
X1382922Y333422D01*
G02X1383123Y333388I72J-187D01*
G01X1383142Y333372D01*
X1383151Y333362D01*
G03X1384229Y332869I1113J1009D01*
G01X1384274D01*
G03X1384337Y332870I8J1502D01*
G01X1384375Y332873D01*
G03X1385767Y334371I-110J1498D01*
G03X1384265Y335873I-1502J0D01*
G01X1384226D01*
G03X1384117Y335866I42J-1502D01*
G01X1384097Y335864D01*
X1384096D01*
X1384036Y335858D01*
X1383997Y335851D01*
X1383984Y335849D01*
X1383935Y335838D01*
G03X1383756Y335785I336J-1465D01*
G03X1383410Y335607I509J-1414D01*
G01X1383352Y335566D01*
G03X1383338Y335555I116J-163D01*
G01X1383300Y335523D01*
G03X1383249Y335478I968J-1149D01*
G01X1383248Y335477D01*
G03X1383146Y335375I1010J-1112D01*
G01X1383118Y335344D01*
X1383041Y335310D01*
X1382982D01*
G02X1382917Y335321I0J200D01*
G01X1382836Y335354D01*
X1382834D01*
X1382576Y335454D01*
G02X1382488Y335521I72J186D01*
G01Y336159D01*
G02X1382535Y336204I160J-120D01*
G01X1382810Y336392D01*
G02X1382900Y336426I114J-165D01*
G01X1382949Y336431D01*
X1382996Y336412D01*
G03X1383550Y336306I554J1396D01*
G01X1383604D01*
X1383615Y336307D01*
X1383619Y336308D01*
X1383627D01*
G03X1385053Y337808I-76J1500D01*
G03X1383563Y339310I-1502J0D01*
G01X1383556D01*
G03X1383014Y339211I-6J-1502D01*
G01X1383001Y339206D01*
X1382956Y339196D01*
G02X1382806Y339227I-38J196D01*
G01X1382532Y339413D01*
G02X1382488Y339456I116J163D01*
G01Y341154D01*
G02X1382540Y341202I160J-121D01*
G01X1382658Y341278D01*
X1382677Y341290D01*
G03X1382715Y341321I-107J170D01*
G01X1382727Y341334D01*
G02X1382873Y341398I147J-136D01*
G01X1382995D01*
X1383032Y341382D01*
G03X1383617Y341264I584J1386D01*
G01X1383618D01*
G03X1383620I1J1504D01*
G03X1383622I1J1504D01*
G01X1383634D01*
G03Y344268I0J1502D01*
G01X1383631D01*
G03X1383029Y344142I0J-1502D01*
G01X1383011Y344134D01*
X1382972Y344125D01*
G02X1382855Y344134I-44J195D01*
G01X1382819Y344152D01*
X1382683Y344239D01*
X1382681D01*
X1382557Y344319D01*
G02X1382525Y344345I109J167D01*
G01X1382518Y344352D01*
X1382503Y344388D01*
G02X1382488Y344464I185J76D01*
G01Y347768D01*
G02X1382505Y347788I161J-119D01*
G01X1382530Y347813D01*
X1382661Y347905D01*
X1382663D01*
X1382811Y348008D01*
G02X1382872Y348032I103J-172D01*
G02X1382940Y348035I43J-195D01*
G01X1382976Y348028D01*
X1382991Y348023D01*
G03X1383503Y347933I513J1414D01*
G01X1383505D01*
G03X1385009Y349437I0J1504D01*
G03X1384696Y350356I-1505J0D01*
G01X1384690Y350363D01*
X1384672Y350392D01*
G02X1384670Y350395I164J112D01*
G02X1384662Y350411I175J97D01*
G01X1384646Y350450D01*
Y350518D01*
G02X1384653Y350568I200J-2D01*
G01X1384714Y350805D01*
G02X1384757Y350885I193J-52D01*
G01X1384843Y350984D01*
X1384870Y350996D01*
G03X1385767Y352371I-605J1375D01*
G03X1384265Y353873I-1502J0D01*
G01X1384226D01*
G03X1384117Y353866I42J-1502D01*
G01X1384097Y353864D01*
X1384096D01*
X1384036Y353858D01*
X1383997Y353851D01*
X1383984Y353849D01*
X1383935Y353838D01*
G03X1383756Y353785I336J-1465D01*
G03X1383410Y353607I509J-1414D01*
G01X1383352Y353566D01*
G03X1383338Y353555I116J-163D01*
G01X1383300Y353523D01*
G03X1383249Y353478I968J-1149D01*
G01X1383248Y353477D01*
G03X1383146Y353375I1010J-1112D01*
G01X1383118Y353344D01*
X1383041Y353310D01*
X1382982D01*
G02X1382917Y353321I0J200D01*
G01X1382836Y353354D01*
X1382834D01*
X1382576Y353454D01*
G02X1382488Y353521I72J186D01*
G01Y365254D01*
G02X1382550Y365308I160J-121D01*
G01X1382605Y365336D01*
X1382867Y365468D01*
G02X1383024Y365478I90J-179D01*
G01X1383050Y365469D01*
G02X1383092Y365448I-68J-188D01*
G01X1383121Y365429D01*
X1383123D01*
X1383172Y365397D01*
X1383207Y365377D01*
X1383212Y365374D01*
X1383214Y365373D01*
X1383219Y365370D01*
G03X1383963Y365173I744J1306D01*
G03Y368177I0J1502D01*
G03X1383083Y367892I0J-1501D01*
G01X1383069Y367882D01*
G02X1382982Y367854I-103J172D01*
G01X1382927Y367850D01*
X1382712Y367959D01*
X1382557Y368038D01*
G02X1382551Y368041I86J180D01*
G02X1382488Y368096I97J175D01*
G01Y371641D01*
G02X1382490Y371667I200J-2D01*
G02X1382545Y371781I198J-25D01*
G01X1385606Y374841D01*
G03X1385988Y375763I-924J923D01*
G01Y392426D01*
G02X1386148Y392506I160J-120D01*
G01X1401971D01*
G02X1402171Y392306I0J-200D01*
G01Y391603D01*
G02X1402166Y391559I-200J0D01*
G02X1402151Y391516I-195J44D01*
G01X1402115Y391442D01*
G02X1402060Y391375I-179J90D01*
G01X1402059Y391374D01*
X1402049Y391366D01*
G03X1401923Y391256I923J-1185D01*
G03X1401921Y391254I140J-142D01*
G01X1401912Y391245D01*
X1401902Y391237D01*
X1401875Y391216D01*
X1401811Y391193D01*
X1401771D01*
X1401474Y391202D01*
G02X1401406Y391220I16J199D01*
G01X1401370Y391237D01*
X1401342Y391267D01*
G03X1400231Y391758I-1111J-1011D01*
G03Y388754I0J-1502D01*
G03X1401243Y389146I0J1502D01*
G01X1401244Y389147D01*
X1401257Y389158D01*
X1401289Y389170D01*
G02X1401360Y389183I71J-187D01*
G01X1401428D01*
X1401458Y389211D01*
X1401492Y389224D01*
G02X1401556Y389236I68J-188D01*
G01X1401655Y389233D01*
X1401657D01*
X1401727Y389230D01*
G02X1401793Y389213I-16J-199D01*
G01X1401829Y389196D01*
X1401857Y389166D01*
G03X1402968Y388675I1111J1011D01*
G01X1402969D01*
G03X1403116Y388682I2J1502D01*
G01X1403135Y388684D01*
G02X1403319Y388574I5J-200D01*
G01X1403402Y388399D01*
Y388397D01*
X1403473Y388250D01*
G02X1403486Y388209I-183J-81D01*
G01Y388208D01*
X1403488Y388200D01*
G02X1403475Y388093I-198J-30D01*
G01X1396326Y380943D01*
G03X1395942Y380019I925J-926D01*
G01Y380017D01*
G03X1395944Y379959I1309J16D01*
G01Y365374D01*
G03X1396353Y364425I1307J1D01*
G02X1396357Y364421I-139J-143D01*
G01X1401557Y359221D01*
G02X1401610Y359119I-143J-139D01*
G02X1401614Y359081I-196J-40D01*
G01Y323145D01*
X1401607Y323132D01*
G03X1401419Y322409I1314J-728D01*
G01Y322373D01*
G03X1404420Y322302I1502J29D01*
G03X1404423Y322391I-1499J95D01*
G01Y322404D01*
G03X1404235Y323132I-1502J0D01*
G01X1404228Y323145D01*
Y359705D01*
G03X1404128Y360206I-1307J0D01*
G01X1404093Y360289D01*
G02X1404109Y360332I195J-48D01*
G01X1404130Y360374D01*
X1404143Y360391D01*
X1404144Y360392D01*
X1404298Y360592D01*
X1404340Y360646D01*
G02X1404458Y360713I152J-130D01*
G01X1404480Y360716D01*
X1404515D01*
X1404526Y360715D01*
G03X1404681Y360707I155J1494D01*
G01X1404695D01*
G03X1406192Y362209I-5J1502D01*
G03X1403188I-1502J0D01*
G01Y362196D01*
G02X1403065Y362012I-200J1D01*
G01X1402876Y361933D01*
X1402716Y361866D01*
G02X1402681Y361856I-72J187D01*
G02X1402619Y361855I-34J197D01*
G01X1399374Y365099D01*
G02X1399372Y365143I197J31D01*
G01X1399375Y365185D01*
X1399493Y365435D01*
Y365437D01*
X1399555Y365570D01*
G02X1399564Y365585I176J-95D01*
G02X1399726Y365669I163J-116D01*
G01X1399731D01*
X1399744Y365668D01*
G03X1399875Y365663I123J1497D01*
G01X1399891D01*
G03X1401386Y367165I-7J1502D01*
G03X1399884Y368667I-1502J0D01*
G01X1399882D01*
G03X1399182Y368493I2J-1503D01*
G01X1399180Y368492D01*
X1399145Y368474D01*
X1399121Y368468D01*
G02X1399068Y368461I-52J193D01*
G01X1398975Y368463D01*
X1398956Y368464D01*
X1398908Y368465D01*
X1398672Y368600D01*
X1398595Y368644D01*
G02X1398558Y368681I122J159D01*
G01Y379391D01*
G02X1398562Y379429I200J-2D01*
G02X1398615Y379531I196J-37D01*
G01X1411588Y392504D01*
G02X1411613Y392506I28J-198D01*
G01X1413463D01*
G03X1413605Y392565I0J200D01*
G01X1419324Y398284D01*
G03X1419383Y398426I-141J142D01*
G01Y406159D01*
G02X1419418Y406270I200J-2D01*
G01Y406272D01*
G02X1419434Y406292I164J-115D01*
G01X1419506Y406339D01*
X1419514Y406345D01*
G02X1419527Y406352I101J-172D01*
G01X1419534Y406355D01*
X1419535Y406356D01*
X1419698Y406433D01*
X1419731Y406449D01*
X1419783Y406473D01*
X1419823Y406492D01*
X1419927D01*
G02X1419989Y406482I0J-200D01*
G01X1420040Y406464D01*
X1420067Y406442D01*
G03X1420996Y406114I937J1174D01*
G01X1421025D01*
G03X1422507Y407616I-20J1502D01*
G03X1421032Y409118I-1502J0D01*
G01X1421028D01*
X1421010Y409119D01*
X1420996D01*
G03X1420216Y408895I9J-1503D01*
G03X1420065Y408788I791J-1277D01*
G01X1420040Y408768D01*
X1419962Y408739D01*
G02X1419823Y408742I-65J189D01*
G01X1419785Y408760D01*
X1419783Y408761D01*
X1419740Y408781D01*
X1419552Y408868D01*
X1419498Y408893D01*
G02X1419387Y409035I85J181D01*
G01Y409037D01*
G02X1419383Y409074I196J40D01*
G01Y439662D01*
X1419386Y439678D01*
G03X1419405Y439919I-1483J238D01*
G03X1419386Y440160I-1502J3D01*
G01X1419383Y440176D01*
Y459859D01*
G02X1419416Y459969I200J0D01*
G01X1419432Y459993D01*
X1419475Y460030D01*
X1419506Y460043D01*
G03X1420405Y461419I-604J1376D01*
G03X1419503Y462796I-1502J0D01*
G01X1419502Y462797D01*
G02X1419415Y462870I80J183D01*
G01X1419399Y462894D01*
X1419391Y462922D01*
G02X1419383Y462978I192J56D01*
G01Y465822D01*
G02X1419463Y465982I200J0D01*
G01X1428728D01*
G03X1429652Y466365I0J1306D01*
G01X1431831Y468544D01*
G02X1431869Y468574I142J-141D01*
G01X1431928Y468609D01*
G02X1431930Y468610I89J-176D01*
G03X1432986Y470045I-447J1435D01*
G03X1431484Y471547I-1502J0D01*
G03X1430050Y470491I0J-1502D01*
G01X1430045Y470476D01*
G02X1430030Y470447I-185J77D01*
G02X1430001Y470410I-171J104D01*
G01X1428245Y468654D01*
G02X1428195Y468618I-140J142D01*
G02X1428104Y468596I-91J178D01*
G01X1420434D01*
G02X1420417Y468610I118J161D01*
G02X1420383Y468652I137J146D01*
G01X1420336Y468733D01*
X1420308Y468781D01*
X1420300Y468796D01*
X1420278Y468834D01*
G02X1420272Y469006I178J92D01*
G01X1420301Y469058D01*
X1420303Y469061D01*
G03X1420538Y469904I-1401J845D01*
G01Y469905D01*
G03X1419509Y471424I-1636J0D01*
G01X1419494Y471430D01*
G02X1419441Y471468I89J180D01*
G02X1419383Y471602I142J141D01*
G01Y483209D01*
G02X1419387Y483248I200J-1D01*
G01X1419404Y483319D01*
X1419406Y483323D01*
G02X1419426Y483353I176J-95D01*
G01X1419529Y483465D01*
X1419531Y483467D01*
X1419627Y483573D01*
G02X1419684Y483612I140J-143D01*
G01X1419715Y483626D01*
X1419738Y483628D01*
G03X1419831Y483636I-82J1501D01*
G03X1419968Y483659I-180J1492D01*
G03X1419986Y483663I-317J1468D01*
G01X1419988D01*
G03X1420012Y483669I-352J1460D01*
G01X1420016D01*
X1420018Y483670D01*
X1420050Y483679D01*
G03X1420107Y483696I-401J1448D01*
G03X1420197Y483728I-458J1431D01*
G03X1420325Y483785I-547J1400D01*
G03X1420789Y484147I-675J1343D01*
G01X1420818Y484172D01*
X1420832Y484178D01*
X1420863Y484192D01*
G02X1420877Y484196I62J-190D01*
G02X1420908Y484201I47J-194D01*
G01X1421074Y484205D01*
X1421076D01*
X1421225Y484206D01*
X1421264Y484190D01*
X1421309Y484169D01*
X1421328Y484161D01*
X1421393Y484114D01*
X1421406Y484100D01*
G03X1422499Y483631I1093J1039D01*
G03X1423440Y483961I0J1507D01*
G01X1423441Y483962D01*
X1423468Y483983D01*
X1423499Y483994D01*
G02X1423567Y484006I68J-188D01*
G01X1423644D01*
G03X1423727Y484024I0J200D01*
G01X1423782Y484049D01*
G02X1423883Y484066I82J-182D01*
G02X1423921Y484059I-17J-199D01*
G01X1423958Y484026D01*
X1423961Y484024D01*
X1423962Y484023D01*
G03X1423967Y484018I144J139D01*
G03X1424999Y483615I1032J1120D01*
G01X1425000D01*
G03X1425985Y483977I-1J1523D01*
G01X1426015Y484001D01*
G02X1426058Y484006I44J-195D01*
G01X1426144D01*
G03X1426227Y484024I0J200D01*
G01X1426290Y484053D01*
G02X1426383Y484066I73J-186D01*
G01X1426420Y484061D01*
X1426427Y484060D01*
X1426479Y484035D01*
X1426501Y484014D01*
X1426510Y484007D01*
X1426515Y484002D01*
G03X1426721Y483852I984J1136D01*
G03X1426726Y483849I776J1287D01*
G01X1426761Y483828D01*
X1426785Y483795D01*
G02X1426817Y483726I-162J-117D01*
G01X1426831Y483665D01*
Y483663D01*
X1426889Y483397D01*
X1426880Y483355D01*
X1426872Y483316D01*
X1426838Y483265D01*
G03X1426581Y482426I1245J-840D01*
G01Y482424D01*
G03X1426582Y482399I1501J48D01*
G01Y482392D01*
G03X1428084Y480923I1502J33D01*
G03X1429586Y482425I0J1502D01*
G03X1428862Y483712I-1506J0D01*
G01X1428856Y483716D01*
X1428855Y483717D01*
X1428850Y483720D01*
X1428816Y483743D01*
X1428795Y483772D01*
G02X1428768Y483828I164J114D01*
G01X1428754Y483890D01*
Y483892D01*
X1428703Y484127D01*
Y484128D01*
X1428697Y484151D01*
X1428701Y484189D01*
G02X1428722Y484259I199J-21D01*
G01X1428730Y484275D01*
X1428737Y484285D01*
X1428745Y484296D01*
G03X1428803Y484389I-1246J842D01*
G01X1428804Y484391D01*
X1428832Y484444D01*
X1428848Y484476D01*
G03X1428971Y484833I-1349J665D01*
G03X1429002Y485137I-1472J304D01*
G01Y485139D01*
G03X1427499Y486641I-1503J-1D01*
G03X1426566Y486316I0J-1502D01*
G01X1426547Y486301D01*
X1426526Y486291D01*
X1426501Y486279D01*
X1426461Y486270D01*
X1426354D01*
G03X1426271Y486252I0J-200D01*
G01X1426231Y486233D01*
G02X1426131Y486216I-82J182D01*
G02X1426075Y486230I20J199D01*
G01X1426050Y486240D01*
G03X1424999Y486661I-1051J-1101D01*
G01X1424998D01*
G03X1424013Y486299I1J-1523D01*
G01X1423983Y486275D01*
X1423961Y486270D01*
X1423854D01*
G03X1423771Y486252I0J-200D01*
G01X1423727Y486230D01*
G02X1423506Y486261I-87J180D01*
G01X1423505D01*
G03X1422500Y486645I-1005J-1123D01*
G01X1422498D01*
G03X1421399Y486169I0J-1508D01*
G01X1421386Y486155D01*
X1421321Y486108D01*
X1421296Y486096D01*
X1421264Y486081D01*
G02X1421181Y486062I-85J181D01*
G01X1420934Y486060D01*
X1420916Y486061D01*
X1420863Y486067D01*
X1420832Y486082D01*
G02X1420775Y486126I92J178D01*
G01X1420773Y486128D01*
X1420770Y486132D01*
G03X1419956Y486600I-1119J-1004D01*
G03X1419848Y486618I-301J-1473D01*
G01X1419842Y486619D01*
G03X1419826Y486621I-194J-1490D01*
G01X1419818Y486622D01*
G03X1419797Y486625I-223J-1487D01*
G01X1419791D01*
X1419783Y486626D01*
G03X1419754Y486628I-118J-1499D01*
G01X1419714Y486631D01*
X1419683Y486645D01*
G02X1419630Y486682I86J180D01*
G01X1419579Y486736D01*
G02X1419577Y486738I140J142D01*
G01X1419437Y486889D01*
X1419436Y486890D01*
X1419409Y486919D01*
X1419396Y486953D01*
G02X1419393Y486960I182J82D01*
G02X1419388Y486978I190J63D01*
G02X1419383Y487022I195J44D01*
G01Y505081D01*
G03X1419324Y505223I-200J0D01*
G01X1400171Y524376D01*
G02X1400127Y524443I142J141D01*
G01X1400113Y524477D01*
Y529120D01*
X1400120Y529158D01*
X1400322Y529360D01*
G03X1400326Y529364I-922J926D01*
G03X1400510Y529596I-925J923D01*
G01X1400522Y529616D01*
X1400587Y529681D01*
G03X1400958Y530577I-896J896D01*
G01Y532312D01*
G02X1400965Y532364I200J0D01*
G02X1400969Y532377I193J-52D01*
G02X1401014Y532449I188J-68D01*
G01X1401180Y532609D01*
X1401233Y532660D01*
G02X1401353Y532710I133J-150D01*
G01X1401406Y532709D01*
X1401442D01*
G03X1402940Y534211I-4J1502D01*
G03X1401438Y535713I-1502J0D01*
G01X1401401D01*
G03X1401340Y535710I43J-1501D01*
G01X1401338D01*
G03X1401287Y535705I121J-1497D01*
G01X1401244Y535701D01*
X1401199Y535716D01*
G02X1401128Y535757I62J190D01*
G01X1400906Y535956D01*
G02X1400840Y536104I134J148D01*
G01Y536822D01*
G02X1400843Y536852I200J-5D01*
G01X1401986Y537995D01*
G03X1402368Y538917I-924J923D01*
G01Y568515D01*
G03X1401986Y569437I-1306J-1D01*
G01X1400115Y571308D01*
G02X1400113Y571334I198J28D01*
G01Y609372D01*
G02X1400116Y609404I200J-3D01*
G01Y609406D01*
G02X1400170Y609512I197J-34D01*
G01X1400188Y609530D01*
G02X1400191Y609533I143J-140D01*
G01X1400194Y609536D01*
G02X1400206Y609546I134J-149D01*
G01X1400208Y609548D01*
G02X1400217Y609554I115J-163D01*
G01X1400219Y609555D01*
X1400223Y609558D01*
X1400253Y609577D01*
X1400255Y609579D01*
X1400467Y609706D01*
G02X1400570Y609735I104J-171D01*
G01X1400671D01*
X1400709Y609727D01*
X1400728Y609718D01*
X1400734Y609715D01*
G03X1401380Y609569I646J1356D01*
G01X1401414D01*
G03X1402885Y611071I-31J1502D01*
G03X1401396Y612573I-1502J0D01*
G01X1401366D01*
G03X1400738Y612428I16J-1502D01*
G03X1400736Y612427I671J-1344D01*
G01X1400717Y612418D01*
X1400697Y612408D01*
X1400687Y612404D01*
X1400669Y612397D01*
G02X1400490Y612419I-68J188D01*
G01X1400255Y612563D01*
X1400253Y612565D01*
X1400223Y612584D01*
X1400219Y612586D01*
X1400217Y612588D01*
G02X1400208Y612594I106J169D01*
G01X1400206Y612596D01*
G02X1400188Y612612I124J157D01*
G01X1400178Y612622D01*
X1400174Y612627D01*
G03X1400166Y612636I-153J-128D01*
G01X1400154Y612649D01*
G02X1400113Y612770I159J121D01*
G01Y617515D01*
G02X1400115Y617543I200J0D01*
G01X1404388Y621816D01*
G03X1404770Y622738I-924J923D01*
G01Y629378D01*
G02X1404787Y629398I161J-119D01*
G01X1407569Y632180D01*
G02X1407646Y632228I142J-141D01*
G01X1407689Y632243D01*
X1407709Y632240D01*
X1407728Y632237D01*
G03X1407950Y632221I219J1487D01*
G01X1407952D01*
G03X1409455Y633724I0J1503D01*
G01Y633726D01*
G03X1409439Y633948I-1503J3D01*
G01X1409436Y633967D01*
X1409433Y633987D01*
X1409448Y634030D01*
G02X1409496Y634107I189J-65D01*
G01X1410618Y635229D01*
G02X1410620Y635231I142J-140D01*
G02X1410640Y635248I139J-144D01*
G01X1412049D01*
G02X1412120Y635166I-110J-167D01*
G01X1412170Y635061D01*
Y635059D01*
X1412229Y634938D01*
G02X1412249Y634851I-180J-87D01*
G01Y634712D01*
G02X1412228Y634623I-200J0D01*
G01X1412218Y634603D01*
X1412209Y634590D01*
X1412208Y634589D01*
G03X1411930Y633724I1225J-871D01*
G01Y633714D01*
G03X1411937Y633570I1502J1D01*
G01X1411938Y633560D01*
X1411940Y633538D01*
G03X1413432Y632214I1492J179D01*
G03X1414924Y633540I0J1502D01*
G01X1414930Y633594D01*
G03X1414935Y633716I-1498J122D01*
G03X1413602Y635209I-1503J0D01*
G01X1413564Y635213D01*
X1413427Y635284D01*
X1413401Y635311D01*
G02X1413345Y635417I141J142D01*
G01X1413417Y635556D01*
X1413444Y635580D01*
G03X1413496Y635629I-870J975D01*
G01X1414288Y636421D01*
G02X1414316Y636423I28J-198D01*
G01X1414343D01*
X1414379Y636438D01*
G03X1414444Y636481I-76J185D01*
G01X1418822Y640859D01*
G02X1418824Y640861I142J-140D01*
G02X1418844Y640878I139J-144D01*
G01X1435209D01*
X1435224Y640870D01*
G03X1435952Y640682I728J1316D01*
G03X1437444Y642008I0J1502D01*
G01X1437450Y642064D01*
G03X1437455Y642186I-1498J122D01*
G01Y642187D01*
G03X1437288Y642873I-1503J-3D01*
G03X1437126Y643123I-1336J-688D01*
G01X1437103Y643152D01*
X1437092Y643186D01*
X1437090Y643192D01*
G02X1437082Y643241I192J57D01*
G01X1437085Y643328D01*
X1437087Y643374D01*
G02X1437145Y643506I200J-9D01*
G01X1440064Y646425D01*
G03X1440123Y646567I-141J142D01*
G01Y647983D01*
G02X1440126Y648015I200J-3D01*
G01Y648017D01*
G02X1440180Y648123I197J-34D01*
G01X1448320Y656262D01*
X1456747Y664689D01*
G02X1456853Y664743I140J-143D01*
G01X1456855D01*
G02X1456887Y664746I35J-197D01*
G01X1468604D01*
G03X1469500Y665117I0J1267D01*
G01X1469526Y665144D01*
X1469528Y665146D01*
G02X1469578Y665182I140J-142D01*
G02X1469669Y665204I91J-178D01*
G01X1477719D01*
G02X1478116Y664761I-1J-400D01*
G01X1478115Y664750D01*
X1465552Y598412D01*
X1460655Y572557D01*
G03X1460619Y572331I3824J-725D01*
G01X1460292Y569798D01*
X1454454Y525412D01*
X1451061Y499621D01*
G02X1450913Y499463I-197J36D01*
G01X1450838Y499444D01*
X1450740Y499419D01*
X1450710Y499422D01*
X1450707D01*
X1450659Y499426D01*
X1450638Y499437D01*
X1450627Y499443D01*
X1450626D01*
X1450565Y499475D01*
G02X1450520Y499508I94J176D01*
G01X1450507Y499521D01*
X1450505Y499524D01*
X1450498Y499533D01*
G03X1449293Y500135I-1205J-905D01*
G03X1447801Y498809I0J-1502D01*
G01X1447794Y498749D01*
G03X1447790Y498633I1499J-110D01*
G03X1448115Y497698I1506J-1D01*
G01X1448124Y497688D01*
X1448132Y497677D01*
X1448145Y497647D01*
X1448149Y497637D01*
G02X1448161Y497570I-188J-68D01*
G01Y497488D01*
G03X1448179Y497405I200J0D01*
G01X1448198Y497365D01*
G02X1448211Y497324I-183J-81D01*
G01Y497242D01*
G02X1448202Y497211I-196J40D01*
G01X1448172Y497133D01*
X1448149Y497107D01*
G03X1447971Y496849I1141J-978D01*
G01X1447953Y496814D01*
G03X1447948Y496804I1342J-677D01*
G01X1447941Y496790D01*
G03X1447790Y496133I1353J-657D01*
G03X1448115Y495198I1506J-1D01*
G01X1448124Y495188D01*
X1448132Y495177D01*
X1448145Y495147D01*
X1448149Y495137D01*
G02X1448161Y495070I-188J-68D01*
G01Y494988D01*
G03X1448179Y494905I200J0D01*
G01X1448198Y494865D01*
G02X1448211Y494824I-183J-81D01*
G01Y494742D01*
G02X1448202Y494711I-196J40D01*
G01X1448172Y494633D01*
X1448149Y494607D01*
G03X1447971Y494349I1141J-978D01*
G01X1447953Y494314D01*
G03X1447948Y494304I1342J-677D01*
G01X1447941Y494290D01*
G03X1447790Y493633I1353J-657D01*
G03X1448115Y492698I1506J-1D01*
G01X1448124Y492688D01*
X1448132Y492677D01*
X1448145Y492647D01*
X1448149Y492637D01*
G02X1448161Y492570I-188J-68D01*
G01Y492488D01*
G03X1448179Y492405I200J0D01*
G01X1448204Y492350D01*
G02X1448171Y492133I-181J-83D01*
G01X1448135Y492092D01*
G03X1447791Y491135I1160J-957D01*
G01Y491133D01*
G03X1449293Y489631I1502J0D01*
G03X1449442Y489638I4J1502D01*
G01X1449470Y489641D01*
X1449516Y489632D01*
G02X1449617Y489580I-37J-196D01*
G01X1449659Y489536D01*
G02X1449715Y489384I-143J-139D01*
G01X1449211Y485539D01*
G02X1449155Y485425I-198J27D01*
G01X1449133Y485403D01*
X1449077Y485373D01*
X1449045Y485368D01*
G03X1447791Y483886I249J-1482D01*
G03X1448234Y482821I1502J0D01*
G01X1448248Y482807D01*
X1448284Y482753D01*
X1448285Y482752D01*
X1448293Y482739D01*
G02X1448302Y482723I-170J-106D01*
G01X1448319Y482682D01*
X1448330Y482654D01*
G02X1448338Y482624I-189J-66D01*
G02X1448341Y482590I-197J-35D01*
G01Y482383D01*
G02X1448327Y482311I-200J1D01*
G01X1448300Y482247D01*
X1448290Y482226D01*
X1448248Y482165D01*
X1448235Y482153D01*
G03X1447801Y481264I1058J-1067D01*
G01X1447794Y481202D01*
G03X1447790Y481086I1499J-110D01*
G03X1448115Y480151I1506J-1D01*
G01X1448124Y480141D01*
X1448132Y480130D01*
X1448145Y480100D01*
X1448149Y480090D01*
G02X1448161Y480023I-188J-68D01*
G01Y479941D01*
G03X1448179Y479858I200J0D01*
G01X1448198Y479818D01*
G02X1448211Y479777I-183J-81D01*
G01Y479695D01*
G02X1448202Y479664I-196J40D01*
G01X1448172Y479586D01*
X1448149Y479560D01*
G03X1447971Y479302I1141J-978D01*
G01X1447953Y479267D01*
G03X1447948Y479257I1342J-677D01*
G01X1447941Y479243D01*
G03X1447790Y478586I1353J-657D01*
G03X1448112Y477656I1504J0D01*
G01X1448133Y477629D01*
X1448145Y477600D01*
X1448149Y477590D01*
G02X1448159Y477550I-188J-68D01*
G01X1448138Y477391D01*
X1448090Y477028D01*
G02X1448078Y476982I-198J27D01*
G01X1448070Y476960D01*
X1448056Y476940D01*
G03X1447971Y476802I1235J-856D01*
G01X1447953Y476767D01*
G03X1447791Y476088I1342J-679D01*
G01Y476086D01*
G03X1447878Y475582I1503J0D01*
G01X1447886Y475559D01*
X1447891Y475514D01*
X1447707Y474117D01*
X1447585Y473186D01*
G02X1447578Y473154I-198J27D01*
G01X1444497Y462991D01*
G02X1444418Y462884I-191J58D01*
G02X1444362Y462857I-114J164D01*
G01X1444204Y462810D01*
G02X1444147Y462802I-56J192D01*
G01X1443894D01*
X1443831Y462823D01*
X1443814Y462837D01*
G03X1443223Y463117I-923J-1185D01*
G03X1442920Y463154I-333J-1465D01*
G01X1442884D01*
G03X1442867I-9J-1502D01*
G01X1442850D01*
G03X1442819Y463153I33J-1502D01*
G01X1442796D01*
G03X1442588Y463124I103J-1499D01*
G03X1442364Y463059I305J-1471D01*
G03X1441954Y462827I525J-1407D01*
G01X1441927Y462806D01*
X1441897Y462796D01*
G02X1441831Y462784I-68J188D01*
G01X1441745D01*
G03X1441662Y462766I0J-200D01*
G01X1441607Y462741D01*
G02X1441390Y462774I-83J181D01*
G01X1441349Y462810D01*
G03X1440392Y463154I-957J-1160D01*
G01X1440390D01*
G03X1438898Y461828I0J-1502D01*
G01X1438891Y461768D01*
G03X1438887Y461652I1499J-110D01*
G03X1439212Y460717I1506J-1D01*
G01X1439220Y460707D01*
X1439229Y460696D01*
X1439242Y460666D01*
X1439246Y460656D01*
G02X1439258Y460589I-188J-68D01*
G01Y460507D01*
G03X1439276Y460424I200J0D01*
G01X1439295Y460384D01*
G02X1439308Y460343I-183J-81D01*
G01Y460261D01*
G02X1439299Y460230I-196J40D01*
G01X1439269Y460152D01*
X1439246Y460126D01*
G03X1439068Y459868I1141J-978D01*
G01X1439050Y459833D01*
G03X1439045Y459823I1342J-677D01*
G01X1439038Y459809D01*
G03X1438887Y459152I1353J-657D01*
G03X1439212Y458217I1506J-1D01*
G01X1439220Y458207D01*
X1439229Y458196D01*
X1439242Y458166D01*
X1439246Y458156D01*
G02X1439258Y458089I-188J-68D01*
G01Y458007D01*
G03X1439276Y457924I200J0D01*
G01X1439301Y457869D01*
G02X1439268Y457652I-181J-83D01*
G01X1439232Y457611D01*
G03X1438888Y456654I1160J-957D01*
G01Y456652D01*
G03X1440390Y455150I1502J0D01*
G03X1441322Y455474I0J1502D01*
G01X1441341Y455489D01*
X1441365Y455501D01*
G02X1441411Y455516I85J-181D01*
G02X1441450Y455520I40J-196D01*
G01X1441535D01*
G03X1441618Y455538I0J200D01*
G01X1441655Y455556D01*
G02X1441729Y455576I88J-180D01*
G01X1441768Y455578D01*
X1441806Y455565D01*
X1441875Y455542D01*
X1441905Y455516D01*
G03X1442075Y455389I982J1137D01*
G02X1442078Y455387I-110J-168D01*
G01X1442091Y455378D01*
X1442105Y455369D01*
X1442127Y455307D01*
G02X1442130Y455182I-188J-67D01*
G01X1435093Y431965D01*
G02X1435045Y431884I-191J59D01*
G01X1434952Y431788D01*
X1434932Y431781D01*
G03X1433959Y430694I492J-1419D01*
G03X1433937Y430574I1465J-331D01*
G01X1433928Y430512D01*
Y430498D01*
X1433926Y430480D01*
G03X1434238Y429437I1498J-120D01*
G02X1434272Y429257I-158J-123D01*
G01X1427220Y405991D01*
X1427217Y405981D01*
G03X1427216Y405978I3723J-1243D01*
G03X1427212Y405966I3722J-1247D01*
G01X1419883Y381786D01*
X1410034Y349292D01*
G02X1409959Y349188I-191J59D01*
G01X1409936Y349171D01*
X1409876Y349152D01*
X1409835D01*
G03X1409830I-2J-1503D01*
G03X1408327Y347649I0J-1503D01*
G03X1409005Y346392I1504J0D01*
G01X1409006Y346391D01*
G02X1409084Y346293I-110J-167D01*
G01X1409095Y346262D01*
X1409097Y346199D01*
X1409067Y346101D01*
X1408383Y343848D01*
X1406673Y338207D01*
G03X1406504Y337072I3758J-1140D01*
G01Y337064D01*
G03X1406505Y337038I3923J138D01*
G01Y337035D01*
X1406826Y298093D01*
X1407252Y246471D01*
Y240221D01*
G02X1407243Y240215I-115J163D01*
G01X1407221Y240203D01*
X1407100Y240174D01*
G03X1406878Y237329I361J-1459D01*
G03X1406954Y237299I590J1382D01*
G01X1406978Y237291D01*
G03X1407013Y237280I468J1428D01*
G01X1407051Y237268D01*
X1407080Y237245D01*
G02X1407154Y237078I-126J-156D01*
G01X1407083Y235819D01*
X1407043Y235108D01*
Y235102D01*
X1406719Y231528D01*
G02X1406692Y231444I-199J18D01*
G01X1406681Y231426D01*
X1406650Y231394D01*
X1406630Y231381D01*
G03X1405943Y230117I819J-1264D01*
G03X1406436Y229003I1505J0D01*
G02X1406438Y229001I-140J-142D01*
G01X1406447Y228993D01*
X1406450Y228990D01*
X1406466Y228947D01*
G02X1406478Y228859I-187J-70D01*
G01X1406198Y225762D01*
G03X1406182Y225409I3911J-354D01*
G01Y225407D01*
G03X1406184Y225259I3927J-21D01*
G01Y225257D01*
X1406251Y220984D01*
Y220970D01*
X1405454Y206773D01*
X1405277Y203609D01*
G02X1405259Y203546I-199J23D01*
G01X1405243Y203513D01*
X1405212Y203485D01*
X1405211Y203484D01*
X1405190Y203465D01*
X1404917Y203329D01*
G02X1404828Y203308I-89J179D01*
G01X1404718D01*
G02X1404666Y203315I0J200D01*
G01X1404641Y203322D01*
X1404617Y203336D01*
G03X1403846Y203550I-773J-1288D01*
G01X1403845D01*
G03X1402602Y202891I0J-1502D01*
G01X1402591Y202875D01*
X1402552Y202836D01*
G02X1402520Y202810I-141J141D01*
G01X1402420Y202747D01*
X1402372Y202743D01*
X1402263Y202732D01*
X1402261D01*
X1402107Y202716D01*
G02X1402039Y202721I-20J199D01*
G01X1402031Y202723D01*
G02X1402026Y202725I72J186D01*
G01X1402019Y202727D01*
X1401994Y202736D01*
X1401954Y202762D01*
X1401938Y202779D01*
G03X1401818Y202893I-1093J-1030D01*
G03X1400947Y203247I-973J-1145D01*
G03X1400870Y203250I-97J-1499D01*
G01X1400843D01*
G03X1400838I-2J-1502D01*
G01X1400837D01*
G03X1400763Y203248I4J-1502D01*
G01X1400757D01*
G03X1400746Y203247I130J-1496D01*
G01X1400742D01*
G03X1399683Y202700I103J-1499D01*
G01X1399643Y202651D01*
X1399642Y202649D01*
X1399641D01*
X1399640Y202647D01*
X1399639Y202646D01*
G03X1399633Y202639I149J-134D01*
G01X1399631Y202636D01*
X1399628Y202632D01*
G03X1399627Y202630I178J-90D01*
G01X1399604Y202595D01*
G03X1399353Y201924I1241J-847D01*
G01X1399349Y201887D01*
G03X1399344Y201810I1496J-136D01*
G03X1399343Y201748I1501J-55D01*
G03Y201746I1502J-1D01*
G01Y201745D01*
G03X1399347Y201632I1502J-3D01*
G01X1399350Y201589D01*
X1399335Y201548D01*
G02X1399289Y201476I-188J69D01*
G01X1399280Y201467D01*
X1399276Y201392D01*
G03X1399319Y201258I200J-10D01*
G01X1399652Y200835D01*
X1399653Y200833D01*
X1399654Y200832D01*
G02X1399660Y200825I-149J-134D01*
G01X1399665Y200818D01*
X1399666Y200817D01*
G03X1399670Y200812I158J122D01*
G01X1399672Y200809D01*
X1399685Y200791D01*
X1399699Y200760D01*
G02X1399713Y200687I-186J-73D01*
G01Y200603D01*
G03X1399731Y200520I200J0D01*
G01X1399756Y200465D01*
G02X1399723Y200248I-181J-83D01*
G01X1399687Y200207D01*
G03X1399343Y199250I1160J-957D01*
G01Y199248D01*
G03X1400845Y197746I1502J0D01*
G03X1401991Y198277I0J1502D01*
G01X1401992Y198278D01*
X1401999Y198286D01*
X1402029Y198315D01*
G02X1402087Y198354I139J-144D01*
G01X1402157Y198385D01*
G02X1402180Y198393I77J-184D01*
G02X1402185Y198395I76J-184D01*
G02X1402237Y198402I52J-193D01*
G01X1402436D01*
G02X1402484Y198396I-1J-200D01*
G01X1402548Y198380D01*
X1402567Y198371D01*
X1402611Y198350D01*
X1402630Y198341D01*
X1402667Y198313D01*
X1402683Y198294D01*
X1402684Y198293D01*
X1402690Y198286D01*
X1402691Y198285D01*
G03X1403828Y197746I1153J963D01*
G01X1403843D01*
G03X1403847I2J1502D01*
G01X1403865D01*
G03X1404357Y197836I-20J1501D01*
G01X1404390Y197848D01*
X1404476D01*
G02X1404583Y197816I-1J-200D01*
G01X1404679Y197748D01*
X1404681D01*
X1404853Y197625D01*
G02X1404865Y197614I-129J-153D01*
G01X1404873Y197606D01*
G02X1404931Y197455I-142J-141D01*
G01X1404908Y197045D01*
X1404906Y197003D01*
X1404887Y196966D01*
G02X1404837Y196902I-179J88D01*
G01X1404768Y196844D01*
X1404766D01*
X1404617Y196721D01*
G02X1404550Y196684I-128J153D01*
G01X1404512Y196672D01*
X1404471Y196676D01*
G03X1404328Y196683I-145J-1500D01*
G01X1404327D01*
G03X1403385Y196353I0J-1509D01*
G01X1403384Y196352D01*
X1403357Y196331D01*
X1403326Y196320D01*
G02X1403258Y196308I-68J188D01*
G01X1403182D01*
G03X1403099Y196290I0J-200D01*
G01X1403059Y196271D01*
G02X1402959Y196254I-82J182D01*
G02X1402903Y196268I20J199D01*
G01X1402878Y196278D01*
G03X1401827Y196699I-1051J-1101D01*
G01X1401826D01*
G03X1400841Y196337I1J-1523D01*
G01X1400811Y196313D01*
X1400789Y196308D01*
X1400682D01*
G03X1400599Y196290I0J-200D01*
G01X1400559Y196271D01*
G02X1400459Y196254I-82J182D01*
G02X1400403Y196268I20J199D01*
G01X1400378Y196278D01*
G03X1399327Y196699I-1051J-1101D01*
G01X1399326D01*
G03X1398341Y196337I1J-1523D01*
G01X1398311Y196313D01*
X1398289Y196308D01*
X1398182D01*
G03X1398099Y196290I0J-200D01*
G01X1398044Y196265D01*
G02X1397827Y196298I-83J181D01*
G01X1397786Y196334D01*
G03X1396829Y196678I-957J-1160D01*
G01X1396827D01*
G03Y193674I0J-1502D01*
G01X1396828D01*
G03X1397759Y193997I0J1504D01*
G01X1397780Y194014D01*
X1397813Y194028D01*
X1397823Y194032D01*
G02X1397890Y194044I68J-188D01*
G01X1397972D01*
G03X1398055Y194062I0J200D01*
G01X1398110Y194087D01*
G02X1398211Y194104I82J-182D01*
G02X1398249Y194097I-17J-199D01*
G01X1398286Y194064D01*
X1398289Y194062D01*
X1398290Y194061D01*
G03X1398295Y194056I144J139D01*
G03X1399327Y193653I1032J1120D01*
G03X1400310Y194014I0J1519D01*
G01X1400330Y194030D01*
X1400339Y194037D01*
G02X1400389Y194044I52J-193D01*
G01X1400472D01*
G03X1400555Y194062I0J200D01*
G01X1400610Y194087D01*
G02X1400711Y194104I82J-182D01*
G02X1400749Y194097I-17J-199D01*
G01X1400786Y194064D01*
X1400789Y194062D01*
X1400790Y194061D01*
G03X1400795Y194056I144J139D01*
G03X1401827Y193653I1032J1120D01*
G03X1402810Y194014I0J1519D01*
G01X1402830Y194030D01*
X1402839Y194037D01*
G02X1402889Y194044I52J-193D01*
G01X1402972D01*
G03X1403055Y194062I0J200D01*
G01X1403098Y194084D01*
G02X1403153Y194102I89J-179D01*
G02X1403207Y194104I34J-197D01*
G01X1403245Y194099D01*
X1403297Y194074D01*
X1403321Y194054D01*
G03X1404307Y193669I1006J1121D01*
G01X1404348Y193668D01*
X1404394Y193648D01*
G02X1404443Y193614I-88J-179D01*
G01X1404528Y193525D01*
X1404530Y193523D01*
X1404643Y193400D01*
G02X1404644Y193398I-171J-87D01*
G01X1404645D01*
X1404646Y193397D01*
X1404650Y193392D01*
G02X1404696Y193253I-154J-128D01*
G01X1404155Y183620D01*
X1403639Y174432D01*
G02X1403638Y174416I-200J4D01*
G01X1401550Y158959D01*
G03X1401515Y158493I3891J-527D01*
G01X1401491Y156950D01*
X1401483Y156399D01*
G02X1401462Y156324I-199J15D01*
G01Y156323D01*
G03X1401055Y154641I3519J-1742D01*
G01X1401050Y154317D01*
X1401025Y152691D01*
Y152690D01*
G03X1401024Y152632I3925J-97D01*
G01Y152630D01*
G03X1401228Y151382I3928J1D01*
G02X1401230Y151262I-190J-63D01*
G02X1401226Y151249I-193J52D01*
G03X1400981Y149942I3681J-1366D01*
G01X1400971Y149321D01*
X1400967Y149032D01*
X1400951Y147991D01*
Y147990D01*
G03X1400950Y147932I3925J-97D01*
G01Y147930D01*
G03X1401036Y147115I3927J2D01*
G03X1401058Y147018I3840J820D01*
G01X1401066Y146986D01*
X1401037Y146694D01*
X1401016Y146657D01*
G03X1400598Y145562I3385J-1919D01*
G01X1400589Y145520D01*
X1400585Y145500D01*
X1400582Y145483D01*
G02X1400519Y145384I-193J53D01*
G01X1400518Y145383D01*
X1400509Y145375D01*
X1400416Y145300D01*
G02X1400373Y145276I-118J161D01*
G01X1400343Y145265D01*
X1400313Y145263D01*
X1400309D01*
G03X1398887Y143938I70J-1501D01*
G01X1398881Y143884D01*
G03X1398876Y143762I1498J-122D01*
G03X1400010Y142305I1503J0D01*
G01X1400051Y142295D01*
X1400090Y142265D01*
X1400111Y142247D01*
X1400133Y142218D01*
X1400226Y142049D01*
Y142047D01*
X1400268Y141971D01*
G02X1400293Y141874I-175J-97D01*
G01Y141823D01*
X1400285Y141769D01*
X1400280Y141753D01*
G03X1400230Y141580I3713J-1167D01*
G03X1400210Y141502I3759J-1006D01*
G01X1400204Y141478D01*
G03X1400118Y140963I3787J-897D01*
G01X1400113Y140912D01*
X1400098Y140758D01*
X1400020Y139975D01*
G02X1399985Y139890I-197J32D01*
G02X1399965Y139866I-163J116D01*
G01X1399960Y139861D01*
G02X1399926Y139833I-144J140D01*
G01X1399827Y139838D01*
X1399817D01*
G03X1399768Y139840I-185J-3922D01*
G03X1399668Y139842I-129J-3925D01*
G01X1399619D01*
G03X1397544Y139230I30J-3927D01*
G03X1397527Y139233I-270J-1478D01*
G01X1397519Y139235D01*
G03X1397261Y139259I-268J-1478D01*
G01X1397248D01*
G03X1395746Y137772I0J-1502D01*
G01Y137756D01*
G03X1395882Y137132I1502J1D01*
G01X1395891Y137112D01*
X1395898Y137080D01*
G03X1395823Y136803I3750J-1164D01*
G03X1395791Y136652I3824J-889D01*
G03X1395722Y135915I3857J-733D01*
G03X1396074Y134289I3928J-1D01*
G02Y134141I-186J-74D01*
G03X1395722Y132515I3576J-1625D01*
G01Y132511D01*
G03X1395898Y131351I3926J2D01*
G01X1395894Y131333D01*
X1395880Y131292D01*
G03X1395865Y131258I1367J-623D01*
G01Y131257D01*
X1395857Y131236D01*
G03X1395814Y131119I1387J-576D01*
G01Y131118D01*
G03X1395810Y131107I1409J-519D01*
G03X1395808Y131099I193J-52D01*
G01X1395807Y131096D01*
Y131095D01*
G03X1395753Y130819I1441J-425D01*
G03X1395746Y130700I1495J-148D01*
G01Y130663D01*
G03X1397248Y129168I1502J7D01*
G01X1397266D01*
G03X1397518Y129192I-16J1502D01*
G01X1397547Y129197D01*
G03X1399615Y128588I2101J3318D01*
G01X1399663D01*
G03X1401749Y129198I-16J3927D01*
G01X1401774Y129193D01*
G03X1401785Y129191I274J1477D01*
G01X1401787D01*
G03X1401810Y129187I269J1478D01*
G03X1401818Y129185I52J192D01*
G03X1401834Y129183I194J1490D01*
G01X1401838D01*
G03X1402061Y129167I219J1486D01*
G01X1402068D01*
G03X1402214Y129176I-19J1504D01*
G03X1402507Y129238I-163J1493D01*
G01X1402509D01*
X1402511Y129239D01*
G03X1402520Y129242I-471J1428D01*
G01X1402539Y129248D01*
X1402578Y129253D01*
G02X1402704Y129221I16J-199D01*
G01X1402859Y129110D01*
X1402861D01*
X1402976Y129026D01*
Y129025D01*
G02X1403024Y128974I-119J-160D01*
G01X1403022Y128902D01*
Y128828D01*
G03X1403374Y127202I3928J-1D01*
G02Y127054I-186J-74D01*
G03X1403022Y125428I3576J-1625D01*
G01Y125359D01*
Y125353D01*
X1403024Y125279D01*
G02X1402981Y125232I-167J110D01*
G01X1402965Y125220D01*
X1402956Y125213D01*
X1402951Y125210D01*
X1402887Y125164D01*
X1402857Y125142D01*
X1402715Y125039D01*
G02X1402624Y125008I-108J168D01*
G01X1402622D01*
G02X1402606Y125007I-20J199D01*
G01X1402530D01*
X1402500Y125016D01*
G03X1402076Y125086I-454J-1432D01*
G01X1402059D01*
X1402042Y125087D01*
X1402020D01*
X1401970Y125084D01*
X1401968D01*
G03X1401861Y125076I58J-1502D01*
G03X1401835Y125073I159J-1495D01*
G01X1401809Y125070D01*
G02X1401791Y125069I-20J199D01*
G01X1401688Y125098D01*
X1401665Y125112D01*
G03X1400833Y125486I-2015J-3370D01*
G03X1399659Y125668I-1182J-3745D01*
G01X1399632D01*
X1399631Y125669D01*
G03X1397636Y125114I18J-3927D01*
G01X1397622Y125105D01*
G02X1397536Y125086I-85J181D01*
G01X1397248D01*
G03X1395746Y123593I0J-1502D01*
G01Y123582D01*
G03X1395891Y122937I1503J-1D01*
G01X1395898Y122908D01*
G03X1395722Y121759I3751J-1162D01*
G01Y121742D01*
G03X1396074Y120116I3928J-1D01*
G02Y119968I-186J-74D01*
G03X1395722Y118342I3576J-1625D01*
G01Y118340D01*
G03X1395899Y117176I3926J2D01*
G01X1395892Y117146D01*
X1395883Y117127D01*
G03X1395746Y116500I1365J-627D01*
G01Y116497D01*
G03X1397248Y114995I1502J0D01*
G01X1397252D01*
G03X1397516Y115018I2J1502D01*
G01X1397548Y115024D01*
G03X1399648Y114415I2100J3318D01*
G01X1399649D01*
G03X1401749Y115024I-1J3927D01*
G01X1401753Y115023D01*
X1401773Y115019D01*
X1401780Y115018D01*
G03X1402048Y114995I262J1479D01*
G01X1402051D01*
G03X1402492Y115062I-3J1502D01*
G01X1402521Y115071D01*
X1402612D01*
G02X1402699Y115050I-2J-200D01*
G01X1402704Y115048D01*
G03X1402709Y115045I105J170D01*
G01X1402714Y115042D01*
X1402723Y115037D01*
X1402807Y114975D01*
X1402810Y114973D01*
X1402901Y114907D01*
X1402969Y114858D01*
X1402977Y114852D01*
G02X1402981Y114849I-118J-162D01*
G02X1403024Y114801I-125J-156D01*
G01X1403022Y114714D01*
Y114655D01*
G03X1403374Y113029I3928J-1D01*
G02Y112881I-186J-74D01*
G03X1403022Y111255I3576J-1625D01*
G03X1403091Y110517I3926J-5D01*
G03X1403158Y110228I3856J742D01*
G03X1403198Y110090I3790J1024D01*
G01Y110089D01*
X1403191Y110056D01*
G03X1403182Y110036I1365J-626D01*
G01X1403181Y110034D01*
G03X1403046Y109430I1367J-623D01*
G01Y109409D01*
G03X1404548Y107908I1502J1D01*
G03X1404810Y107931I0J1502D01*
G01X1404848Y107937D01*
G03X1405052Y107816I2104J3315D01*
G01X1405054D01*
X1405103Y107788D01*
X1405118Y107751D01*
X1405196Y107462D01*
X1405195Y107408D01*
X1405188Y107382D01*
X1405171Y107321D01*
X1405159Y107300D01*
G03X1404965Y106562I1308J-738D01*
G01Y106526D01*
X1404966Y106510D01*
Y106507D01*
G03X1404975Y106388I1501J54D01*
G03X1405142Y105854I1492J173D01*
G03X1405540Y105379I1325J706D01*
G01X1405548Y105373D01*
X1405576Y105346D01*
X1405627Y105284D01*
X1405637Y105263D01*
X1405647Y105217D01*
X1405631Y104911D01*
X1405629Y104862D01*
X1405557Y104738D01*
X1405539Y104720D01*
X1405495Y104675D01*
X1405470Y104658D01*
G03X1404806Y103411I839J-1247D01*
G03X1407810I1502J0D01*
G03X1407222Y104603I-1502J0D01*
G01X1407211Y104611D01*
X1407185Y104637D01*
X1407167Y104660D01*
G02X1407131Y104771I164J114D01*
G01X1407146Y105105D01*
X1407165Y105142D01*
X1407169Y105151D01*
X1407204Y105210D01*
X1407218Y105233D01*
X1407280Y105297D01*
X1407305Y105314D01*
G03X1407969Y106557I-838J1247D01*
G01Y106583D01*
G03X1407894Y107034I-1502J-18D01*
G01X1407887Y107054D01*
X1407882Y107103D01*
G02X1407888Y107162I199J10D01*
G02X1407896Y107186I193J-51D01*
G01X1408035Y107465D01*
G03X1408039Y107471I-164J114D01*
G02X1408050Y107485I163J-116D01*
G01X1408125Y107509D01*
G03X1408968Y107888I-1177J3746D01*
G02X1409068Y107917I104J-171D01*
G02X1409094Y107916I5J-200D01*
G03X1409247Y107907I165J1494D01*
G01X1409249D01*
G03X1409324Y107909I-3J1503D01*
G01X1409362Y107912D01*
G03X1410451Y108510I-114J1498D01*
G01X1410459Y108520D01*
G03X1412634Y109624I-602J3880D01*
G01X1416221Y113211D01*
G03X1416710Y113805I-2772J2781D01*
G01X1416828Y113982D01*
G02X1416851Y114010I165J-112D01*
G01X1417848Y115007D01*
G02X1417909Y115049I142J-141D01*
G01X1417928Y115056D01*
X1417933Y115058D01*
X1417935D01*
G03X1417942Y115060I-409J1445D01*
G01X1417944Y115061D01*
X1417959Y115066D01*
G03X1417962Y115067I-473J1425D01*
G01X1417963D01*
G03X1418001Y115080I-467J1427D01*
G03X1418079Y115110I-500J1416D01*
G01X1418089Y115114D01*
X1418103Y115120D01*
X1418109Y115123D01*
X1418148Y115140D01*
X1418173Y115153D01*
X1418175Y115154D01*
G03X1418236Y115186I-667J1346D01*
G01X1418258Y115199D01*
G03X1418321Y115238I-759J1296D01*
G03X1418360Y115264I-814J1263D01*
G03X1418377Y115276I-858J1233D01*
G03X1418933Y116043I-876J1220D01*
G03X1419001Y116433I-1433J451D01*
G01Y116441D01*
G02X1419032Y116541I200J-7D01*
G01X1420584Y118865D01*
X1420596Y118883D01*
X1420994Y119281D01*
X1424992Y123280D01*
G03X1425834Y124532I-2776J2776D01*
G01X1427033Y127376D01*
X1427784Y129158D01*
G02X1427829Y129224I184J-77D01*
G01X1427858Y129252D01*
X1427884Y129262D01*
G03X1428857Y130561I-526J1408D01*
G01X1428861Y130625D01*
Y130671D01*
G03X1428738Y131266I-1503J-1D01*
G01X1428722Y131304D01*
Y131341D01*
G02X1428737Y131421I200J4D01*
G01X1435238Y146854D01*
G03X1435546Y148378I-3618J1524D01*
G01Y148443D01*
Y148447D01*
X1435469Y153087D01*
X1435449Y154275D01*
G03X1435366Y155015I-3926J-66D01*
G01X1435262Y155514D01*
X1434229Y160447D01*
G02X1434267Y160611I196J41D01*
G02X1434281Y160627I157J-124D01*
G01X1434540Y160869D01*
G02X1434627Y160917I137J-146D01*
G01X1434649Y160922D01*
X1434701D01*
X1434728Y160914D01*
G03X1435135Y160858I408J1456D01*
G01X1435138D01*
G03X1436160Y161256I0J1511D01*
G01X1436164Y161260D01*
X1436173Y161267D01*
X1436210Y161287D01*
X1436266Y161317D01*
X1436305Y161326D01*
X1436538D01*
G02X1436611Y161312I-1J-200D01*
G01X1436663Y161292D01*
X1436677Y161287D01*
G02X1436723Y161260I-78J-185D01*
G01X1436728Y161255D01*
X1436735Y161249D01*
G03X1437735Y160865I1003J1119D01*
G01X1437774Y160866D01*
G03X1438639Y161167I-38J1502D01*
G03X1439240Y162368I-900J1201D01*
G03X1438873Y163352I-1503J0D01*
G03X1437914Y163860I-1135J-984D01*
G01X1437833Y163870D01*
G03X1437809Y163871I-20J-199D01*
G01X1437737D01*
G03X1436735Y163487I1J-1503D01*
G01X1436728Y163481D01*
X1436723Y163476D01*
G02X1436677Y163449I-124J158D01*
G01X1436663Y163444D01*
X1436611Y163424D01*
G02X1436538Y163410I-74J186D01*
G01X1436328D01*
G02X1436281Y163416I2J200D01*
G01X1436257Y163422D01*
G02X1436209Y163442I52J193D01*
G01X1436190Y163453D01*
X1436173Y163468D01*
X1436170Y163471D01*
G03X1435138Y163878I-1032J-1105D01*
G03X1434180Y163536I0J-1513D01*
G01X1434174Y163531D01*
G02X1433999Y163498I-121J159D01*
G01X1433665Y163615D01*
G02X1433629Y163631I63J190D01*
G02X1433535Y163763I102J172D01*
G01X1432071Y170755D01*
X1432070Y170761D01*
X1428077Y196997D01*
X1428062Y197095D01*
X1428061Y197102D01*
X1428058Y197122D01*
X1427645Y199837D01*
X1427457Y201072D01*
X1427330Y201904D01*
Y201907D01*
X1427329Y201914D01*
X1426838Y205146D01*
G02X1426836Y205172I198J28D01*
G01X1426813Y206612D01*
G02X1426832Y206701I200J4D01*
G01X1426841Y206720D01*
X1426872Y206758D01*
X1426893Y206773D01*
G03X1427496Y207978I-903J1205D01*
G03X1427492Y208094I-1503J6D01*
G01X1427485Y208154D01*
Y208155D01*
G03X1427439Y208385I-1491J-179D01*
G03X1427172Y208909I-1446J-407D01*
G01X1427161Y208923D01*
X1427135Y208972D01*
X1427125Y209016D01*
Y209123D01*
G03X1427107Y209206I-200J0D01*
G01X1427082Y209261D01*
G02X1427115Y209478I181J83D01*
G01X1427151Y209519D01*
G03X1427495Y210455I-1160J957D01*
G01Y210479D01*
G03X1427209Y211360I-1502J-1D01*
G01X1427184Y211394D01*
X1427169Y211413D01*
G02X1427148Y211447I159J122D01*
G01X1427146Y211451D01*
G02X1427125Y211540I179J89D01*
G01Y211623D01*
G03X1427107Y211706I-200J0D01*
G01X1427082Y211761D01*
G02X1427115Y211978I181J83D01*
G01X1427151Y212019D01*
G03X1427495Y212955I-1160J957D01*
G01Y212979D01*
G03X1427209Y213860I-1502J-1D01*
G01X1427184Y213894D01*
X1427169Y213913D01*
G02X1427148Y213947I159J122D01*
G01X1427146Y213951D01*
G02X1427125Y214040I179J89D01*
G01Y214123D01*
G03X1427107Y214206I-200J0D01*
G01X1427082Y214261D01*
G02X1427115Y214478I181J83D01*
G01X1427151Y214519D01*
G03X1427495Y215453I-1160J957D01*
G01Y215477D01*
X1427496Y215478D01*
G03X1426751Y216776I-1503J0D01*
G01X1426736Y216785D01*
G02X1426651Y216935I115J164D01*
G01X1426569Y222209D01*
G02X1426598Y222315I200J2D01*
G01X1426626Y222362D01*
X1426637Y222368D01*
X1426671Y222385D01*
G03X1427496Y223719I-678J1341D01*
G01Y223739D01*
G03X1427490Y223859I-1503J-15D01*
G01X1427485Y223902D01*
Y223903D01*
G03X1427439Y224133I-1491J-179D01*
G03X1427172Y224657I-1446J-407D01*
G01X1427161Y224671D01*
X1427135Y224720D01*
X1427125Y224764D01*
Y224874D01*
G03X1427109Y224952I-200J0D01*
G01X1427082Y225014D01*
X1427081Y225017D01*
X1427071Y225039D01*
X1427067Y225069D01*
G02Y225119I198J25D01*
G01X1427072Y225155D01*
X1427096Y225205D01*
X1427117Y225229D01*
G03X1427123Y225236I-1137J981D01*
G01X1427128Y225242D01*
X1427134Y225248D01*
X1427143Y225259D01*
X1427168Y225290D01*
G03X1427185Y225312I-1180J929D01*
G03X1427200Y225332I-1194J911D01*
G03X1427495Y226226I-1207J894D01*
G01Y226227D01*
G03X1427180Y227147I-1502J0D01*
G01X1427178Y227149D01*
X1427151Y227190D01*
G02X1427125Y227287I174J99D01*
G01Y227374D01*
G03X1427109Y227452I-200J0D01*
G01X1427082Y227514D01*
X1427081Y227517D01*
X1427071Y227539D01*
X1427067Y227569D01*
G02Y227619I198J25D01*
G01X1427072Y227655D01*
X1427096Y227705D01*
X1427117Y227729D01*
G03X1427123Y227736I-1137J981D01*
G01X1427128Y227742D01*
X1427134Y227748D01*
X1427143Y227759D01*
X1427168Y227790D01*
G03X1427185Y227812I-1180J929D01*
G03X1427200Y227832I-1194J911D01*
G03X1427495Y228726I-1207J894D01*
G01Y228727D01*
G03X1427180Y229647I-1502J0D01*
G01X1427178Y229649D01*
X1427151Y229690D01*
G02X1427125Y229787I174J99D01*
G01Y229871D01*
G03X1427107Y229954I-200J0D01*
G01X1427082Y230002D01*
G02X1427063Y230084I181J85D01*
G01Y230098D01*
G02X1427065Y230121I200J-6D01*
G01X1427070Y230147D01*
X1427097Y230204D01*
X1427116Y230225D01*
G03X1427496Y231224I-1124J999D01*
G03Y231226I-1504J1D01*
G01X1427495Y231239D01*
Y231267D01*
X1427494Y231275D01*
Y231302D01*
X1427492Y231322D01*
Y231327D01*
G03X1427483Y231428I-1500J-83D01*
G01Y231431D01*
G03X1427406Y231736I-1487J-213D01*
G03X1427397Y231760I-1411J-515D01*
G01X1427379Y231809D01*
X1427363Y231842D01*
X1427362Y231845D01*
G03X1427249Y232051I-1370J-617D01*
G02X1427247Y232053I137J139D01*
G03X1427229Y232081I-1272J-798D01*
G01X1427215Y232102D01*
X1427178Y232216D01*
G02X1427179Y232236I200J0D01*
G01X1427468Y235173D01*
X1427557Y236070D01*
G03X1427576Y236455I-3908J386D01*
G01Y243508D01*
G03X1427575Y243537I-3923J-121D01*
G01Y243540D01*
X1427528Y249385D01*
Y257634D01*
G03X1427527Y257656I-3887J-166D01*
G01Y257735D01*
Y257737D01*
X1427526Y257805D01*
Y257807D01*
X1427525Y257868D01*
Y257870D01*
X1427524Y257960D01*
G02X1427528Y258004I200J4D01*
G02X1427676Y258157I196J-41D01*
G01X1427714Y258167D01*
G02X1427853Y258151I48J-194D01*
G01X1427883Y258134D01*
X1427923Y258112D01*
X1427939Y258103D01*
G02X1427965Y258083I-109J-168D01*
G01X1427979Y258070D01*
X1427994Y258047D01*
G03X1429247Y257378I1253J839D01*
G03X1430749Y258880I0J1502D01*
G03X1429423Y260372I-1502J0D01*
G01X1429369Y260378D01*
G03X1428205Y259963I-122J-1498D01*
G01X1428178Y259936D01*
X1428092Y259900D01*
G02X1427951Y259897I-74J185D01*
G01X1427748Y259979D01*
X1427746D01*
X1427613Y260032D01*
G02X1427502Y260163I82J182D01*
G02X1427498Y260184I194J48D01*
G01X1427479Y261570D01*
X1427469Y262370D01*
X1427462Y262957D01*
G02X1427584Y263143I200J2D01*
G01X1427689Y263183D01*
X1427691D01*
X1427942Y263275D01*
G02X1428140Y263240I69J-188D01*
G01X1428165Y263215D01*
X1428170Y263209D01*
G03X1429322Y262673I1152J970D01*
G03X1430263Y263003I0J1507D01*
G01X1430264Y263004D01*
X1430291Y263025D01*
X1430322Y263036D01*
G02X1430390Y263048I68J-188D01*
G01X1430467D01*
G03X1430550Y263066I0J200D01*
G01X1430605Y263091D01*
G02X1430822Y263058I83J-181D01*
G01X1430863Y263022D01*
G03X1431820Y262678I957J1160D01*
G01X1431822D01*
G03Y265682I0J1502D01*
G03X1430890Y265358I0J-1502D01*
G01X1430871Y265343D01*
X1430849Y265333D01*
X1430828Y265322D01*
X1430784Y265312D01*
X1430677D01*
G03X1430594Y265294I0J-200D01*
G01X1430550Y265272D01*
G02X1430329Y265303I-87J180D01*
G01X1430328D01*
G03X1429323Y265687I-1005J-1123D01*
G01X1429322D01*
G03X1428162Y265141I0J-1505D01*
G01X1428147Y265123D01*
X1428117Y265100D01*
X1428067Y265075D01*
G02X1427986Y265057I-83J182D01*
G01X1427931D01*
G02X1427871Y265067I2J200D01*
G01X1427765Y265102D01*
X1427763D01*
X1427561Y265172D01*
G02X1427434Y265323I70J187D01*
G01X1427432Y265335D01*
X1427374Y270002D01*
X1427338Y272871D01*
X1426842Y334070D01*
G02X1426843Y334086I200J-4D01*
G01X1426895Y334449D01*
X1427031Y335398D01*
X1427032Y335406D01*
G02X1427034Y335414I195J-44D01*
G01X1434040Y358529D01*
X1434784Y360981D01*
G02X1434841Y361071I191J-58D01*
G01X1434859Y361087D01*
X1434903Y361111D01*
X1434931Y361117D01*
G03X1436110Y362584I-323J1467D01*
G01Y362624D01*
G03X1435716Y363601I-1502J-38D01*
G01X1435692Y363627D01*
X1435635Y363766D01*
G02X1435639Y363805I200J-1D01*
G01X1437578Y370200D01*
G02X1437682Y370308I186J-75D01*
G01X1437774Y370344D01*
G02X1437843Y370357I71J-187D01*
G01X1437986D01*
X1438033Y370345D01*
X1438055Y370333D01*
G03X1438768Y370153I713J1322D01*
G03X1440260Y371479I0J1502D01*
G01X1440266Y371533D01*
G03X1438911Y373151I-1498J122D01*
G01X1438867Y373155D01*
X1438734Y373232D01*
X1438708Y373255D01*
X1438649Y373337D01*
Y373339D01*
X1438584Y373431D01*
X1438568Y373455D01*
X1438565Y373459D01*
X1440132Y378630D01*
X1440913Y381206D01*
G02X1440959Y381285I191J-59D01*
G01X1440991Y381319D01*
X1441019Y381329D01*
G03X1441110Y381364I-494J1419D01*
G01X1441112D01*
G03X1442026Y382747I-589J1383D01*
G01Y382760D01*
X1442024Y382789D01*
G03X1441734Y383636I-1501J-41D01*
G01Y383637D01*
G02X1441701Y383807I160J119D01*
G01X1445724Y397077D01*
X1454686Y426644D01*
X1466971Y466882D01*
G03X1467123Y467626I-3720J1147D01*
G01Y467629D01*
X1467126Y467652D01*
X1467132Y467697D01*
G02X1467139Y467729I198J-27D01*
G01X1467446Y468741D01*
G03X1467581Y469368I-3758J1137D01*
G01X1480516Y567700D01*
X1480517Y567706D01*
X1522583Y790160D01*
X1538174Y872473D01*
G02X1538187Y872510I195J-48D01*
G02X1538309Y872616I181J-85D01*
G01X1538342Y872625D01*
X1545235D01*
G02X1545633Y872193I-1J-400D01*
G01X1544402Y856945D01*
X1539602Y797515D01*
X1537566Y772313D01*
X1536887Y763904D01*
X1536166Y754982D01*
X1530698Y687284D01*
Y687279D01*
X1530696Y687263D01*
X1530695Y687254D01*
X1530694Y687242D01*
Y687239D01*
X1530693Y687230D01*
G03X1530691Y687205I3878J-323D01*
G01X1530433Y684013D01*
X1529771Y675813D01*
X1529214Y668919D01*
X1529013Y666426D01*
X1528133Y655526D01*
X1527244Y644510D01*
G03X1527239Y644436I3880J-299D01*
G01X1525793Y620901D01*
X1524916Y606632D01*
Y606629D01*
X1524803Y605190D01*
X1521775Y566696D01*
Y566690D01*
X1520632Y555832D01*
G03X1520611Y555434I3870J-404D01*
G01X1520588Y545370D01*
Y545361D01*
G03X1520605Y544990I3891J-8D01*
G03X1520623Y544835I3874J371D01*
G01X1521042Y541764D01*
X1521246Y540263D01*
G02X1521234Y540178I-199J-15D01*
G01X1521226Y540157D01*
G02X1521189Y540106I-178J91D01*
G01X1521173Y540090D01*
X1521142Y540066D01*
X1521012Y539967D01*
X1521009Y539965D01*
X1520904Y539890D01*
G02X1520788Y539852I-117J162D01*
G01X1520731D01*
X1520657Y539867D01*
X1520640Y539874D01*
G03X1520119Y540001I-683J-1669D01*
G03X1519952Y540008I-159J-1795D01*
G03X1518150Y538206I0J-1802D01*
G01Y534806D01*
G03X1519952Y533004I1802J0D01*
G03X1520428Y533067I4J1802D01*
G03X1520590Y533120I-479J1738D01*
G03X1520824Y533228I-636J1687D01*
G01X1520846Y533240D01*
X1520884Y533250D01*
X1520896Y533253D01*
X1520921Y533261D01*
X1520975Y533264D01*
X1521071Y533242D01*
X1521109Y533234D01*
X1521224Y533156D01*
X1521245Y533128D01*
G03X1521275Y533089I1206J896D01*
G01X1521279Y533084D01*
X1521280Y533083D01*
G03X1521573Y532807I1167J946D01*
G03X1521612Y532780I874J1221D01*
G01X1521613Y532779D01*
G03X1521628Y532770I780J1283D01*
G02X1521634Y532766I-108J-168D01*
G03X1521654Y532753I828J1253D01*
G02X1521658Y532751I-87J-180D01*
G01X1521659Y532750D01*
X1521660Y532749D01*
G03X1521671Y532743I725J1315D01*
G03X1521678Y532738I875J1217D01*
G01X1521695Y532728D01*
G03X1521699Y532726I674J1343D01*
G01X1521700Y532725D01*
G03X1521759Y532693I745J1304D01*
G03X1521762Y532691I112J164D01*
G02X1521768Y532688I-86J-180D01*
G03X1521778Y532683I676J1339D01*
G01X1521783Y532681D01*
X1521792Y532676D01*
X1521793Y532675D01*
X1521794D01*
X1521834Y532657D01*
G03X1521893Y532632I615J1370D01*
G03X1522106Y532565I556J1396D01*
G01X1522107D01*
X1522111Y532564D01*
X1522130Y532559D01*
X1522145Y532554D01*
X1522172Y532544D01*
X1522191Y532537D01*
X1522225Y532517D01*
G02X1522315Y532403I-101J-173D01*
G01X1522321Y532382D01*
X1522882Y528267D01*
X1523136Y526405D01*
X1523228Y525728D01*
X1523616Y522880D01*
X1523617Y522874D01*
Y522869D01*
X1523947Y519820D01*
X1523999Y519336D01*
G02X1524000Y519320I-199J-20D01*
G01X1524373Y484727D01*
X1524522Y470890D01*
Y470882D01*
X1523973Y452759D01*
X1522997Y420525D01*
X1522834Y415550D01*
X1522778Y413864D01*
Y413854D01*
X1522552Y411035D01*
G02X1522492Y410908I-199J16D01*
G01X1522466Y410882D01*
X1522401Y410854D01*
X1522364Y410852D01*
G03X1521231Y410232I85J-1500D01*
G01X1521224Y410223D01*
X1521135Y410165D01*
G02X1521070Y410137I-110J167D01*
G01X1520988Y410118D01*
G02X1520932Y410114I-42J195D01*
G02X1520857Y410133I11J200D01*
G01X1520845Y410140D01*
G03X1519955Y410376I-892J-1566D01*
G01X1519952D01*
G03X1518150Y408574I0J-1802D01*
G01Y405174D01*
G03X1519952Y403372I1802J0D01*
G01X1519965D01*
G03X1520822Y403595I-11J1802D01*
G01X1520825Y403597D01*
X1520844Y403607D01*
X1520934Y403632D01*
X1520987Y403630D01*
X1521069Y403611D01*
X1521105Y403603D01*
X1521224Y403525D01*
X1521245Y403497D01*
G03X1521784Y403049I1203J899D01*
G02X1521878Y402953I-88J-180D01*
G02X1521895Y402853I-183J-83D01*
G01X1521894Y402844D01*
Y402842D01*
X1521655Y399873D01*
X1521400Y396691D01*
X1521367Y396285D01*
G02X1521321Y396173I-199J16D01*
G01X1521301Y396149D01*
G03X1521291Y396137I1149J-968D01*
G01X1521287Y396132D01*
X1521278Y396121D01*
X1521275Y396118D01*
G03X1521256Y396093I1186J-921D01*
G03X1521254Y396091I139J-141D01*
G03X1521249Y396084I1220J-877D01*
G01X1521228Y396054D01*
X1521187Y396026D01*
X1521173Y396017D01*
X1521150Y395983D01*
X1521047Y395960D01*
X1521045D01*
X1521005Y395951D01*
G02X1520972Y395948I-35J197D01*
G01X1520932D01*
G02X1520857Y395963I1J200D01*
G01X1520840Y395971D01*
X1520830Y395976D01*
G03X1520178Y396190I-878J-1576D01*
G03X1519809Y396199I-228J-1789D01*
G01X1519796Y396198D01*
G03X1518243Y394974I156J-1795D01*
G03X1518150Y394404I1709J-571D01*
G01Y392702D01*
X1518149Y391001D01*
G03X1519951Y389198I1803J0D01*
G01X1519952D01*
G03X1520120Y389206I-2J1802D01*
G01X1520127Y389207D01*
X1520131D01*
G03X1520162Y389211I-215J1789D01*
G01X1520167D01*
G03X1520201Y389216I-245J1786D01*
G01X1520207D01*
X1520213Y389217D01*
X1520217Y389218D01*
X1520226Y389219D01*
X1520230Y389220D01*
X1520242Y389221D01*
G03X1520450Y389268I-293J1779D01*
G01X1520464Y389272D01*
X1520497Y389277D01*
X1520535D01*
G02X1520640Y389236I-17J-199D01*
G01X1520712Y389177D01*
G02X1520768Y389103I-127J-154D01*
G02X1520785Y389019I-183J-81D01*
G01X1520390Y384118D01*
G02X1520290Y383973I-198J29D01*
G01X1520258Y383955D01*
G02X1520160Y383929I-99J174D01*
G01X1520091D01*
G02X1520047Y383934I0J200D01*
G01X1519998Y383945D01*
G02X1519971Y383955I56J192D01*
G01X1519966Y383957D01*
X1519945Y383967D01*
G03X1519353Y384102I-623J-1367D01*
G01X1519312D01*
G03X1518485Y381352I9J-1502D01*
G03X1519314Y381098I836J1248D01*
G01X1519327D01*
G03X1519803Y381177I-5J1502D01*
G01X1519834Y381181D01*
X1519872D01*
G02X1519961Y381160I0J-200D01*
G01X1519977Y381152D01*
X1519996Y381143D01*
X1520060Y381091D01*
G02X1520113Y381026I-125J-156D01*
G02X1520135Y380934I-178J-91D01*
G01X1520078Y380222D01*
G02X1519996Y380086I-198J27D01*
G01X1519953Y380058D01*
G02X1519853Y380030I-102J172D01*
G01X1519781D01*
X1519753Y380038D01*
G03X1519321Y380102I-434J-1438D01*
G03X1517819Y378600I0J-1502D01*
G03X1519315Y377098I1502J0D01*
G01X1519324D01*
G03X1519534Y377113I-2J1502D01*
G01X1519548Y377115D01*
X1519584Y377116D01*
G02X1519716Y377063I-4J-200D01*
G01X1519754Y377027D01*
G03X1519756Y377025I142J140D01*
G01X1519774Y377009D01*
X1519779Y377004D01*
X1519796Y376961D01*
G02X1519809Y376872I-186J-73D01*
G01X1518799Y364298D01*
X1518156Y356286D01*
X1517573Y349025D01*
G02X1517545Y348939I-199J17D01*
G01X1517522Y348900D01*
X1517492Y348880D01*
G02X1517445Y348859I-104J171D01*
G02X1517387Y348850I-59J191D01*
G01X1517307D01*
X1517278Y348859D01*
G03X1516840Y348924I-437J-1437D01*
G01X1516832D01*
G03X1516830Y345920I6J-1502D01*
G01X1516841D01*
G03X1516990Y345928I-6J1502D01*
G02X1517146Y345876I20J-199D01*
G01X1517236Y345792D01*
G02X1517300Y345629I-135J-147D01*
G01X1510207Y257272D01*
G03X1510205Y257245I3915J-304D01*
G03X1510198Y257115I3917J-276D01*
G01X1509525Y240321D01*
G02X1509405Y240157I-199J20D01*
G01X1509384Y240151D01*
G03X1508321Y238714I440J-1437D01*
G03X1509271Y237317I1502J0D01*
G01X1509273Y237316D01*
G02X1509367Y237240I-73J-186D01*
G01X1509382Y237216D01*
X1509399Y237157D01*
X1509224Y232792D01*
X1509176Y231594D01*
G02X1509147Y231498I-200J8D01*
G01X1509135Y231477D01*
X1509098Y231442D01*
X1509074Y231429D01*
G03X1508304Y230117I733J-1312D01*
G03X1508309Y229998I1503J4D01*
G01X1508315Y229940D01*
G03X1508971Y228868I1494J177D01*
G01X1508973Y228867D01*
G02X1509040Y228792I-111J-167D01*
G01X1509050Y228771D01*
X1509061Y228722D01*
X1509040Y228189D01*
X1508656Y218596D01*
Y218594D01*
G03X1508653Y218527I3921J-209D01*
G01Y218525D01*
G03X1508652Y218441I3926J-89D01*
G01Y218439D01*
G03Y218436I200J-1D01*
G03X1508653Y218378I3926J39D01*
G01Y218377D01*
X1508678Y216756D01*
X1508822Y207565D01*
Y207555D01*
X1508728Y204858D01*
X1508436Y196505D01*
G02X1508298Y196321I-200J6D01*
G01X1508093Y196239D01*
X1508091D01*
X1507996Y196203D01*
X1507964Y196196D01*
G02X1507809Y196240I-28J198D01*
G02X1507797Y196251I129J153D01*
G01X1507789Y196259D01*
G03X1506689Y196720I-1100J-1082D01*
G03X1505693Y196356I0J-1545D01*
G01X1505692Y196355D01*
X1505681Y196346D01*
G02X1505564Y196308I-117J162D01*
G01X1505544D01*
G03X1505461Y196290I0J-200D01*
G01X1505421Y196271D01*
G02X1505321Y196254I-82J182D01*
G02X1505265Y196268I20J199D01*
G01X1505240Y196278D01*
G03X1504189Y196699I-1051J-1101D01*
G01X1504188D01*
G03X1503203Y196337I1J-1523D01*
G01X1503173Y196313D01*
X1503151Y196308D01*
X1503044D01*
G03X1502961Y196290I0J-200D01*
G01X1502921Y196271D01*
G02X1502821Y196254I-82J182D01*
G02X1502765Y196268I20J199D01*
G01X1502740Y196278D01*
G03X1501689Y196699I-1051J-1101D01*
G01X1501688D01*
G03X1500703Y196337I1J-1523D01*
G01X1500673Y196313D01*
X1500651Y196308D01*
X1500544D01*
G03X1500461Y196290I0J-200D01*
G01X1500406Y196265D01*
G02X1500189Y196298I-83J181D01*
G01X1500148Y196334D01*
G03X1499191Y196678I-957J-1160D01*
G01X1499189D01*
G03Y193674I0J-1502D01*
G01X1499190D01*
G03X1500121Y193997I0J1504D01*
G01X1500142Y194014D01*
X1500175Y194028D01*
X1500185Y194032D01*
G02X1500252Y194044I68J-188D01*
G01X1500334D01*
G03X1500417Y194062I0J200D01*
G01X1500472Y194087D01*
G02X1500573Y194104I82J-182D01*
G02X1500611Y194097I-17J-199D01*
G01X1500648Y194064D01*
X1500651Y194062D01*
X1500652Y194061D01*
G03X1500657Y194056I144J139D01*
G03X1501689Y193653I1032J1120D01*
G03X1502672Y194014I0J1519D01*
G01X1502692Y194030D01*
X1502701Y194037D01*
G02X1502751Y194044I52J-193D01*
G01X1502834D01*
G03X1502917Y194062I0J200D01*
G01X1502972Y194087D01*
G02X1503073Y194104I82J-182D01*
G02X1503111Y194097I-17J-199D01*
G01X1503148Y194064D01*
X1503151Y194062D01*
X1503152Y194061D01*
G03X1503157Y194056I144J139D01*
G03X1504189Y193653I1032J1120D01*
G03X1505172Y194014I0J1519D01*
G01X1505192Y194030D01*
X1505201Y194037D01*
G02X1505251Y194044I52J-193D01*
G01X1505630D01*
G02X1505745Y194007I-1J-200D01*
G01X1505758Y193997D01*
X1505770Y193988D01*
X1505789Y193969D01*
G02X1505821Y193926I-143J-140D01*
G01X1505843Y193884D01*
G03X1506689Y193632I846J1294D01*
G01X1506691D01*
G03X1507699Y194007I0J1542D01*
G01X1507722Y194027D01*
X1507774Y194050D01*
X1507788Y194055D01*
G02X1507803Y194060I71J-187D01*
G01X1507853Y194070D01*
G02X1507918Y194068I26J-198D01*
G01X1507953Y194061D01*
X1508020Y194018D01*
X1508022Y194017D01*
X1508031Y194011D01*
G03X1508061Y193995I109J168D01*
G01X1508066Y193993D01*
X1508145Y193955D01*
X1508227Y193916D01*
G02X1508290Y193868I-87J-180D01*
G02X1508340Y193729I-150J-132D01*
G01X1508193Y189525D01*
X1508170Y188902D01*
G02X1508169Y188882I-200J0D01*
G01X1503884Y157164D01*
G03X1503849Y156699I3891J-527D01*
G01X1503783Y152464D01*
G02X1503781Y152435I-200J-1D01*
G01X1503430Y150285D01*
G03X1503380Y149658I3841J-622D01*
G01Y149573D01*
G03Y149570I200J-2D01*
G01X1503385Y149320D01*
Y149316D01*
G03X1503383Y149238I3924J-140D01*
G01X1503352Y147292D01*
Y147226D01*
G03X1503442Y146386I3926J-4D01*
G01X1503443Y146383D01*
X1503446Y146367D01*
X1503448Y146255D01*
X1503451Y146118D01*
Y146116D01*
X1503453Y146008D01*
G02X1503440Y145932I-200J-5D01*
G02X1503434Y145919I-185J77D01*
G01X1503422Y145896D01*
X1503416Y145886D01*
X1503415Y145884D01*
G03X1503329Y145702I3475J-1753D01*
G01Y145701D01*
X1503318Y145676D01*
G03X1503310Y145658I3551J-1589D01*
G01X1503309Y145657D01*
G03X1503302Y145641I3559J-1567D01*
G01X1503298Y145631D01*
G03X1503293Y145620I3539J-1615D01*
G01X1503265Y145550D01*
X1503249Y145507D01*
X1503239Y145480D01*
G03X1503228Y145451I3633J-1395D01*
G01Y145449D01*
X1503215Y145416D01*
G03X1503200Y145375I3647J-1358D01*
G01X1503190Y145352D01*
G02X1503112Y145270I-178J91D01*
G03X1502743Y145315I-371J-1508D01*
G01X1502741D01*
G03Y142209I0J-1553D01*
G03X1502881Y142215I4J1553D01*
G01X1502892Y142207D01*
X1502936Y142170D01*
X1502952Y142156D01*
X1502984Y142129D01*
X1503024Y142047D01*
G02X1503036Y142016I-180J-88D01*
G01X1503052Y141964D01*
X1503054Y141945D01*
G03X1503488Y140547I3868J434D01*
G01X1503505Y140515D01*
X1503510Y140481D01*
G02X1503508Y140415I-198J-27D01*
G01X1503498Y140376D01*
X1503412Y140058D01*
Y140056D01*
X1503394Y139987D01*
X1503391Y139975D01*
G02X1503309Y139868I-191J61D01*
G01X1503054Y139718D01*
G02X1503029Y139707I-93J177D01*
G01X1502955Y139726D01*
G03X1502821Y139757I-952J-3809D01*
G03X1502032Y139842I-813J-3842D01*
G01X1501981D01*
G03X1499906Y139230I30J-3927D01*
G03X1499889Y139233I-270J-1478D01*
G01X1499881Y139235D01*
G03X1499623Y139259I-268J-1478D01*
G01X1499610D01*
G03X1498108Y137772I0J-1502D01*
G01Y137756D01*
G03X1498244Y137132I1502J1D01*
G01X1498253Y137112D01*
X1498260Y137080D01*
G03X1498185Y136803I3750J-1164D01*
G03X1498153Y136652I3824J-889D01*
G03X1498084Y135915I3857J-733D01*
G03X1498436Y134289I3928J-1D01*
G02Y134141I-186J-74D01*
G03X1498084Y132515I3576J-1625D01*
G01Y132511D01*
G03X1498260Y131351I3926J2D01*
G01X1498256Y131333D01*
X1498242Y131292D01*
G03X1498227Y131258I1367J-623D01*
G01Y131257D01*
X1498219Y131236D01*
G03X1498176Y131119I1387J-576D01*
G01Y131118D01*
G03X1498172Y131107I1409J-519D01*
G03X1498170Y131099I193J-52D01*
G01X1498169Y131096D01*
Y131095D01*
G03X1498115Y130819I1441J-425D01*
G03X1498108Y130700I1495J-148D01*
G01Y130663D01*
G03X1499610Y129168I1502J7D01*
G01X1499628D01*
G03X1499880Y129192I-16J1502D01*
G01X1499909Y129197D01*
G03X1501977Y128588I2101J3318D01*
G01X1502025D01*
G03X1504111Y129198I-16J3927D01*
G01X1504136Y129193D01*
G03X1504147Y129191I274J1477D01*
G01X1504149D01*
G03X1504172Y129187I269J1478D01*
G03X1504180Y129185I52J192D01*
G03X1504196Y129183I194J1490D01*
G01X1504200D01*
G03X1504423Y129167I219J1486D01*
G01X1504430D01*
G03X1504576Y129176I-19J1504D01*
G03X1504869Y129238I-163J1493D01*
G01X1504871D01*
X1504873Y129239D01*
G03X1504882Y129242I-471J1428D01*
G01X1504901Y129248D01*
X1504940Y129253D01*
G02X1505066Y129221I16J-199D01*
G01X1505221Y129110D01*
X1505223D01*
X1505338Y129026D01*
Y129025D01*
G02X1505386Y128974I-119J-160D01*
G01X1505384Y128902D01*
Y128828D01*
G03X1505736Y127202I3928J-1D01*
G02Y127054I-186J-74D01*
G03X1505384Y125428I3576J-1625D01*
G01Y125425D01*
G03X1505395Y125133I3926J2D01*
G01X1505400Y125062D01*
G02X1505398Y125058I-179J87D01*
G02X1505391Y125047I-172J102D01*
G01X1505338Y124976D01*
G02X1505248Y124913I-155J126D01*
G01X1505218Y124903D01*
X1505163Y124901D01*
X1505108Y124916D01*
X1505090Y124925D01*
G03X1505011Y124961I-662J-1349D01*
G01X1504987Y124971D01*
G03X1504411Y125086I-576J-1387D01*
G01X1504371D01*
G03X1504285Y125081I44J-1501D01*
G03X1504274Y125080I130J-1496D01*
G01X1504136Y125068D01*
X1504075Y125082D01*
X1504047Y125099D01*
G03X1502010Y125668I-2036J-3357D01*
G03X1501072Y125555I-3J-3926D01*
G03X1500624Y125416I937J-3813D01*
G03X1499906Y125058I1384J-3675D01*
G01X1499864Y125065D01*
X1499862D01*
G03X1499711Y125083I-253J-1481D01*
G01X1499709D01*
G03X1499690Y125084I-88J-1499D01*
G01X1499688D01*
G03X1499633Y125086I-82J-1500D01*
G01X1499606D01*
G03X1498108Y123593I4J-1502D01*
G01Y123582D01*
G03X1498253Y122937I1503J-1D01*
G01X1498260Y122908D01*
G03X1498084Y121759I3751J-1162D01*
G01Y121742D01*
G03X1498436Y120116I3928J-1D01*
G02Y119968I-186J-74D01*
G03X1498084Y118342I3576J-1625D01*
G01Y118340D01*
G03X1498261Y117176I3926J2D01*
G01X1498254Y117146D01*
X1498245Y117127D01*
G03X1498108Y116500I1365J-627D01*
G01Y116497D01*
G03X1499610Y114995I1502J0D01*
G01X1499614D01*
G03X1499878Y115018I2J1502D01*
G01X1499910Y115024D01*
G03X1502010Y114415I2100J3318D01*
G01X1502011D01*
G03X1504111Y115024I-1J3927D01*
G01X1504115Y115023D01*
X1504135Y115019D01*
X1504142Y115018D01*
G03X1504410Y114995I262J1479D01*
G01X1504413D01*
G03X1504854Y115062I-3J1502D01*
G01X1504883Y115071D01*
X1504974D01*
G02X1505061Y115050I-2J-200D01*
G01X1505066Y115048D01*
G03X1505071Y115045I105J170D01*
G01X1505076Y115042D01*
X1505085Y115037D01*
X1505169Y114975D01*
X1505172Y114973D01*
X1505263Y114907D01*
X1505331Y114858D01*
X1505339Y114852D01*
G02X1505343Y114849I-118J-162D01*
G02X1505386Y114801I-125J-156D01*
G01X1505384Y114714D01*
Y114655D01*
G03X1505736Y113029I3928J-1D01*
G02Y112881I-186J-74D01*
G03X1505384Y111255I3576J-1625D01*
G03X1505453Y110517I3926J-5D01*
G03X1505520Y110228I3856J742D01*
G03X1505560Y110090I3790J1024D01*
G01Y110089D01*
X1505553Y110056D01*
G03X1505544Y110036I1365J-626D01*
G01X1505543Y110034D01*
G03X1505408Y109430I1367J-623D01*
G01Y109409D01*
G03X1506910Y107908I1502J1D01*
G03X1507172Y107931I0J1502D01*
G01X1507210Y107937D01*
G03X1507414Y107816I2104J3315D01*
G01X1507416D01*
X1507465Y107788D01*
X1507480Y107751D01*
X1507558Y107462D01*
X1507557Y107408D01*
X1507550Y107382D01*
X1507533Y107321D01*
X1507521Y107300D01*
G03X1507327Y106562I1308J-738D01*
G01Y106526D01*
X1507328Y106510D01*
Y106507D01*
G03X1507337Y106388I1501J54D01*
G03X1507504Y105854I1492J173D01*
G03X1507902Y105379I1325J706D01*
G01X1507910Y105373D01*
X1507938Y105346D01*
X1507989Y105284D01*
X1507999Y105263D01*
X1508009Y105217D01*
X1507993Y104911D01*
X1507991Y104862D01*
X1507919Y104738D01*
X1507901Y104720D01*
X1507857Y104675D01*
X1507832Y104658D01*
G03X1507168Y103411I839J-1247D01*
G03X1510172I1502J0D01*
G03X1509584Y104603I-1502J0D01*
G01X1509573Y104611D01*
X1509547Y104637D01*
X1509529Y104660D01*
G02X1509493Y104771I164J114D01*
G01X1509508Y105105D01*
X1509527Y105142D01*
X1509531Y105151D01*
X1509566Y105210D01*
X1509580Y105233D01*
X1509642Y105297D01*
X1509667Y105314D01*
G03X1510331Y106557I-838J1247D01*
G01Y106583D01*
G03X1510256Y107034I-1502J-18D01*
G01X1510249Y107054D01*
X1510244Y107103D01*
G02X1510250Y107162I199J10D01*
G02X1510258Y107186I193J-51D01*
G01X1510397Y107465D01*
G03X1510401Y107471I-164J114D01*
G02X1510412Y107485I163J-116D01*
G01X1510487Y107509D01*
G03X1511330Y107888I-1177J3746D01*
G02X1511430Y107917I104J-171D01*
G02X1511456Y107916I5J-200D01*
G03X1511609Y107907I165J1494D01*
G01X1511611D01*
G03X1511686Y107909I-3J1503D01*
G01X1511724Y107912D01*
G03X1512813Y108510I-114J1498D01*
G01X1512821Y108520D01*
G03X1514996Y109624I-602J3880D01*
G01X1520516Y115143D01*
X1520528Y115149D01*
G03X1520540Y115155I-666J1347D01*
G01X1520544Y115157D01*
G03X1521201Y115814I-682J1339D01*
G01X1521203Y115818D01*
G03X1521209Y115830I-1341J678D01*
G01X1521215Y115842D01*
X1521685Y116312D01*
X1526409Y121037D01*
G03X1526772Y121454I-2773J2780D01*
G03X1526996Y121785I-3136J2363D01*
G01X1527000Y121792D01*
X1527024Y121825D01*
G03X1527233Y122072I-2864J2635D01*
G03X1527429Y122346I-3064J2399D01*
G03X1527494Y122450I-3267J2114D01*
G01X1527498Y122458D01*
X1527504Y122467D01*
G03X1527528Y122507I-3325J2022D01*
G03X1527560Y122562I-3348J1985D01*
G01Y122563D01*
X1527584Y122607D01*
X1527588Y122615D01*
G03X1527760Y122977I-3424J1849D01*
G01X1530145Y128735D01*
X1530317Y129148D01*
Y129150D01*
X1530371Y129276D01*
G02X1530399Y129317I178J-91D01*
G01X1530419Y129340D01*
X1530451Y129358D01*
G03X1531222Y130670I-731J1312D01*
G03X1531169Y131073I-1503J7D01*
G01X1531164Y131091D01*
X1531161Y131126D01*
Y131129D01*
X1531157Y131176D01*
X1531586Y132211D01*
X1533200Y136109D01*
X1537308Y146026D01*
G03X1537492Y146590I-3596J1485D01*
G01X1537495Y146601D01*
G02X1537498Y146611I193J-52D01*
G01X1537533Y146693D01*
Y146695D01*
X1537579Y146805D01*
X1537580D01*
X1537600Y146853D01*
Y146855D01*
G03X1537908Y148378I-3618J1524D01*
G01Y148443D01*
Y148447D01*
X1537862Y151228D01*
X1537850Y151942D01*
G03X1537767Y152682I-3926J-66D01*
G01X1537570Y153623D01*
X1536093Y160680D01*
X1536092Y160683D01*
G02X1536175Y160884I197J36D01*
G01X1536477Y161093D01*
G02X1536698Y161098I114J-164D01*
G03X1537500Y160866I802J1270D01*
G03X1538527Y161272I0J1502D01*
G01X1538528Y161273D01*
G02X1538599Y161315I135J-147D01*
G02X1538664Y161326I65J-189D01*
G01X1538936D01*
G02X1539001Y161315I0J-200D01*
G02X1539072Y161273I-64J-189D01*
G01X1539073Y161272D01*
G03X1540100Y160866I1027J1096D01*
G03Y163870I0J1502D01*
G03X1539073Y163464I0J-1502D01*
G01X1539072Y163463D01*
G02X1539001Y163421I-135J147D01*
G02X1538936Y163410I-65J189D01*
G01X1538664D01*
G02X1538599Y163421I0J200D01*
G02X1538528Y163463I64J189D01*
G01X1538527Y163464D01*
G03X1537500Y163870I-1027J-1096D01*
G03X1537300Y163857I-3J-1502D01*
G03X1536256Y163210I200J-1489D01*
G01Y163209D01*
G02X1536167Y163137I-165J113D01*
G02X1536052Y163126I-76J185D01*
G01X1535691Y163196D01*
G02X1535657Y163206I39J196D01*
G02X1535533Y163352I72J187D01*
G01X1534415Y168694D01*
X1533379Y173639D01*
Y173643D01*
X1531033Y186051D01*
X1529621Y193521D01*
X1529360Y194902D01*
G02X1529357Y194936I197J35D01*
G01X1529176Y206563D01*
G02X1529197Y206656I200J4D01*
G01X1529219Y206699D01*
X1529232Y206709D01*
G03X1529897Y207978I-878J1269D01*
G03X1529535Y208971I-1543J0D01*
G01X1529534Y208972D01*
X1529511Y209000D01*
X1529487Y209065D01*
Y209123D01*
G03X1529469Y209206I-200J0D01*
G01X1529444Y209261D01*
G02X1529477Y209478I181J83D01*
G01X1529513Y209519D01*
G03X1529857Y210455I-1160J957D01*
G01Y210479D01*
G03X1529571Y211360I-1502J-1D01*
G01X1529546Y211394D01*
X1529531Y211413D01*
G02X1529510Y211447I159J122D01*
G01X1529508Y211451D01*
G02X1529487Y211540I179J89D01*
G01Y211623D01*
G03X1529469Y211706I-200J0D01*
G01X1529444Y211761D01*
G02X1529477Y211978I181J83D01*
G01X1529513Y212019D01*
G03X1529857Y212955I-1160J957D01*
G01Y212979D01*
G03X1529571Y213860I-1502J-1D01*
G01X1529546Y213894D01*
X1529531Y213913D01*
G02X1529510Y213947I159J122D01*
G01X1529508Y213951D01*
G02X1529487Y214040I179J89D01*
G01Y214123D01*
G03X1529469Y214206I-200J0D01*
G01X1529447Y214250D01*
G02X1529478Y214471I180J87D01*
G01Y214472D01*
G03X1529862Y215477I-1123J1005D01*
G01Y215478D01*
G03X1529281Y216668I-1509J0D01*
G01X1529261Y216683D01*
X1529238Y216712D01*
G02X1529233Y216720I167J110D01*
G02X1529232Y216722I178J90D01*
G01X1529194Y216795D01*
Y216797D01*
X1529185Y216814D01*
X1529179Y216839D01*
G02X1529173Y216894I194J49D01*
G01X1529241Y218860D01*
X1529275Y219838D01*
X1529298Y220501D01*
X1529300Y220548D01*
X1529302Y220612D01*
X1529352Y222038D01*
X1529363Y222339D01*
Y222341D01*
X1529372Y222554D01*
G02X1529374Y222569I199J-19D01*
G01X1529380Y222590D01*
G02X1529401Y222639I193J-54D01*
G01X1529412Y222658D01*
X1529430Y222677D01*
X1529434Y222681D01*
G03X1529857Y223715I-1079J1045D01*
G01Y223732D01*
G03X1529519Y224677I-1502J-4D01*
G01X1529498Y224703D01*
X1529449Y224833D01*
X1529451Y224874D01*
X1529461Y225136D01*
X1529462Y225166D01*
X1529485Y225235D01*
X1529509Y225264D01*
X1529510Y225265D01*
G03X1529524Y225282I-1153J963D01*
G01X1529885Y225718D01*
G03X1529864Y225995I-154J128D01*
G01X1529845Y226014D01*
X1529849Y226069D01*
Y226075D01*
G03X1529857Y226225I-1494J155D01*
G01Y226262D01*
G03X1529587Y227086I-1502J-36D01*
G01X1529581Y227094D01*
X1529571Y227111D01*
X1529552Y227137D01*
X1529542Y227171D01*
X1529532Y227204D01*
X1529537Y227333D01*
Y227335D01*
X1529548Y227641D01*
X1529551Y227727D01*
X1529552Y227756D01*
X1529589Y227870D01*
X1529606Y227894D01*
G03X1529614Y227906I-1246J839D01*
G01X1529616Y227909D01*
X1529623Y227919D01*
X1529632Y227933D01*
G03X1529857Y228712I-1278J791D01*
G01Y228727D01*
G03X1529657Y229476I-1502J0D01*
G01X1529644Y229498D01*
X1529616Y229598D01*
X1529617Y229630D01*
X1529630Y230002D01*
X1529644Y230405D01*
G02X1529653Y230456I200J-9D01*
G01X1529659Y230477D01*
X1529669Y230497D01*
X1529671Y230500D01*
X1529672Y230502D01*
X1529674Y230505D01*
G03X1529857Y231200I-1321J719D01*
G01Y231231D01*
G03X1529722Y231850I-1502J-3D01*
G01X1529721Y231852D01*
X1529716Y231863D01*
X1529709Y231885D01*
X1529697Y231920D01*
X1529799Y234847D01*
X1530058Y242259D01*
X1530343Y250425D01*
X1530386Y251656D01*
Y251658D01*
X1530567Y256183D01*
Y256187D01*
X1530604Y256653D01*
X1530634Y257021D01*
X1530649Y257195D01*
G02X1530725Y257331I198J-22D01*
G01X1530771Y257361D01*
X1530850Y257412D01*
X1530870Y257425D01*
X1530872Y257426D01*
X1530910Y257451D01*
G02X1530947Y257469I105J-170D01*
G02X1531027Y257480I67J-189D01*
G01X1531031D01*
X1531048Y257479D01*
X1531088Y257471D01*
X1531102Y257466D01*
G03X1531608Y257378I507J1414D01*
G01X1531620D01*
G03X1533111Y258880I-11J1502D01*
G03X1531609Y260382I-1502J0D01*
G03X1531318Y260353I3J-1502D01*
G01X1531316D01*
G02X1531146Y260400I-37J196D01*
G01X1531028Y260506D01*
X1530995Y260536D01*
G02X1530930Y260700I134J148D01*
G01X1531018Y261802D01*
X1531030Y261953D01*
X1531068Y262426D01*
G02X1531133Y262549I198J-26D01*
G01X1531163Y262574D01*
X1531217Y262616D01*
X1531278Y262663D01*
G02X1531358Y262695I113J-165D01*
G01X1531426D01*
X1531442Y262692D01*
G03X1531683Y262673I239J1488D01*
G01X1531684D01*
G03X1532625Y263003I0J1507D01*
G01X1532626Y263004D01*
X1532653Y263025D01*
X1532684Y263036D01*
G02X1532752Y263048I68J-188D01*
G01X1532829D01*
G03X1532912Y263066I0J200D01*
G01X1532967Y263091D01*
G02X1533184Y263058I83J-181D01*
G01X1533225Y263022D01*
G03X1534182Y262678I957J1160D01*
G01X1534184D01*
G03Y265682I0J1502D01*
G03X1533252Y265358I0J-1502D01*
G01X1533233Y265343D01*
X1533211Y265333D01*
X1533190Y265322D01*
X1533146Y265312D01*
X1533039D01*
G03X1532956Y265294I0J-200D01*
G01X1532913Y265272D01*
G02X1532858Y265254I-89J179D01*
G02X1532804Y265252I-34J197D01*
G01X1532766Y265257D01*
X1532714Y265282D01*
X1532690Y265302D01*
G03X1531684Y265687I-1006J-1122D01*
G03X1531676I-4J-1507D01*
G01X1531623D01*
X1531538Y265736D01*
G02X1531497Y265768I101J172D01*
G01X1531458Y265809D01*
G02X1531456Y265811I140J142D01*
G01X1531384Y265888D01*
X1531379Y265893D01*
X1531366Y265932D01*
G02X1531356Y266012I189J64D01*
G01X1534565Y305993D01*
X1537119Y337813D01*
G02X1537250Y337976I198J-25D01*
G01X1537344Y338005D01*
X1537346D01*
X1537394Y338019D01*
G02X1537445Y338026I52J-193D01*
G01X1537504D01*
G02X1537548Y338021I0J-200D01*
G02X1537591Y338006I-44J-195D01*
G01X1537609Y337997D01*
X1537644Y337968D01*
X1537660Y337948D01*
G03X1537682Y337920I1193J915D01*
G03X1538852Y337361I1170J944D01*
G01X1538853D01*
G03Y340365I0J1502D01*
G01X1538852D01*
G03X1537835Y339967I1J-1502D01*
G01X1537834Y339966D01*
X1537813Y339947D01*
X1537794Y339928D01*
X1537739Y339899D01*
X1537708Y339894D01*
G02X1537589Y339910I-34J197D01*
G01X1537487Y339958D01*
G03X1537485Y339960I-142J-140D01*
G01X1537418Y339990D01*
G02X1537399Y340001I91J178D01*
G02X1537309Y340184I110J167D01*
G01X1537817Y346515D01*
G02X1537937Y346674I199J-25D01*
G01X1537949Y346679D01*
X1537950D01*
X1537997Y346699D01*
X1538013Y346707D01*
X1538055Y346724D01*
G02X1538164Y346737I77J-184D01*
G01X1538186Y346733D01*
X1538228Y346718D01*
G02X1538255Y346706I-67J-188D01*
G01X1538291Y346687D01*
G02X1538302Y346680I-102J-172D01*
G01X1538311Y346673D01*
G03X1538651Y346476I917J1191D01*
G03X1539228Y346361I577J1388D01*
G01X1539229D01*
G03Y349365I0J1502D01*
G01X1539227D01*
G03X1538527Y349192I0J-1502D01*
G01X1538506Y349181D01*
X1538435Y349163D01*
X1538415Y349160D01*
G02X1538360Y349162I-20J199D01*
G01X1538239Y349187D01*
X1538228Y349190D01*
G02X1538171Y349216I53J193D01*
G01X1538152Y349230D01*
X1538150Y349232D01*
X1538147Y349234D01*
X1538145Y349236D01*
G03X1538143Y349237I-89J-176D01*
G03X1538129Y349249I-137J-146D01*
G01X1538117Y349258D01*
G02X1538049Y349407I132J150D01*
G01X1538331Y352925D01*
G02X1538482Y353090I198J-30D01*
G01X1538483D01*
G03X1538977Y353309I-353J1463D01*
G03X1539624Y354738I-847J1244D01*
G03X1539301Y355498I-1493J-186D01*
G03X1538726Y355934I-1169J-944D01*
G01X1538711Y355941D01*
X1538589Y356125D01*
Y356130D01*
X1542938Y410316D01*
G03X1542949Y410511I-3914J319D01*
G01X1544771Y470607D01*
G03X1544772Y470652I-3925J110D01*
G01Y470674D01*
G03Y470725I-3926J26D01*
G01Y470768D01*
X1544564Y490135D01*
X1544281Y516367D01*
X1544021Y540539D01*
G02X1544093Y540695I200J2D01*
G02X1544157Y540731I128J-153D01*
G01X1544336Y540792D01*
X1544525Y540856D01*
G02X1544740Y540783I55J-193D01*
G03X1545032Y540476I1443J1080D01*
G03X1546067Y540065I1150J1388D01*
G01X1546110Y540062D01*
G03X1546182Y540061I61J1802D01*
G01X1546184D01*
G03X1547986Y541863I-1J1803D01*
G01Y545264D01*
G03X1544380I-1803J0D01*
G01Y544427D01*
Y544426D01*
G02X1544181Y544227I-200J1D01*
G01X1544178D01*
G02X1543979Y544425I1J200D01*
G01X1543970Y545269D01*
X1543946Y547465D01*
X1543926Y549254D01*
X1543934Y549261D01*
X1544048Y549363D01*
G02X1544182Y549415I134J-148D01*
G01X1544202D01*
X1544212Y549414D01*
G03X1544375Y549405I164J1493D01*
G03X1545307Y549729I0J1502D01*
G01X1545326Y549744D01*
X1545350Y549756D01*
G02X1545396Y549771I85J-181D01*
G02X1545435Y549775I40J-196D01*
G01X1545520D01*
G03X1545603Y549793I0J200D01*
G01X1545658Y549818D01*
G02X1545875Y549785I83J-181D01*
G01X1545916Y549749D01*
G03X1546869Y549405I957J1160D01*
G01X1546875D01*
G03X1548377Y550892I0J1502D01*
G01Y550909D01*
G03X1548091Y551790I-1502J-1D01*
G01X1548066Y551823D01*
X1548051Y551842D01*
G02X1548030Y551876I159J122D01*
G01X1548028Y551880D01*
G02X1548007Y551969I179J89D01*
G01Y552052D01*
G03X1547989Y552135I-200J0D01*
G01X1547964Y552190D01*
G02X1547997Y552407I181J83D01*
G01X1548033Y552448D01*
G03X1548377Y553405I-1160J957D01*
G01Y553407D01*
G03X1546875Y554909I-1502J0D01*
G03X1545943Y554585I0J-1502D01*
G01X1545924Y554570D01*
X1545902Y554560D01*
X1545881Y554549D01*
X1545837Y554539D01*
X1545730D01*
G03X1545647Y554521I0J-200D01*
G01X1545603Y554499D01*
G02X1545382Y554530I-87J180D01*
G01X1545381D01*
G03X1544376Y554914I-1005J-1123D01*
G01X1544374D01*
G03X1544156Y554898I1J-1507D01*
G01X1544104Y554891D01*
X1544007Y554928D01*
G02X1543966Y554952I80J183D01*
G01X1543956Y554960D01*
X1543949Y554966D01*
X1543909Y555000D01*
X1543900Y555008D01*
X1543883Y555044D01*
G02X1543864Y555128I181J85D01*
G01X1543728Y567662D01*
X1543727Y567765D01*
X1543724Y568030D01*
G02X1543769Y568159I200J3D01*
G01X1543966Y568377D01*
G02X1544084Y568433I140J-143D01*
G01X1544087D01*
G03X1544134Y568438I-135J1496D01*
G01X1544135D01*
G02X1544266Y568408I23J-199D01*
G01X1544499Y568245D01*
G02X1544571Y568145I-118J-161D01*
G01X1544574Y568131D01*
G03X1546036Y566973I1462J344D01*
G01X1546037D01*
G03X1546755Y567156I-1J1502D01*
G01X1546757Y567157D01*
G02X1546856Y567181I95J-176D01*
G01X1546905Y567180D01*
X1547066Y567085D01*
G02X1547143Y566987I-111J-166D01*
G01Y566926D01*
G03X1548645Y565427I1502J3D01*
G01X1548657D01*
G03X1550159Y566928I0J1502D01*
G01Y566930D01*
G03X1550153Y567058I-1502J-6D01*
G01X1550152Y567072D01*
G02Y567080I200J4D01*
G01X1550153Y567094D01*
G03X1550159Y567227I-1496J134D01*
G01Y567229D01*
G03X1549660Y568348I-1504J0D01*
G01X1549628Y568377D01*
X1549611Y568415D01*
X1549598Y568443D01*
X1549585Y568548D01*
X1549584Y568554D01*
X1549623Y568615D01*
G03X1549861Y569426I-1263J811D01*
G03X1549859Y569512I-1502J8D01*
G02X1549860Y569540I200J7D01*
G03X1549871Y569723I-1502J182D01*
G01Y569726D01*
G03X1548360Y571238I-1512J0D01*
G01X1548359D01*
G03X1548194Y571228I9J-1512D01*
G01X1548155Y571224D01*
X1548120Y571233D01*
G02X1548058Y571261I50J194D01*
G01X1547877Y571396D01*
X1547846Y571419D01*
X1547789Y571508D01*
X1547783Y571524D01*
X1547763Y571570D01*
X1547759Y571589D01*
G03X1546293Y572764I-1466J-327D01*
G03X1544933Y571900I0J-1502D01*
G01X1544918Y571868D01*
X1544844Y571794D01*
G02X1544782Y571752I-141J142D01*
G01X1544619Y571681D01*
G02X1544553Y571665I-79J183D01*
G01X1544509Y571663D01*
X1544487Y571671D01*
X1544470Y571677D01*
G03X1544403Y571700I-534J-1446D01*
G01X1544369Y571711D01*
X1544343Y571730D01*
G02X1544297Y571779I121J160D01*
G01X1544231Y571879D01*
G02X1544203Y571944I167J110D01*
G01X1544195Y571976D01*
X1544199Y572010D01*
G03X1544206Y572162I-1495J145D01*
G03X1544200Y572293I-1502J-3D01*
G01X1544199Y572303D01*
Y572311D01*
X1544200Y572327D01*
G03X1544206Y572462I-1496J134D01*
G01Y572463D01*
G03X1543727Y573563I-1503J0D01*
G01X1543726Y573564D01*
G02X1543663Y573702I137J146D01*
G01X1543645Y575399D01*
X1543620Y577660D01*
Y577674D01*
X1543776Y580200D01*
X1545153Y602590D01*
Y602594D01*
X1561794Y815932D01*
X1566206Y872497D01*
G02X1566214Y872515I186J-72D01*
G02X1566392Y872625I179J-90D01*
G01X1578595D01*
G02X1578712Y872578I-12J-200D01*
G02X1578775Y872481I-129J-153D01*
G01X1578782Y872456D01*
X1585925Y735223D01*
X1589057Y675049D01*
X1589436Y667765D01*
X1589801Y660748D01*
X1590276Y651623D01*
X1590558Y646212D01*
X1590702Y643445D01*
X1592259Y613529D01*
X1592782Y603479D01*
X1594542Y569670D01*
Y569652D01*
G02X1594500Y569530I-200J1D01*
G01X1594479Y569504D01*
X1594426Y569469D01*
X1594391Y569459D01*
G03X1593255Y568000I369J-1459D01*
G03X1594498Y566518I1505J0D01*
G01X1594515Y566515D01*
X1594545Y566505D01*
X1594580Y566492D01*
G02X1594594Y566485I-82J-182D01*
G01X1594620Y566471D01*
G02X1594679Y566417I-103J-172D01*
G02X1594687Y566405I-162J-117D01*
G01X1594713Y566363D01*
X1594716Y566310D01*
X1594731Y566032D01*
X1594739Y565881D01*
X1594740Y565869D01*
Y565868D01*
X1594747Y565729D01*
X1594788Y564939D01*
X1594818Y564355D01*
G02X1594760Y564204I-200J-10D01*
G01X1594709Y564153D01*
X1594680Y564138D01*
G03X1594049Y562073I685J-1338D01*
G01X1594051Y562070D01*
X1594056Y562060D01*
G03X1594492Y561577I1307J741D01*
G03X1594705Y561450I873J1222D01*
G03X1594833Y561394I666J1347D01*
G01X1594840Y561392D01*
X1594846Y561389D01*
X1594885Y561370D01*
G02X1594981Y561211I-104J-171D01*
G01X1594988Y561100D01*
Y561098D01*
X1595020Y560444D01*
Y560433D01*
G02X1594888Y560246I-200J1D01*
G01X1594879Y560243D01*
X1594872Y560241D01*
G03X1593796Y558800I427J-1441D01*
G03X1595029Y557319I1506J0D01*
G01X1595030D01*
X1595045Y557316D01*
G02X1595144Y557255I-51J-194D01*
G01X1595167Y557229D01*
X1595179Y557201D01*
G02X1595194Y557143I-184J-79D01*
G01Y557135D01*
X1595207Y556890D01*
X1595208Y556874D01*
X1595225Y556545D01*
G02X1595197Y556433I-200J-10D01*
G01X1595183Y556409D01*
X1595139Y556369D01*
X1595112Y556356D01*
G03X1594329Y555457I649J-1356D01*
G03X1594274Y555222I1430J-459D01*
G03X1594268Y555179I1484J-229D01*
G01Y555176D01*
G03X1594267Y555167I1492J-170D01*
G01X1594259Y555094D01*
G03X1594258Y555072I199J-20D01*
G01Y554999D01*
G03X1594378Y554411I1502J0D01*
G03X1595204Y553603I1384J589D01*
G01X1595230Y553592D01*
X1595233Y553591D01*
X1595249Y553579D01*
G02X1595283Y553546I-121J-159D01*
G01X1595329Y553485D01*
X1595333Y553480D01*
X1595350Y553457D01*
X1595353Y553453D01*
G02X1595391Y553346I-162J-118D01*
G01X1595413Y552936D01*
X1595423Y552743D01*
X1595435Y552507D01*
X1595445Y552312D01*
X1595477Y551703D01*
X1595480Y551640D01*
X1595483Y551591D01*
Y551576D01*
G02X1595459Y551481I-200J0D01*
G01X1595441Y551447D01*
X1595377Y551376D01*
X1595354Y551350D01*
X1595267Y551303D01*
X1595250Y551297D01*
X1595203Y551280D01*
X1595187Y551277D01*
G03X1593980Y550057I273J-1477D01*
G03X1594059Y549257I1481J-258D01*
G03X1594330Y548809I1403J542D01*
G01X1594331Y548808D01*
G02X1594389Y548652I-142J-141D01*
G01X1594385Y548604D01*
Y548602D01*
X1594366Y548352D01*
G02X1594363Y548337I-197J32D01*
G02X1594355Y548313I-193J51D01*
G01X1594326Y548252D01*
X1594294Y548225D01*
G03X1593758Y547075I966J-1150D01*
G03X1595260Y545573I1502J0D01*
G01X1595278D01*
G03X1595363Y545575I7J1503D01*
G01X1595406Y545577D01*
X1595500Y545541D01*
G02X1595559Y545505I-73J-186D01*
G01X1595639Y545436D01*
X1595641Y545434D01*
X1595747Y545341D01*
G02X1595796Y545277I-131J-151D01*
G01X1595813Y545241D01*
X1595815Y545200D01*
X1595889Y543789D01*
X1595941Y542787D01*
X1595974Y542141D01*
G02X1595950Y542036I-200J-10D01*
G02X1595851Y541946I-176J95D01*
G01X1595831Y541940D01*
G03X1595630Y541864I430J-1440D01*
G03X1594758Y540500I631J-1364D01*
G03X1595898Y539042I1502J0D01*
G01X1595922Y539036D01*
X1596004Y538992D01*
X1596027Y538973D01*
X1596045Y538955D01*
X1596102Y538889D01*
G02X1596107Y538883I-151J-131D01*
G01X1596108Y538882D01*
Y538881D01*
G02X1596137Y538833I-155J-126D01*
G02X1596150Y538786I-185J-77D01*
G01X1596165Y538482D01*
X1596206Y537693D01*
X1596233Y537177D01*
X1596245Y536950D01*
X1596348Y534966D01*
X1596520Y531636D01*
G02X1596482Y531527I-200J8D01*
G02X1596385Y531455I-162J117D01*
G01X1596372Y531451D01*
G03X1595258Y530000I388J-1451D01*
G03X1595271Y529800I1502J-3D01*
G03X1596494Y528521I1489J200D01*
G01X1596528Y528515D01*
X1596604Y528473D01*
G02X1596694Y528323I-110J-168D01*
G01X1596695Y528306D01*
Y528304D01*
X1602197Y422599D01*
X1605995Y349626D01*
X1606196Y345765D01*
Y345763D01*
X1606198Y345727D01*
X1606199Y345702D01*
G02X1606157Y345579I-200J0D01*
G01X1605963Y345353D01*
X1605926Y345335D01*
X1605837Y345291D01*
X1605802Y345287D01*
G03X1604464Y343794I164J-1493D01*
G03X1605966Y342292I1502J0D01*
G01X1605996D01*
G02X1606121Y342247I-1J-200D01*
G01X1606180Y342192D01*
X1606331Y342052D01*
X1606338Y342045D01*
G02X1606396Y341914I-142J-141D01*
G01X1606481Y340285D01*
X1606588Y338238D01*
X1606682Y336430D01*
X1606836Y333466D01*
X1606837Y333454D01*
Y333408D01*
X1606825Y333375D01*
X1606795Y333291D01*
X1606774Y333265D01*
G03X1606445Y332323I1174J-939D01*
G01Y332294D01*
G03X1606873Y331276I1502J32D01*
G01X1606899Y331249D01*
X1606946Y331142D01*
G02X1606957Y331105I-186J-75D01*
G01X1606958Y331097D01*
G02X1606960Y331072I-198J-28D01*
G01X1606993Y330452D01*
X1606994Y330429D01*
X1607017Y329995D01*
Y329993D01*
X1607021Y329919D01*
X1607008Y329882D01*
X1606999Y329854D01*
X1606987Y329829D01*
X1606965Y329795D01*
X1606958Y329783D01*
X1606956Y329780D01*
G03X1606738Y329009I1284J-779D01*
G01Y328995D01*
G03X1607060Y328070I1502J4D01*
G01X1607079Y328046D01*
X1607112Y327960D01*
X1607124Y327929D01*
X1610977Y253909D01*
Y253897D01*
X1610948Y245881D01*
G02X1610848Y245708I-200J0D01*
G01X1610700Y245623D01*
X1610601Y245620D01*
X1610586Y245627D01*
G03X1610584Y245628I-673J-1343D01*
G01X1610533Y245653D01*
X1610505Y245666D01*
G03X1610455Y245688I-630J-1364D01*
G01X1610454D01*
X1610444Y245692D01*
G03X1610427Y245699I-580J-1385D01*
G01X1610426D01*
X1610393Y245711D01*
G03X1610379Y245716I-512J-1412D01*
G03X1610262Y245752I-500J-1416D01*
G01X1610246Y245756D01*
G03X1609896Y245799I-357J-1459D01*
G01X1609881D01*
G03X1609538Y245759I1J-1502D01*
G01X1609512Y245753D01*
X1609473Y245749D01*
G02X1609355Y245783I-6J200D01*
G02X1609329Y245804I112J166D01*
G01X1609088Y246084D01*
G02X1609045Y246263I151J131D01*
G01X1609053Y246292D01*
X1609056Y246298D01*
X1609058Y246304D01*
G03X1609169Y246871I-1392J567D01*
G01Y246874D01*
G03X1609164Y246993I-1503J-4D01*
G01X1609162Y247009D01*
Y247013D01*
G03X1607666Y248376I-1496J-139D01*
G03Y245372I0J-1502D01*
G01X1607670D01*
G03X1608014Y245412I0J1502D01*
G01X1608040Y245418D01*
X1608079Y245422D01*
G02X1608197Y245388I6J-200D01*
G02X1608223Y245367I-112J-166D01*
G01X1608384Y245180D01*
X1608464Y245087D01*
G02X1608508Y244914I-151J-131D01*
G01X1608499Y244881D01*
X1608494Y244867D01*
G03X1608383Y244300I1392J-567D01*
G01Y244297D01*
G03X1608388Y244178I1503J4D01*
G01X1608391Y244147D01*
G03X1609866Y242795I1495J150D01*
G01X1609890D01*
G03X1609987Y242798I2J1503D01*
G01X1609989D01*
G03X1610399Y242885I-104J1499D01*
G02X1610563Y242873I69J-188D01*
G02X1610584Y242861I-89J-179D01*
G01X1610740Y242750D01*
X1610857Y242667D01*
G02X1610883Y242644I-119J-161D01*
G01X1610895Y242630D01*
G02X1610936Y242516I-159J-122D01*
G01X1610935Y242317D01*
X1610928Y240152D01*
Y240076D01*
Y240074D01*
X1610935Y239637D01*
G02X1610927Y239578I-200J-3D01*
G01X1610905Y239503D01*
X1610892Y239481D01*
G03X1610687Y238832I1292J-765D01*
G03X1610781Y238180I1497J-117D01*
G03X1610929Y237890I1404J534D01*
G01Y237889D01*
X1610931Y237887D01*
Y237886D01*
G02X1610964Y237784I-167J-110D01*
G01X1610967Y237573D01*
X1611065Y231214D01*
G02X1611055Y231146I-200J-5D01*
G01X1611043Y231112D01*
X1611019Y231084D01*
G03X1610667Y230118I1150J-966D01*
G01Y230117D01*
G03X1610673Y229976I1502J-7D01*
G01X1610677Y229940D01*
G03X1610716Y229733I1494J174D01*
G01X1610752Y229597D01*
G03X1610759Y229575I194J50D01*
G01X1610761Y229570D01*
X1610765Y229564D01*
G03X1610768Y229557I185J75D01*
G01X1610835Y229426D01*
G03X1610841Y229415I1321J714D01*
G01X1610843Y229411D01*
G03X1610859Y229382I1323J711D01*
G01Y229381D01*
G03X1611009Y229161I1312J733D01*
G01X1611011Y229159D01*
X1611017Y229151D01*
X1611019Y229148D01*
G03X1611029Y229138I146J136D01*
G03X1611031Y229136I1063J1061D01*
G03X1611038Y229128I1134J985D01*
G01X1611044Y229122D01*
G03X1611046Y229120I1064J1062D01*
G03X1611048Y229117I1246J828D01*
G03X1611061Y229103I1108J1016D01*
G01X1611075Y229087D01*
X1611101Y229021D01*
X1611104Y228796D01*
X1611265Y218486D01*
Y218476D01*
X1610913Y209500D01*
X1610416Y196798D01*
G02X1610386Y196700I-200J8D01*
G01X1610373Y196679D01*
X1610340Y196648D01*
X1610312Y196631D01*
X1610075Y196501D01*
G02X1610068Y196497I-103J171D01*
G01X1610012Y196469D01*
G02X1609869Y196455I-90J179D01*
G01X1609835Y196465D01*
X1609827Y196469D01*
X1609813Y196478D01*
G03X1609053Y196683I-759J-1304D01*
G01X1609051D01*
G03X1608109Y196353I0J-1509D01*
G01X1608108Y196352D01*
X1608081Y196331D01*
X1608050Y196320D01*
G02X1607982Y196308I-68J188D01*
G01X1607906D01*
G03X1607823Y196290I0J-200D01*
G01X1607783Y196271D01*
G02X1607683Y196254I-82J182D01*
G02X1607627Y196268I20J199D01*
G01X1607602Y196278D01*
G03X1606551Y196699I-1051J-1101D01*
G01X1606550D01*
G03X1605565Y196337I1J-1523D01*
G01X1605535Y196313D01*
X1605513Y196308D01*
X1605406D01*
G03X1605323Y196290I0J-200D01*
G01X1605283Y196271D01*
G02X1605183Y196254I-82J182D01*
G02X1605127Y196268I20J199D01*
G01X1605102Y196278D01*
G03X1604051Y196699I-1051J-1101D01*
G01X1604050D01*
G03X1603065Y196337I1J-1523D01*
G01X1603035Y196313D01*
X1603013Y196308D01*
X1602906D01*
G03X1602823Y196290I0J-200D01*
G01X1602768Y196265D01*
G02X1602551Y196298I-83J181D01*
G01X1602510Y196334D01*
G03X1601553Y196678I-957J-1160D01*
G01X1601551D01*
G03Y193674I0J-1502D01*
G01X1601552D01*
G03X1602483Y193997I0J1504D01*
G01X1602504Y194014D01*
X1602537Y194028D01*
X1602547Y194032D01*
G02X1602614Y194044I68J-188D01*
G01X1602696D01*
G03X1602779Y194062I0J200D01*
G01X1602834Y194087D01*
G02X1602935Y194104I82J-182D01*
G02X1602973Y194097I-17J-199D01*
G01X1603010Y194064D01*
X1603013Y194062D01*
X1603014Y194061D01*
G03X1603019Y194056I144J139D01*
G03X1604051Y193653I1032J1120D01*
G03X1605034Y194014I0J1519D01*
G01X1605054Y194030D01*
X1605063Y194037D01*
G02X1605113Y194044I52J-193D01*
G01X1605196D01*
G03X1605279Y194062I0J200D01*
G01X1605334Y194087D01*
G02X1605435Y194104I82J-182D01*
G02X1605473Y194097I-17J-199D01*
G01X1605510Y194064D01*
X1605513Y194062D01*
X1605514Y194061D01*
G03X1605519Y194056I144J139D01*
G03X1606551Y193653I1032J1120D01*
G03X1607534Y194014I0J1519D01*
G01X1607554Y194030D01*
X1607563Y194037D01*
G02X1607613Y194044I52J-193D01*
G01X1607698D01*
G03X1607738Y194048I0J200D01*
G01X1607762Y194053D01*
X1607971D01*
G02X1608039Y194041I0J-200D01*
G01X1608070Y194030D01*
X1608075Y194026D01*
X1608097Y194008D01*
G03X1609050Y193669I952J1168D01*
G01X1609053D01*
G03X1609708Y193819I0J1507D01*
G01X1609728Y193829D01*
X1609755Y193836D01*
G02X1609911Y193809I47J-195D01*
G01X1610065Y193709D01*
X1610067D01*
X1610171Y193640D01*
X1610181Y193633D01*
G02X1610261Y193474I-120J-160D01*
G01Y192852D01*
Y192844D01*
X1609933Y184460D01*
Y184450D01*
X1606246Y157164D01*
G03X1606211Y156699I3891J-527D01*
G01X1606190Y155394D01*
X1606180Y155350D01*
X1606170Y155331D01*
G03X1605763Y153648I3519J-1742D01*
G01X1605737Y151975D01*
Y151974D01*
G03X1605732Y151780I3862J-197D01*
G01Y151777D01*
G03X1605733Y151697I3892J9D01*
G01Y151687D01*
G03X1605732Y151638I3925J-105D01*
G01Y151636D01*
G03X1605745Y151321I3926J4D01*
G03X1605850Y150682I3914J315D01*
G01X1605854Y150666D01*
X1605836Y150555D01*
X1605828Y150504D01*
X1605792Y150284D01*
G03X1605769Y150120I3841J-622D01*
G03X1605742Y149658I3864J-458D01*
G01Y149573D01*
G03Y149570I200J-2D01*
G01X1605743Y149534D01*
X1605740Y149515D01*
G03X1605690Y148948I3876J-628D01*
G01X1605660Y147001D01*
Y146937D01*
G03Y146935I3926J-1D01*
G03X1605808Y145867I3926J0D01*
G01X1605812Y145854D01*
Y145853D01*
X1605819Y145828D01*
X1605822Y145711D01*
Y145709D01*
X1605825Y145557D01*
G02X1605817Y145497I-200J-4D01*
G01X1605811Y145482D01*
Y145481D01*
X1605808Y145473D01*
G03X1605796Y145446I3550J-1594D01*
G01X1605795Y145445D01*
G03X1605790Y145432I3626J-1402D01*
G01X1605778Y145402D01*
X1605695Y145308D01*
X1605663Y145286D01*
X1605585Y145247D01*
G02X1605496Y145226I-89J179D01*
G01X1605439D01*
X1605420Y145230D01*
G03X1605416Y145231I-366J-1457D01*
G01X1605410Y145233D01*
G03X1605294Y145252I-301J-1472D01*
G01X1605290D01*
G03X1605128Y145264I-192J-1490D01*
G01X1605103D01*
G03X1603601Y143762I0J-1502D01*
G03X1605102Y142260I1502J0D01*
G01X1605156D01*
G02X1605289Y142209I0J-200D01*
G01X1605301Y142199D01*
X1605303Y142197D01*
X1605493Y142026D01*
G02X1605539Y141965I-134J-149D01*
G01X1605556Y141930D01*
X1605559Y141892D01*
G03X1605561Y141870I3876J341D01*
G01X1605562Y141859D01*
X1605563Y141855D01*
X1605564Y141841D01*
G03X1605570Y141787I3871J403D01*
G01X1605571Y141782D01*
Y141780D01*
G03X1605694Y141166I3865J455D01*
G03X1605720Y141079I3741J1071D01*
G01Y141077D01*
G03X1605815Y140810I3712J1170D01*
G03X1605886Y140642I3619J1430D01*
G01X1605897Y140605D01*
G02X1605898Y140602I-187J-64D01*
G01X1605908Y140557D01*
X1605896Y140511D01*
X1605864Y140389D01*
X1605851Y140340D01*
X1605797Y140138D01*
X1605785Y140093D01*
X1605753Y139978D01*
G02X1605701Y139894I-191J60D01*
G01X1605669Y139869D01*
X1605543Y139792D01*
X1605541D01*
X1605426Y139723D01*
G02X1605393Y139707I-103J171D01*
G01X1605318Y139726D01*
G03X1604394Y139842I-948J-3811D01*
G01X1604343D01*
G03X1602268Y139230I30J-3927D01*
G03X1602251Y139233I-270J-1478D01*
G01X1602243Y139235D01*
G03X1601985Y139259I-268J-1478D01*
G01X1601972D01*
G03X1600470Y137772I0J-1502D01*
G01Y137756D01*
G03X1600606Y137132I1502J1D01*
G01X1600615Y137112D01*
X1600622Y137080D01*
G03X1600547Y136803I3750J-1164D01*
G03X1600515Y136652I3824J-889D01*
G03X1600446Y135915I3857J-733D01*
G03X1600798Y134289I3928J-1D01*
G02Y134141I-186J-74D01*
G03X1600446Y132515I3576J-1625D01*
G01Y132511D01*
G03X1600622Y131351I3926J2D01*
G01X1600618Y131333D01*
X1600604Y131292D01*
G03X1600589Y131258I1367J-623D01*
G01Y131257D01*
X1600581Y131236D01*
G03X1600538Y131119I1387J-576D01*
G01Y131118D01*
G03X1600534Y131107I1409J-519D01*
G03X1600532Y131099I193J-52D01*
G01X1600531Y131096D01*
Y131095D01*
G03X1600477Y130819I1441J-425D01*
G03X1600470Y130700I1495J-148D01*
G01Y130663D01*
G03X1601972Y129168I1502J7D01*
G01X1601990D01*
G03X1602242Y129192I-16J1502D01*
G01X1602271Y129197D01*
G03X1604339Y128588I2101J3318D01*
G01X1604387D01*
G03X1606473Y129198I-16J3927D01*
G01X1606498Y129193D01*
G03X1606509Y129191I274J1477D01*
G01X1606511D01*
G03X1606534Y129187I269J1478D01*
G03X1606542Y129185I52J192D01*
G03X1606558Y129183I194J1490D01*
G01X1606562D01*
G03X1606785Y129167I219J1486D01*
G01X1606792D01*
G03X1606938Y129176I-19J1504D01*
G03X1607231Y129238I-163J1493D01*
G01X1607233D01*
X1607235Y129239D01*
G03X1607244Y129242I-471J1428D01*
G01X1607263Y129248D01*
X1607302Y129253D01*
G02X1607428Y129221I16J-199D01*
G01X1607583Y129110D01*
X1607585D01*
X1607700Y129026D01*
Y129025D01*
G02X1607748Y128974I-119J-160D01*
G01X1607746Y128902D01*
Y128828D01*
G03X1608098Y127202I3928J-1D01*
G02Y127054I-186J-74D01*
G03X1607746Y125428I3576J-1625D01*
G03X1607748Y125284I3926J-17D01*
G03X1607751Y125212I3924J127D01*
G01X1607755Y125133D01*
X1607728Y125101D01*
X1607659Y125019D01*
X1607624Y125001D01*
X1607588Y124982D01*
X1607530Y124953D01*
X1607494Y124949D01*
X1607455Y124944D01*
X1607371Y124962D01*
X1607360Y124966D01*
X1607352Y124970D01*
G03X1606784Y125086I-579J-1386D01*
G01X1606770D01*
G03X1606515Y125064I1J-1502D01*
G01X1606476Y125057D01*
G03X1604372Y125668I-2103J-3315D01*
G01X1604335Y125669D01*
G03X1602360Y125114I38J-3927D01*
G01X1602346Y125105D01*
G02X1602260Y125086I-85J181D01*
G01X1601972D01*
G03X1600470Y123593I0J-1502D01*
G01Y123582D01*
G03X1600615Y122937I1503J-1D01*
G01X1600622Y122908D01*
G03X1600446Y121759I3751J-1162D01*
G01Y121742D01*
G03X1600798Y120116I3928J-1D01*
G02Y119968I-186J-74D01*
G03X1600446Y118342I3576J-1625D01*
G01Y118340D01*
G03X1600623Y117176I3926J2D01*
G01X1600616Y117146D01*
X1600607Y117127D01*
G03X1600470Y116500I1365J-627D01*
G01Y116497D01*
G03X1601972Y114995I1502J0D01*
G01X1601976D01*
G03X1602240Y115018I2J1502D01*
G01X1602272Y115024D01*
G03X1604372Y114415I2100J3318D01*
G01X1604373D01*
G03X1606473Y115024I-1J3927D01*
G01X1606477Y115023D01*
X1606497Y115019D01*
X1606504Y115018D01*
G03X1606772Y114995I262J1479D01*
G01X1606775D01*
G03X1607216Y115062I-3J1502D01*
G01X1607245Y115071D01*
X1607336D01*
G02X1607423Y115050I-2J-200D01*
G01X1607428Y115048D01*
G03X1607433Y115045I105J170D01*
G01X1607438Y115042D01*
X1607447Y115037D01*
X1607531Y114975D01*
X1607534Y114973D01*
X1607625Y114907D01*
X1607693Y114858D01*
X1607701Y114852D01*
G02X1607705Y114849I-118J-162D01*
G02X1607748Y114801I-125J-156D01*
G01X1607746Y114714D01*
Y114655D01*
G03X1608098Y113029I3928J-1D01*
G02Y112881I-186J-74D01*
G03X1607746Y111255I3576J-1625D01*
G03X1607815Y110517I3926J-5D01*
G03X1607882Y110228I3856J742D01*
G03X1607922Y110090I3790J1024D01*
G01Y110089D01*
X1607915Y110056D01*
G03X1607906Y110036I1365J-626D01*
G01X1607905Y110034D01*
G03X1607770Y109430I1367J-623D01*
G01Y109409D01*
G03X1609272Y107908I1502J1D01*
G01X1609277D01*
G03X1609502Y107925I0J1502D01*
G02X1609635Y107898I29J-198D01*
G03X1609776Y107816I2044J3353D01*
G01X1609778D01*
X1609827Y107788D01*
X1609842Y107751D01*
X1609920Y107462D01*
X1609919Y107408D01*
X1609912Y107382D01*
X1609895Y107321D01*
X1609883Y107300D01*
G03X1609689Y106562I1308J-738D01*
G01Y106526D01*
X1609690Y106512D01*
Y106508D01*
G03X1609696Y106418I1501J55D01*
G03X1609863Y105859I1495J142D01*
G01X1609871Y105843D01*
G03X1609875Y105836I175J96D01*
G02X1609879Y105829I-172J-103D01*
G01Y105828D01*
G03X1609999Y105646I1311J734D01*
G03X1610001Y105644I141J139D01*
G03X1610040Y105597I1175J935D01*
G02X1610044Y105591I-164J-114D01*
G03X1610051Y105582I1189J918D01*
G03X1610057Y105576I144J138D01*
G03X1610113Y105515I1134J985D01*
G03X1610224Y105411I1081J1043D01*
G01X1610225Y105410D01*
X1610239Y105399D01*
G03X1610252Y105388I977J1141D01*
G03X1610256Y105385I903J1199D01*
G01X1610265Y105378D01*
X1610273Y105370D01*
X1610283Y105362D01*
X1610302Y105343D01*
X1610322Y105319D01*
X1610323Y105318D01*
X1610325Y105315D01*
G02X1610369Y105196I-156J-125D01*
G01Y105180D01*
X1610351Y104846D01*
G02X1610323Y104764I-199J22D01*
G01X1610311Y104745D01*
X1610280Y104712D01*
X1610255Y104697D01*
G03X1609530Y103411I778J-1286D01*
G03X1612534I1502J0D01*
G03X1611957Y104594I-1501J0D01*
G01X1611955Y104596D01*
X1611938Y104610D01*
X1611907Y104647D01*
X1611905Y104650D01*
G02X1611854Y104798I149J134D01*
G01X1611858Y104873D01*
Y104875D01*
X1611872Y105148D01*
X1611890Y105187D01*
X1611910Y105225D01*
X1611948Y105262D01*
X1611966Y105274D01*
X1611974Y105279D01*
X1611981Y105283D01*
X1611991Y105289D01*
G03X1612693Y106555I-800J1271D01*
G01Y106577D01*
G03X1612674Y106803I-1502J-12D01*
G01X1612668Y106836D01*
G03X1612614Y107043I-1477J-275D01*
G02X1612611Y107162I189J64D01*
G01X1612613Y107169D01*
G02X1612619Y107186I191J-58D01*
G02X1612623Y107195I185J-77D01*
G01X1612631Y107211D01*
X1612719Y107386D01*
X1612734Y107415D01*
X1612758Y107463D01*
X1612773Y107485D01*
X1612774Y107486D01*
X1612849Y107509D01*
G03X1613420Y107739I-1177J3746D01*
G03X1613692Y107888I-1749J3515D01*
G02X1613791Y107917I104J-171D01*
G02X1613818Y107916I6J-200D01*
G03X1613971Y107907I165J1494D01*
G01X1613973D01*
G03X1614048Y107909I-3J1503D01*
G01X1614086Y107912D01*
G03X1615175Y108510I-114J1498D01*
G01X1615183Y108520D01*
G03X1617358Y109624I-602J3880D01*
G01X1622878Y115143D01*
X1622890Y115149D01*
G03X1622902Y115155I-666J1347D01*
G01X1622906Y115157D01*
G03X1623563Y115814I-682J1339D01*
G01X1623565Y115818D01*
G03X1623571Y115830I-1341J678D01*
G01X1623577Y115842D01*
X1624047Y116312D01*
X1628771Y121037D01*
G03X1629134Y121454I-2773J2780D01*
G03X1629358Y121785I-3136J2363D01*
G01X1629362Y121792D01*
X1629386Y121825D01*
G03X1629595Y122072I-2864J2635D01*
G03X1629791Y122346I-3064J2399D01*
G03X1629856Y122450I-3267J2114D01*
G01X1629860Y122458D01*
X1629866Y122467D01*
G03X1629890Y122507I-3325J2022D01*
G03X1629922Y122562I-3348J1985D01*
G01Y122563D01*
X1629946Y122607D01*
X1629950Y122615D01*
G03X1630122Y122977I-3424J1849D01*
G01X1632507Y128735D01*
X1632679Y129148D01*
Y129150D01*
X1632733Y129276D01*
G02X1632761Y129317I178J-91D01*
G01X1632781Y129340D01*
X1632813Y129358D01*
G03X1633584Y130670I-731J1312D01*
G03X1633531Y131073I-1503J7D01*
G01X1633526Y131091D01*
X1633523Y131126D01*
Y131129D01*
X1633519Y131176D01*
X1633948Y132211D01*
X1635562Y136109D01*
X1639670Y146026D01*
G03X1639854Y146590I-3596J1485D01*
G01X1639857Y146601D01*
G02X1639860Y146611I193J-52D01*
G01X1639895Y146693D01*
Y146695D01*
X1639941Y146805D01*
X1639942D01*
X1639962Y146853D01*
Y146855D01*
G03X1640270Y148378I-3618J1524D01*
G01Y148443D01*
Y148447D01*
X1640193Y153088D01*
X1640173Y154276D01*
G03X1640090Y155016I-3926J-66D01*
G01X1639902Y155915D01*
X1638951Y160457D01*
G02X1638955Y160556I196J42D01*
G02X1639002Y160636I192J-59D01*
G01X1639260Y160877D01*
G02X1639262Y160879I142J-140D01*
G02X1639452Y160923I134J-148D01*
G03X1639862Y160866I410J1446D01*
G03X1640889Y161272I0J1502D01*
G01X1640890Y161273D01*
G02X1640961Y161315I135J-147D01*
G02X1641026Y161326I65J-189D01*
G01X1641298D01*
G02X1641363Y161315I0J-200D01*
G02X1641434Y161273I-64J-189D01*
G01X1641435Y161272D01*
G03X1642462Y160866I1027J1096D01*
G03Y163870I0J1502D01*
G03X1641435Y163464I0J-1502D01*
G01X1641434Y163463D01*
G02X1641363Y163421I-135J147D01*
G02X1641298Y163410I-65J189D01*
G01X1641026D01*
G02X1640961Y163421I0J200D01*
G02X1640890Y163463I64J189D01*
G01X1640889Y163464D01*
G03X1639862Y163870I-1027J-1096D01*
G03X1638931Y163547I0J-1503D01*
G01X1638905Y163526D01*
X1638778Y163481D01*
G02X1638721Y163489I-1J200D01*
G01X1638563Y163545D01*
X1638390Y163606D01*
G02X1638261Y163753I67J188D01*
G01X1637067Y169453D01*
X1636437Y172464D01*
X1634558Y181439D01*
X1632206Y192670D01*
G02X1632202Y192709I196J40D01*
G01X1632053Y207290D01*
X1632062Y207309D01*
G03X1632219Y207974I-1345J669D01*
G03Y207981I-1502J4D01*
G01Y208000D01*
G03X1632211Y208136I-1502J-20D01*
G03X1632060Y208653I-1494J-156D01*
G01X1632049Y208675D01*
X1632039Y208717D01*
X1632035Y209056D01*
Y209092D01*
X1632028Y209742D01*
X1632038Y209761D01*
G03X1632220Y210478I-1321J717D01*
G01Y210480D01*
G03X1632037Y211197I-1503J-2D01*
G01X1632036Y211199D01*
G02X1632013Y211278I176J94D01*
G01X1632004Y212075D01*
G02X1632011Y212130I200J2D01*
G01X1632018Y212154D01*
X1632034Y212179D01*
G03X1632257Y212978I-1317J798D01*
G01Y212980D01*
G03X1632028Y213788I-1542J-1D01*
G01X1632017Y213806D01*
X1631994Y213879D01*
G02X1631986Y213936I192J56D01*
G01X1631978Y214649D01*
Y214656D01*
X1631995Y214685D01*
X1631997Y214688D01*
G03X1632220Y215477I-1281J788D01*
G01Y215479D01*
G03X1632216Y215596I-1503J7D01*
G01X1632209Y215655D01*
G03X1631981Y216290I-1493J-178D01*
G01X1631961Y216322D01*
X1631934Y218986D01*
Y222782D01*
G02X1631968Y222893I200J0D01*
G03X1632219Y223689I-1251J832D01*
G01Y223780D01*
G03X1631916Y224632I-1502J-54D01*
G01X1631915Y224634D01*
G02X1631875Y224743I160J120D01*
G01Y224791D01*
X1631871Y225179D01*
Y225194D01*
X1631912Y225316D01*
G03X1631935Y225346I-1180J929D01*
G01X1631938Y225349D01*
G03X1632099Y225637I-1223J873D01*
G03X1632220Y226226I-1382J591D01*
G01X1632219Y226274D01*
G03X1631916Y227132I-1502J-48D01*
G01X1631889Y227168D01*
G02X1631850Y227274I161J119D01*
G01X1631847Y227543D01*
X1631845Y227695D01*
X1631868Y227761D01*
X1631891Y227788D01*
G03X1631912Y227814I-1158J957D01*
G01Y227816D01*
G03X1631936Y227847I-1175J935D01*
G03X1631938Y227849I-139J141D01*
G03X1632099Y228137I-1223J873D01*
G03X1632220Y228726I-1382J591D01*
G01X1632219Y228773D01*
G03X1631870Y229690I-1502J-47D01*
G01X1631837Y229730D01*
G02X1631830Y229741I165J113D01*
G03X1631826Y229747I-168J-108D01*
G02X1631824Y229750I165J112D01*
G01Y229765D01*
X1631823Y229893D01*
X1631820Y230195D01*
X1631837Y230222D01*
X1631862Y230253D01*
G03X1631921Y230327I-1145J973D01*
G01X1631923Y230329D01*
G03X1632220Y231226I-1206J897D01*
G03X1631825Y232241I-1502J0D01*
G01X1631798Y232272D01*
X1631574Y254265D01*
Y269165D01*
G03X1631569Y269367I-3891J5D01*
G01X1631275Y275027D01*
X1631262Y275271D01*
X1630732Y285463D01*
X1628561Y327253D01*
G02X1628627Y327400I200J-1D01*
G01X1628935Y327639D01*
X1628985Y327647D01*
X1629019Y327653D01*
X1629069Y327644D01*
X1629090Y327637D01*
G03X1629550Y327565I460J1430D01*
G01X1629553D01*
G03X1631055Y329067I0J1502D01*
G03X1630611Y330133I-1502J0D01*
G01X1630610Y330134D01*
G02X1630552Y330272I142J141D01*
G01X1630548Y330545D01*
Y330551D01*
G02X1630581Y330658I200J-3D01*
G01X1630605Y330693D01*
X1630616Y330705D01*
G03X1631016Y331725I-1104J1021D01*
G01Y331728D01*
G03X1630811Y332485I-1502J0D01*
G03X1630527Y332837I-1298J-757D01*
G01X1630514Y332849D01*
X1630487Y332884D01*
G02X1630466Y332917I158J123D01*
G01X1630441Y332966D01*
G02X1630420Y333040I178J91D01*
G01X1630418Y333063D01*
X1630400Y333289D01*
G02X1630431Y333408I200J12D01*
G01X1630454Y333438D01*
G03X1630804Y334402I-1153J964D01*
G03X1629302Y335904I-1502J0D01*
G01X1629291D01*
G03X1629289I-1J-1504D01*
G01X1629288D01*
G03X1628687Y335779I-1J-1504D01*
G01X1628649Y335762D01*
X1628477D01*
X1628448Y335791D01*
X1628447D01*
X1628377Y335833D01*
X1628375D01*
X1628178Y335953D01*
G02X1628121Y336016I117J163D01*
G02X1628097Y336090I175J98D01*
G01X1628084Y336336D01*
X1628022Y337535D01*
X1627986Y338227D01*
X1627679Y344123D01*
X1627370Y350064D01*
X1627369Y350101D01*
X1627396Y350185D01*
G02X1627413Y350223I190J-62D01*
G01X1627435Y350259D01*
X1627445Y350276D01*
G03X1627650Y351033I-1297J757D01*
G01Y351045D01*
X1627648Y351103D01*
G03X1627636Y351233I-1501J-73D01*
G03X1627328Y351963I-1490J-199D01*
G01X1627308Y351988D01*
X1627264Y352101D01*
X1627262Y352134D01*
X1626874Y359596D01*
X1626739Y362189D01*
X1626693Y363069D01*
X1626663Y363637D01*
X1622646Y440810D01*
Y441303D01*
G02X1622743Y441474I200J0D01*
G01X1622802Y441510D01*
X1622805Y441513D01*
X1623020Y441645D01*
G02X1623174Y441663I98J-174D01*
G01X1623207Y441652D01*
X1623224Y441643D01*
X1623232Y441639D01*
G03X1623238Y441636I675J1342D01*
G01X1623239Y441635D01*
G03X1623469Y441534I717J1320D01*
G03X1623625Y441490I485J1421D01*
G01X1623641Y441486D01*
G03X1623948Y441454I308J1470D01*
G01X1623971D01*
G03X1625457Y442956I-16J1502D01*
G03X1623955Y444458I-1502J0D01*
G03X1623098Y444190I0J-1504D01*
G01X1623095Y444188D01*
X1623087Y444183D01*
X1623047Y444161D01*
G02X1622980Y444146I-77J185D01*
G02X1622889Y444163I-10J200D01*
G01X1622807Y444202D01*
X1622805D01*
X1622586Y444309D01*
X1622585Y444310D01*
X1622580Y444311D01*
G02X1622522Y444348I77J185D01*
G03X1622520Y444350I-142J-140D01*
G02X1622492Y444381I134J149D01*
G01X1622477Y444403D01*
X1622468Y444428D01*
G02X1622456Y444480I187J71D01*
G01X1622248Y448475D01*
X1622199Y449419D01*
X1621979Y453643D01*
X1621973Y453758D01*
X1621965Y453908D01*
X1621952Y454156D01*
X1621921Y454755D01*
Y454767D01*
G02X1622049Y454953I200J-1D01*
G01X1622060Y454956D01*
G03X1622067Y454959I-588J1381D01*
G01X1622080Y454963D01*
G03X1622086Y454965I-472J1427D01*
G01X1622098Y454969D01*
G03X1623098Y456386I-504J1417D01*
G03X1621910Y457855I-1502J0D01*
G01X1621908D01*
X1621907Y457856D01*
G02X1621797Y457921I41J196D01*
G01X1621776Y457946D01*
X1621764Y457975D01*
G02X1621750Y458033I186J75D01*
G01X1621638Y460194D01*
X1621501Y462841D01*
X1621407Y464642D01*
Y464645D01*
X1621405Y464689D01*
X1621416Y464716D01*
X1621450Y464767D01*
G02X1621474Y464796I165J-112D01*
G03X1621917Y465873I-1088J1077D01*
G01Y465874D01*
G03X1621347Y467066I-1531J0D01*
G01X1621287Y467115D01*
G02X1621276Y467160I187J70D01*
G01X1621249Y467673D01*
X1621221Y468211D01*
X1621188Y468844D01*
X1620724Y477762D01*
X1620464Y482755D01*
X1620308Y485742D01*
X1617683Y536175D01*
X1617563Y538492D01*
X1617471Y540259D01*
X1617422Y541203D01*
X1617419Y541260D01*
X1617418Y541272D01*
Y541299D01*
G02X1617439Y541376I200J-13D01*
G01X1617473Y541442D01*
G02X1617509Y541491I177J-93D01*
G01X1617530Y541512D01*
G03X1618124Y542675I-910J1198D01*
G01Y542710D01*
G03X1617368Y544017I-1503J3D01*
G01X1617342Y544032D01*
X1617326Y544049D01*
G02X1617298Y544084I141J142D01*
G01X1617279Y544120D01*
X1617268Y544159D01*
X1617265Y544219D01*
Y544221D01*
X1617254Y544427D01*
X1617249Y544525D01*
X1617241Y544675D01*
X1617225Y544984D01*
Y544990D01*
X1617221Y545065D01*
X1617220Y545078D01*
Y545086D01*
X1617219Y545100D01*
X1617217Y545146D01*
G02X1617248Y545260I200J7D01*
G01X1617252Y545268D01*
X1617297Y545343D01*
G02X1617358Y545401I165J-113D01*
G01X1617384Y545416D01*
G03X1617387Y545418I-109J167D01*
G01X1617397Y545425D01*
X1617403Y545429D01*
G03X1617953Y546016I-781J1283D01*
G03X1617216Y548092I-1331J696D01*
G01X1617178Y548108D01*
X1617099Y548191D01*
G02X1617077Y548223I153J129D01*
G02X1617055Y548292I176J94D01*
G01X1616695Y555168D01*
X1615369Y580641D01*
X1615327Y581451D01*
X1614513Y597096D01*
X1614130Y604466D01*
X1613913Y608632D01*
X1613856Y609724D01*
X1613674Y613226D01*
X1613571Y615206D01*
X1613510Y616371D01*
X1613509Y616394D01*
X1613505Y616466D01*
Y616486D01*
G02X1613581Y616642I200J-1D01*
G01X1613594Y616652D01*
X1613846Y616840D01*
X1613863Y616848D01*
X1613869Y616851D01*
G02X1613958Y616872I89J-179D01*
G01X1614036D01*
X1614067Y616862D01*
G03X1614538Y616786I472J1426D01*
G03X1616040Y618288I0J1502D01*
G03X1614575Y619790I-1502J0D01*
G01X1614541D01*
G03X1613913Y619654I-3J-1502D01*
G01X1613894Y619645D01*
X1613840Y619633D01*
G02X1613711Y619652I-37J196D01*
G01X1613525Y619761D01*
X1613523D01*
X1613408Y619830D01*
G02X1613326Y619954I114J164D01*
G01X1613323Y619973D01*
X1612875Y628570D01*
X1612424Y637236D01*
X1611825Y648751D01*
X1611435Y656238D01*
X1609984Y684129D01*
G02X1610078Y684302I200J3D01*
G01X1610333Y684461D01*
G02X1610438Y684491I105J-170D01*
G01X1610543D01*
X1610576Y684483D01*
X1610605Y684468D01*
G03X1611300Y684298I695J1335D01*
G03X1611302I1J1504D01*
G03X1611304I1J1504D01*
G03X1611306I1J1504D01*
G01X1611332D01*
G03X1612818Y685800I-16J1502D01*
G03X1611316Y687302I-1502J0D01*
G01X1611315D01*
G03X1610452Y687029I1J-1502D01*
G01X1610441Y687021D01*
X1610417Y687008D01*
G02X1610253Y687004I-86J180D01*
G01X1610145Y687056D01*
X1609985Y687134D01*
X1609969Y687142D01*
X1609936Y687158D01*
X1609926Y687164D01*
X1609900Y687178D01*
X1609875Y687203D01*
G02X1609817Y687334I142J141D01*
G01X1608840Y706101D01*
X1606301Y754871D01*
X1605837Y763793D01*
X1604087Y797404D01*
X1600194Y872210D01*
Y872217D01*
G02X1600593Y872625I400J8D01*
G01X1616755D01*
X1616764D01*
G02X1616952Y872459I-9J-200D01*
G01X1629049Y803003D01*
G02X1628970Y802808I-197J-34D01*
G01X1628933Y802780D01*
X1628929Y802777D01*
G02X1628863Y802745I-119J161D01*
G01X1628829Y802736D01*
X1628752Y802744D01*
X1628718Y802761D01*
G03X1628574Y802826I-689J-1335D01*
G03X1628045Y802929I-547J-1399D01*
G01X1628018D01*
G03X1626525Y801427I9J-1502D01*
G03X1628027Y799925I1502J0D01*
G03X1629126Y800403I0J1502D01*
G02X1629187Y800448I147J-136D01*
G01X1629190Y800449D01*
G02X1629192Y800450I90J-178D01*
G01X1629202Y800455D01*
G02X1629221Y800461I70J-188D01*
G02X1629324I52J-194D01*
G01X1629435Y800427D01*
X1629438Y800426D01*
X1629475Y800384D01*
G02X1629522Y800286I-150J-132D01*
G01X1630011Y797477D01*
X1630623Y793961D01*
X1631125Y791082D01*
X1631508Y788882D01*
G02X1631413Y788676I-197J-34D01*
G01X1631245Y788577D01*
X1631090Y788485D01*
G02X1630973Y788458I-101J172D01*
G01X1630944Y788460D01*
X1630889Y788481D01*
X1630864Y788501D01*
G03X1629927Y788829I-937J-1174D01*
G03Y785825I0J-1502D01*
G03X1631206Y786539I0J1503D01*
G01X1631214Y786552D01*
G02X1631334Y786631I163J-117D01*
G01X1631414D01*
X1631598Y786596D01*
X1631782Y786560D01*
G02X1631939Y786409I-38J-197D01*
G01X1662589Y610412D01*
X1662584Y610405D01*
X1662516Y610337D01*
G03X1662572Y608154I1061J-1065D01*
G03X1662939Y607909I1009J1114D01*
G01X1663001Y607880D01*
X1663032Y607861D01*
X1663034Y607859D01*
X1663045Y607796D01*
X1663154Y607169D01*
X1663155Y607168D01*
X1663156Y607160D01*
G02X1663157Y607155I-195J-42D01*
G01X1665675Y587580D01*
X1667883Y570416D01*
X1668193Y568008D01*
G02X1668195Y567984I-198J-29D01*
G01X1668242Y563030D01*
X1668259Y561260D01*
X1668276Y559448D01*
X1668498Y535936D01*
X1668974Y485503D01*
X1669212Y460244D01*
G03X1669239Y459816I3891J31D01*
G03X1669287Y459517I3864J467D01*
G01X1677143Y420252D01*
G02X1677115Y420124I-198J-24D01*
G01X1677092Y420092D01*
X1677066Y420066D01*
X1677053Y420056D01*
G03X1676431Y418838I882J-1218D01*
G03X1677575Y417378I1504J0D01*
G01X1677603Y417371D01*
X1677657Y417340D01*
G02X1677727Y417274I-98J-174D01*
G02X1677752Y417215I-169J-107D01*
G01X1677754Y417205D01*
X1678290Y414531D01*
X1678413Y413915D01*
X1678661Y412677D01*
X1678726Y412351D01*
X1679106Y410452D01*
X1679094Y410407D01*
X1679091Y410394D01*
X1679082Y410366D01*
G03X1679079Y410356I1437J-437D01*
G01X1679078Y410352D01*
X1679074Y410340D01*
G03X1679015Y409924I1444J-417D01*
G01Y409922D01*
G03X1679382Y408939I1503J1D01*
G01X1679403Y408915D01*
X1679422Y408875D01*
X1679425Y408860D01*
X1679426Y408858D01*
X1679428Y408844D01*
X1679435Y408807D01*
X1679725Y407347D01*
G02X1679698Y407209I-197J-33D01*
G01X1679672Y407174D01*
X1679645Y407147D01*
X1679632Y407138D01*
G03X1679016Y405924I888J-1214D01*
G03X1680155Y404466I1503J0D01*
G01X1680177Y404461D01*
X1680184Y404459D01*
X1680210Y404454D01*
X1680260Y404427D01*
X1680283Y404404D01*
G02X1680337Y404303I-142J-141D01*
G01X1680345Y404262D01*
Y404261D01*
X1680526Y403357D01*
X1680623Y402871D01*
X1681226Y399852D01*
G02X1681220Y399768I-198J-28D01*
G01X1681206Y399724D01*
X1681172Y399688D01*
G02X1681170Y399686I-142J140D01*
G01X1681011Y399522D01*
X1680939Y399448D01*
G02X1680782Y399391I-141J142D01*
G01X1680778D01*
X1680766Y399393D01*
G03X1680534Y399414I-251J-1481D01*
G01X1680523D01*
G03X1680521I-1J-1502D01*
G01X1680518D01*
G03X1679016Y397912I0J-1502D01*
G03X1680342Y396420I1502J0D01*
G01X1680426Y396410D01*
G03X1680446Y396409I20J199D01*
G01X1680518D01*
G03X1681147Y396548I-2J1503D01*
G03X1681305Y396632I-625J1366D01*
G01X1681312Y396636D01*
X1681348Y396654D01*
G02X1681386Y396666I79J-184D01*
G02X1681496Y396657I39J-196D01*
G01X1681716Y396562D01*
X1681718D01*
X1681792Y396529D01*
G02X1681821Y396513I-82J-183D01*
G01X1681859Y396488D01*
G02X1681918Y396391I-134J-148D01*
G01X1682284Y394572D01*
X1687006Y370977D01*
X1688711Y362458D01*
X1688982Y361103D01*
X1689714Y357447D01*
X1689726Y357387D01*
X1689717Y357346D01*
G03X1689705Y357290I1462J-343D01*
G03X1689694Y357227I1474J-290D01*
G01Y357223D01*
X1689692Y357210D01*
G03X1689690Y357194I1490J-194D01*
G01Y357192D01*
X1689684Y357141D01*
G03X1689686Y356869I1498J-125D01*
G01X1689688Y356850D01*
Y356849D01*
X1689691Y356825D01*
X1689950Y354846D01*
G02X1689922Y354716I-198J-25D01*
G01X1689872Y354666D01*
G02X1689838Y354639I-141J142D01*
G01X1689780Y354603D01*
G02X1689623Y354588I-96J176D01*
G01X1689600Y354597D01*
G02X1689547Y354631I80J183D01*
G01X1689540Y354637D01*
G03X1688594Y354972I-946J-1167D01*
G01X1688589D01*
G03X1688503Y354970I-8J-1502D01*
G01X1688485Y354969D01*
G03X1687091Y353470I109J-1499D01*
G03X1688593Y351968I1502J0D01*
G03X1689911Y352749I0J1503D01*
G01X1689927Y352778D01*
G02X1690128Y352879I175J-97D01*
G01X1690179Y352872D01*
X1690180D01*
X1690232Y352865D01*
X1690319Y352850D01*
G02X1690357Y352836I-50J-194D01*
G01X1690390Y352814D01*
G02X1690418Y352789I-118J-161D01*
G01X1690430Y352776D01*
X1690442Y352755D01*
G03X1690510Y352647I1304J746D01*
G03X1690653Y352471I1234J857D01*
G01X1690654Y352470D01*
X1690664Y352459D01*
X1690692Y352420D01*
X1690699Y352408D01*
X1690724Y352362D01*
G02X1690739Y352321I-179J-89D01*
G01X1690938Y351329D01*
X1691000Y351021D01*
X1691335Y349345D01*
Y349343D01*
X1691390Y349060D01*
G02X1691392Y349033I-198J-28D01*
G01Y348963D01*
G02X1691361Y348856I-200J0D01*
G03X1691115Y348015I1315J-841D01*
G03X1691803Y346721I1561J0D01*
G01X1691835Y346699D01*
X1691856Y346668D01*
G02X1691886Y346596I-166J-111D01*
G01X1693094Y340559D01*
X1694297Y334546D01*
X1694961Y331227D01*
X1695166Y330200D01*
X1703355Y288929D01*
X1703343Y288911D01*
X1703316Y288870D01*
G02X1703296Y288847I-160J119D01*
G01X1703291Y288842D01*
G02X1703289Y288840I-142J140D01*
G03X1703286Y288837I140J-143D01*
G02X1703276Y288828I-139J144D01*
G01X1703229Y288793D01*
X1703222Y288788D01*
G02X1703220Y288787I-90J178D01*
G03X1703218Y288785I140J-142D01*
G02X1703203Y288776I-110J167D01*
G01X1703160Y288755D01*
X1703145Y288750D01*
X1703144D01*
G03X1702107Y287320I467J-1430D01*
G03X1703600Y285818I1502J0D01*
G01X1703611D01*
G03X1703800Y285830I0J1502D01*
G01X1703802D01*
X1703872Y285838D01*
G02X1703938Y285829I6J-200D01*
G02X1703972Y285815I-59J-191D01*
G01X1706669Y272223D01*
X1711390Y248426D01*
G02X1711303Y248219I-196J-39D01*
G01X1711275Y248201D01*
X1711123Y248102D01*
X1711099Y248090D01*
G02X1711019Y248072I-83J182D01*
G01X1711018D01*
G02X1710967Y248079I1J200D01*
G01X1710960Y248081D01*
X1710894Y248102D01*
X1710870Y248118D01*
G03X1710028Y248376I-842J-1245D01*
G03Y245372I0J-1502D01*
G01X1710032D01*
G03X1710376Y245412I0J1502D01*
G01X1710402Y245418D01*
X1710441Y245422D01*
G02X1710559Y245388I6J-200D01*
G02X1710585Y245367I-112J-166D01*
G01X1710746Y245180D01*
X1710826Y245087D01*
G02X1710871Y244916I-151J-131D01*
G01X1710865Y244896D01*
G03X1710741Y244298I1383J-599D01*
G01Y244297D01*
G03X1712248Y242790I1507J0D01*
G03X1712372Y242795I1J1507D01*
G02X1712537Y242643I-30J-198D01*
G01X1712651Y242071D01*
X1713034Y240135D01*
G02X1713038Y240099I-196J-40D01*
G01X1713057Y238905D01*
X1713055Y238892D01*
G03X1713045Y238714I1492J-173D01*
G01Y238688D01*
G03X1713050Y238588I1502J25D01*
G01X1713051Y238580D01*
Y238574D01*
X1713052Y238564D01*
G03X1713061Y238493I1494J153D01*
G01Y238492D01*
X1713063Y238478D01*
X1713183Y230807D01*
X1713173Y230763D01*
X1713164Y230743D01*
G03X1713028Y230117I1367J-625D01*
G03X1713029Y230063I1503J1D01*
G01X1713033Y230004D01*
G03X1713185Y229451I1498J114D01*
G01X1713195Y229430D01*
X1713205Y229388D01*
X1713537Y208112D01*
X1713739Y195153D01*
G02X1713738Y195138I-200J6D01*
G01X1713737Y195131D01*
X1709171Y161331D01*
X1708512Y156450D01*
G03X1708477Y155982I3891J-526D01*
G01X1708476Y155930D01*
X1708474Y155779D01*
X1708471Y155603D01*
G02X1708469Y155577I-200J2D01*
G01X1708133Y153273D01*
G03X1708092Y152711I3851J-563D01*
G01Y147850D01*
X1708087Y147828D01*
G03X1707998Y147112I3835J-840D01*
G02X1707994Y147078I-200J6D01*
G01X1707984Y147031D01*
G03X1707742Y145679I3649J-1351D01*
G01Y145672D01*
X1707740Y145636D01*
G02X1707694Y145534I-198J28D01*
G01X1707505Y145327D01*
X1707467Y145309D01*
X1707371Y145262D01*
X1707337Y145258D01*
X1707333D01*
G03X1705963Y143762I132J-1496D01*
G03X1707380Y142262I1502J0D01*
G01X1707424Y142259D01*
X1707458Y142242D01*
G02X1707511Y142203I-90J-178D01*
G01X1707655Y142038D01*
X1707658Y142035D01*
X1707709Y141974D01*
G02X1707756Y141853I-153J-129D01*
G01Y141832D01*
X1707755Y141823D01*
Y141820D01*
X1707754Y141812D01*
G03X1707746Y141667I3881J-287D01*
G01Y141665D01*
G03X1707742Y141498I3888J-177D01*
G01Y140164D01*
G02X1707741Y140146I-200J2D01*
G01X1707740Y140137D01*
G02X1707680Y140019I-198J27D01*
G01X1707653Y139995D01*
X1707430Y139802D01*
X1707418Y139792D01*
X1707402Y139786D01*
X1707319Y139798D01*
X1707317D01*
G03X1707018Y139831I-580J-3884D01*
G03X1706756Y139842I-296J-3915D01*
G01X1706705D01*
G03X1704630Y139230I30J-3927D01*
G03X1704613Y139233I-270J-1478D01*
G01X1704605Y139235D01*
G03X1704347Y139259I-268J-1478D01*
G01X1704334D01*
G03X1702832Y137772I0J-1502D01*
G01Y137756D01*
G03X1702968Y137132I1502J1D01*
G01X1702977Y137112D01*
X1702984Y137080D01*
G03X1702909Y136803I3750J-1164D01*
G03X1702877Y136652I3824J-889D01*
G03X1702808Y135915I3857J-733D01*
G03X1703160Y134289I3928J-1D01*
G02Y134141I-186J-74D01*
G03X1702808Y132515I3576J-1625D01*
G01Y132511D01*
G03X1702984Y131351I3926J2D01*
G01X1702980Y131333D01*
X1702966Y131292D01*
G03X1702951Y131258I1367J-623D01*
G01Y131257D01*
X1702943Y131236D01*
G03X1702900Y131119I1387J-576D01*
G01Y131118D01*
G03X1702896Y131107I1409J-519D01*
G03X1702894Y131099I193J-52D01*
G01X1702893Y131096D01*
Y131095D01*
G03X1702839Y130819I1441J-425D01*
G03X1702832Y130700I1495J-148D01*
G01Y130663D01*
G03X1704334Y129168I1502J7D01*
G01X1704352D01*
G03X1704604Y129192I-16J1502D01*
G01X1704633Y129197D01*
G03X1706701Y128588I2101J3318D01*
G01X1706749D01*
G03X1708835Y129198I-16J3927D01*
G01X1708860Y129193D01*
G03X1708871Y129191I274J1477D01*
G01X1708873D01*
G03X1708896Y129187I269J1478D01*
G03X1708904Y129185I52J192D01*
G03X1708920Y129183I194J1490D01*
G01X1708924D01*
G03X1709147Y129167I219J1486D01*
G01X1709154D01*
G03X1709300Y129176I-19J1504D01*
G03X1709593Y129238I-163J1493D01*
G01X1709595D01*
X1709597Y129239D01*
G03X1709606Y129242I-471J1428D01*
G01X1709625Y129248D01*
X1709664Y129253D01*
G02X1709790Y129221I16J-199D01*
G01X1709945Y129110D01*
X1709947D01*
X1710062Y129026D01*
Y129025D01*
G02X1710110Y128974I-119J-160D01*
G01X1710108Y128902D01*
Y128828D01*
G03X1710460Y127202I3928J-1D01*
G02Y127054I-186J-74D01*
G03X1710108Y125428I3576J-1625D01*
G01Y125359D01*
Y125353D01*
X1710110Y125280D01*
G02X1710061Y125228I-168J109D01*
G01X1710034Y125208D01*
X1709799Y125037D01*
G02X1709645Y125002I-118J162D01*
G01X1709615Y125008D01*
X1709601Y125013D01*
G03X1709135Y125087I-466J-1429D01*
G01X1709130D01*
G03X1708873Y125065I-1J-1503D01*
G01X1708856Y125063D01*
G02X1708831Y125062I-20J199D01*
G03X1706736Y125668I-2096J-3320D01*
G01X1706716D01*
Y125669D01*
G03X1704722Y125114I19J-3927D01*
G01X1704708Y125105D01*
G02X1704622Y125086I-85J181D01*
G01X1704334D01*
G03X1702832Y123593I0J-1502D01*
G01Y123580D01*
G03X1702969Y122952I1503J-1D01*
G01X1702982Y122914D01*
X1702984Y122906D01*
G03X1702808Y121746I3750J-1162D01*
G01Y121742D01*
G03X1703160Y120116I3928J-1D01*
G02Y119968I-186J-74D01*
G03X1702808Y118342I3576J-1625D01*
G01Y118340D01*
G03X1702985Y117176I3926J2D01*
G01X1702978Y117146D01*
X1702969Y117127D01*
G03X1702832Y116500I1365J-627D01*
G01Y116497D01*
G03X1704334Y114995I1502J0D01*
G01X1704338D01*
G03X1704602Y115018I2J1502D01*
G01X1704634Y115024D01*
G03X1706734Y114415I2100J3318D01*
G03X1708834Y115024I0J3927D01*
G01X1708859Y115019D01*
G03X1709134Y114995I268J1478D01*
G01X1709137D01*
G03X1709566Y115058I-1J1502D01*
G01X1709580Y115062D01*
X1709630Y115070D01*
G02X1709649Y115071I20J-199D01*
G01X1709698D01*
G02X1709811Y115036I0J-200D01*
G01X1709893Y114975D01*
X1709896Y114973D01*
X1710063Y114852D01*
G02X1710067Y114849I-118J-162D01*
G02X1710110Y114801I-125J-156D01*
G01X1710108Y114714D01*
Y114655D01*
G03X1710460Y113029I3928J-1D01*
G02Y112881I-186J-74D01*
G03X1710108Y111255I3576J-1625D01*
G03X1710177Y110517I3926J-5D01*
G03X1710244Y110228I3856J742D01*
G03X1710284Y110090I3790J1024D01*
G01Y110089D01*
X1710277Y110056D01*
G03X1710268Y110036I1365J-626D01*
G01X1710267Y110034D01*
G03X1710132Y109430I1367J-623D01*
G01Y109409D01*
G03X1711634Y107908I1502J1D01*
G01X1711639D01*
G03X1711864Y107925I0J1502D01*
G02X1711997Y107898I29J-198D01*
G03X1712138Y107816I2044J3353D01*
G01X1712140D01*
X1712189Y107788D01*
X1712204Y107751D01*
X1712282Y107462D01*
X1712281Y107408D01*
X1712274Y107382D01*
X1712257Y107321D01*
X1712245Y107300D01*
G03X1712051Y106562I1308J-738D01*
G01Y106526D01*
X1712052Y106512D01*
Y106508D01*
G03X1712058Y106418I1501J55D01*
G03X1712225Y105859I1495J142D01*
G01X1712233Y105843D01*
G03X1712237Y105836I175J96D01*
G02X1712241Y105829I-172J-103D01*
G01Y105828D01*
G03X1712361Y105646I1311J734D01*
G03X1712363Y105644I141J139D01*
G03X1712402Y105597I1175J935D01*
G02X1712406Y105591I-164J-114D01*
G03X1712413Y105582I1189J918D01*
G03X1712419Y105576I144J138D01*
G03X1712475Y105515I1134J985D01*
G03X1712586Y105411I1081J1043D01*
G01X1712587Y105410D01*
X1712601Y105399D01*
G03X1712614Y105388I977J1141D01*
G03X1712618Y105385I903J1199D01*
G01X1712627Y105378D01*
X1712635Y105370D01*
X1712645Y105362D01*
X1712664Y105343D01*
X1712684Y105319D01*
X1712685Y105318D01*
X1712687Y105315D01*
G02X1712731Y105196I-156J-125D01*
G01Y105180D01*
X1712713Y104846D01*
G02X1712685Y104764I-199J22D01*
G01X1712673Y104745D01*
X1712642Y104712D01*
X1712617Y104697D01*
G03X1711892Y103411I778J-1286D01*
G03X1714896I1502J0D01*
G03X1714319Y104594I-1501J0D01*
G01X1714317Y104596D01*
X1714300Y104610D01*
X1714269Y104647D01*
X1714267Y104650D01*
G02X1714216Y104798I149J134D01*
G01X1714220Y104873D01*
Y104875D01*
X1714234Y105148D01*
X1714252Y105187D01*
X1714272Y105225D01*
X1714310Y105262D01*
X1714328Y105274D01*
X1714336Y105279D01*
X1714343Y105283D01*
X1714353Y105289D01*
G03X1715055Y106555I-800J1271D01*
G01Y106577D01*
G03X1715036Y106803I-1502J-12D01*
G01X1715030Y106836D01*
G03X1714975Y107047I-1478J-273D01*
G01X1714969Y107064D01*
G02X1714980Y107183I196J42D01*
G01X1715103Y107427D01*
G02X1715147Y107480I173J-99D01*
G01X1715162Y107493D01*
X1715212Y107509D01*
G03X1715973Y107841I-1181J3745D01*
G01X1715975D01*
G03X1716042Y107881I-1979J3391D01*
G02X1716048Y107885I114J-164D01*
G01X1716051Y107886D01*
G03X1716056Y107889I-100J173D01*
G02X1716154Y107917I102J-172D01*
G02X1716180Y107916I5J-200D01*
G03X1716333Y107907I165J1494D01*
G01X1716335D01*
G03X1716410Y107909I-3J1503D01*
G01X1716448Y107912D01*
G03X1717453Y108407I-113J1498D01*
G01X1717454Y108408D01*
G02X1717602Y108474I148J-134D01*
G01X1717760D01*
G03X1720536Y109624I0J3926D01*
G01X1730539Y119627D01*
G03X1731381Y120879I-2776J2776D01*
G01X1731877Y122054D01*
X1731887Y122069D01*
G03X1732237Y122728I-3247J2147D01*
G01X1734896Y129145D01*
G02X1734906Y129163I179J-88D01*
G01X1734922Y129182D01*
G03X1734929Y129190I-144J133D01*
G01X1734935Y129199D01*
X1734938Y129203D01*
X1734979Y129244D01*
G02X1735007Y129267I140J-142D01*
G01X1735046Y129293D01*
X1735063Y129301D01*
G03X1735947Y130697I-618J1369D01*
G01X1735946Y130717D01*
Y130718D01*
G03X1735945Y130741I-1501J-54D01*
G03X1735883Y131102I-1501J-72D01*
G01Y131104D01*
G03X1735877Y131123I-1435J-443D01*
G01Y131125D01*
G03X1735844Y131215I-1427J-472D01*
G01X1735830Y131250D01*
X1735821Y131289D01*
G02X1735833Y131410I196J42D01*
G01X1736101Y132057D01*
X1736700Y133501D01*
Y133503D01*
X1741981Y146040D01*
G03X1742218Y146820I-3618J1525D01*
G01X1742652Y149068D01*
G03X1742700Y149379I-3853J754D01*
G03X1742724Y149812I-3903J433D01*
G03X1742699Y150250I-3927J-4D01*
G01X1742554Y151540D01*
X1742329Y153543D01*
G02X1742328Y153565I199J20D01*
G01Y154608D01*
G03X1742249Y155387I-3891J-1D01*
G01X1741972Y156743D01*
G02X1741969Y156760I195J43D01*
G01X1741951Y156915D01*
X1741854Y157783D01*
G03X1741795Y158150I-3902J-439D01*
G01X1741774Y158251D01*
X1741574Y159208D01*
X1741290Y160566D01*
G02X1741354Y160757I196J41D01*
G01X1741500Y160885D01*
X1741518Y160901D01*
G02X1741650Y160951I132J-150D01*
G01X1741725D01*
X1741755Y160941D01*
G03X1742223Y160866I469J1427D01*
G01X1742243D01*
G03X1743249Y161270I-19J1502D01*
G01X1743279Y161299D01*
X1743314Y161313D01*
G02X1743350Y161323I71J-187D01*
G02X1743384Y161326I35J-197D01*
G01X1743624D01*
G02X1743697Y161312I-1J-200D01*
G01X1743749Y161292D01*
X1743763Y161287D01*
G02X1743809Y161260I-78J-185D01*
G01X1743814Y161255D01*
X1743821Y161249D01*
G03X1744821Y160865I1003J1119D01*
G01X1744860Y160866D01*
G03X1745725Y161167I-38J1502D01*
G03X1746326Y162368I-900J1201D01*
G03X1745959Y163352I-1503J0D01*
G03X1745000Y163860I-1135J-984D01*
G01X1744919Y163870D01*
G03X1744895Y163871I-20J-199D01*
G01X1744823D01*
G03X1743821Y163487I1J-1503D01*
G01X1743814Y163481D01*
X1743809Y163476D01*
G02X1743763Y163449I-124J158D01*
G01X1743749Y163444D01*
X1743697Y163424D01*
G02X1743624Y163410I-74J186D01*
G01X1743424D01*
G02X1743351Y163424I1J200D01*
G01X1743299Y163444D01*
X1743284Y163449D01*
G02X1743269Y163457I87J180D01*
G01X1743235Y163480D01*
X1743234Y163481D01*
X1743227Y163487D01*
G03X1742224Y163871I-1003J-1118D01*
G01X1742151D01*
G03X1742127Y163870I-4J-200D01*
G01X1742047Y163860D01*
X1742046D01*
G03X1741232Y163498I176J-1492D01*
G01X1741206Y163475D01*
X1741132Y163445D01*
G02X1741062Y163430I-76J185D01*
G01X1741028Y163429D01*
X1740798Y163504D01*
X1740715Y163531D01*
X1740700Y163536D01*
X1740665Y163547D01*
X1736462Y183625D01*
X1734527Y193065D01*
X1734213Y194603D01*
G02X1734210Y194631I196J35D01*
G01Y206884D01*
G02X1734222Y206951I200J-1D01*
G01X1734253Y207039D01*
X1734273Y207064D01*
G03X1734582Y207977I-1194J913D01*
G01Y207979D01*
G03X1734275Y208890I-1503J1D01*
G01X1734271Y208895D01*
X1734269Y208898D01*
X1734244Y208935D01*
X1734230Y208963D01*
G02X1734215Y209006I180J87D01*
G02X1734210Y209050I195J44D01*
G01Y209387D01*
G02X1734217Y209439I200J0D01*
G03X1734219Y209443I-174J90D01*
G02X1734221Y209452I196J-39D01*
G01X1734249Y209533D01*
X1734269Y209560D01*
X1734270Y209561D01*
G03X1734581Y210488I-1192J915D01*
G03X1734266Y211400I-1503J-9D01*
G01X1734244Y211435D01*
X1734228Y211466D01*
G02X1734214Y211509I182J83D01*
G01Y211511D01*
G02X1734210Y211549I196J40D01*
G01Y211887D01*
G02X1734217Y211939I200J0D01*
G03X1734219Y211943I-174J90D01*
G02X1734221Y211952I196J-39D01*
G01X1734249Y212033D01*
X1734269Y212060D01*
X1734270Y212061D01*
G03X1734581Y212988I-1192J915D01*
G03X1734266Y213900I-1503J-9D01*
G01X1734244Y213935D01*
X1734228Y213966D01*
G02X1734214Y214009I182J83D01*
G01Y214011D01*
G02X1734210Y214049I196J40D01*
G01Y214429D01*
X1734220Y214472D01*
X1734231Y214494D01*
X1734253Y214540D01*
X1734266Y214557D01*
G03X1734582Y215477I-1187J922D01*
G01Y215502D01*
X1734579Y215559D01*
G03X1734282Y216379I-1500J-80D01*
G01X1734272Y216392D01*
X1734251Y216432D01*
X1734241Y216452D01*
X1734220Y216516D01*
G02X1734210Y216578I190J62D01*
G01Y220234D01*
G03X1734211Y220275I-3891J115D01*
G03Y220279I-200J2D01*
G03X1734210Y220347I-3892J-23D01*
G01Y220366D01*
X1734209Y220368D01*
X1734159Y222533D01*
Y222535D01*
X1734157Y222606D01*
X1734172Y222645D01*
X1734194Y222701D01*
G02X1734228Y222758I186J-73D01*
G01X1734240Y222772D01*
X1734243Y222776D01*
G03X1734247Y222781I-1171J941D01*
G01X1734248Y222782D01*
G03X1734578Y223624I-1169J944D01*
G03X1734581Y223710I-1499J95D01*
G01Y223730D01*
G03X1734182Y224746I-1503J-4D01*
G01X1734158Y224772D01*
X1734110Y224885D01*
X1734104Y224918D01*
G02X1734103Y224928I199J25D01*
G01X1734101Y224993D01*
X1734100Y225034D01*
Y225036D01*
X1734099Y225076D01*
X1734128Y225150D01*
X1734157Y225180D01*
G03X1734581Y226222I-1078J1046D01*
G01Y226241D01*
G03X1734574Y226374I-1502J-12D01*
G01X1734571Y226401D01*
Y226403D01*
G03X1734112Y227317I-1492J-177D01*
G01X1734087Y227340D01*
X1734074Y227366D01*
G02X1734054Y227419I175J96D01*
G01X1734042Y227477D01*
Y227486D01*
X1734103Y227626D01*
X1734131Y227654D01*
G03X1734581Y228726I-1052J1072D01*
G03X1734568Y228926I-1502J3D01*
G01X1734567Y228937D01*
G03X1734329Y229560I-1488J-211D01*
G01X1734307Y229592D01*
X1734295Y229609D01*
X1734271Y229642D01*
X1734254Y229662D01*
G02X1734236Y229691I161J120D01*
G01X1734232Y229699D01*
G02X1734211Y229788I179J89D01*
G01Y229871D01*
G03X1734193Y229954I-200J0D01*
G01X1734168Y230002D01*
G02X1734149Y230084I181J85D01*
G01Y230098D01*
G02X1734151Y230121I200J-6D01*
G01X1734156Y230147D01*
X1734183Y230204D01*
X1734202Y230225D01*
G03X1734582Y231224I-1124J999D01*
G03Y231226I-1504J1D01*
G01Y231251D01*
X1734579Y231310D01*
G03X1734524Y231638I-1500J-83D01*
G03X1734000Y232413I-1444J-412D01*
G01X1733999D01*
G02X1733944Y232481I124J157D01*
G01X1733934Y232501D01*
X1733923Y232543D01*
X1733762Y239405D01*
G03X1733739Y239752I-3892J-84D01*
G03X1733697Y240033I-3868J-435D01*
G01X1733692Y240059D01*
X1733687Y240084D01*
X1733317Y241932D01*
X1733316Y241939D01*
X1733315Y241943D01*
G03X1733308Y241983I-3870J-657D01*
G01Y241989D01*
G03X1733305Y242005I-3857J-715D01*
G01Y242009D01*
G03X1733280Y242142I-3871J-659D01*
G01X1716950Y324447D01*
G02X1716958Y324537I198J28D01*
G02X1716977Y324579I191J-61D01*
G01X1717013Y324637D01*
X1717045Y324660D01*
X1717046Y324661D01*
X1717133Y324725D01*
X1717167Y324735D01*
X1717168D01*
G03X1718257Y326179I-413J1444D01*
G03X1717895Y327157I-1502J0D01*
G03X1717453Y327510I-1142J-977D01*
G03X1717450Y327512I-112J-164D01*
G01X1717398Y327538D01*
X1717362Y327554D01*
G03X1717311Y327576I-621J-1369D01*
G03X1717306Y327578I-77J-185D01*
G02X1717298Y327581I66J189D01*
G01X1717293Y327583D01*
G02X1717198Y327685I90J179D01*
G01X1717112Y327890D01*
Y327892D01*
X1717094Y327933D01*
G02X1717078Y328011I184J78D01*
G01Y328049D01*
X1717086Y328094D01*
G02X1717091Y328112I195J-44D01*
G01X1717094Y328121D01*
X1717096Y328126D01*
G03X1717125Y328201I-1386J579D01*
G01X1717135Y328231D01*
G03X1717179Y328400I-1429J462D01*
G03X1717204Y328582I-1473J295D01*
G01Y328601D01*
G03X1717205Y328619I-1499J92D01*
G01X1717206Y328627D01*
Y328631D01*
X1717207Y328641D01*
Y328676D01*
X1717208Y328692D01*
G03X1716593Y329904I-1502J0D01*
G01X1716592Y329905D01*
X1716561Y329929D01*
G02X1716482Y330081I121J159D01*
G01X1716476Y330265D01*
G02X1716534Y330412I200J6D01*
G01X1716557Y330435D01*
X1716569Y330444D01*
G03X1717197Y331719I-980J1275D01*
G03X1715590Y333326I-1607J0D01*
G01X1715589D01*
G03X1715381Y333313I-4J-1607D01*
G01X1715274Y333299D01*
G02X1715190Y333320I5J200D01*
G01X1715005Y334253D01*
X1714484Y336881D01*
X1713954Y339552D01*
G02Y339630I196J39D01*
G01X1713961Y339666D01*
X1713972Y339683D01*
G03X1714094Y339894I-1235J855D01*
G01X1714095Y339897D01*
X1714103Y339916D01*
G02X1714151Y339982I182J-82D01*
G01X1714173Y340003D01*
X1714201Y340016D01*
G02X1714249Y340031I83J-182D01*
G01X1714519Y340068D01*
X1714521D01*
X1714604Y340079D01*
G02X1714761Y340022I16J-199D01*
G01X1714776Y340007D01*
X1714781Y340001D01*
G03X1715928Y339467I1149J968D01*
G01X1715987D01*
X1716007Y339469D01*
X1716011D01*
G03X1717432Y340969I-81J1500D01*
G03X1716106Y342461I-1502J0D01*
G01X1716049Y342467D01*
G03X1715930Y342472I-123J-1498D01*
G03X1714570Y341609I0J-1503D01*
G01X1714558Y341583D01*
X1714516Y341535D01*
G02X1714512Y341531I-143J139D01*
G03X1714508Y341527I139J-143D01*
G02X1714415Y341473I-143J140D01*
G01X1714394Y341468D01*
X1714238Y341448D01*
X1714236D01*
X1714071Y341425D01*
G02X1713914Y341471I-27J198D01*
G02X1713903Y341481I129J153D01*
G01X1713888Y341496D01*
X1713883Y341502D01*
G03X1713631Y341739I-1148J-968D01*
G02X1713629Y341741I140J142D01*
G03X1713596Y341766I-924J-1185D01*
G01X1713594D01*
G03X1713567Y341786I-908J-1197D01*
G01X1713535Y341809D01*
X1713516Y341837D01*
G02X1713485Y341911I165J113D01*
G01X1713296Y342866D01*
G02X1713341Y343021I199J26D01*
G01X1713346Y343026D01*
G03X1713728Y344027I-1122J1001D01*
G01Y344028D01*
G03X1713715Y344228I-1502J3D01*
G03X1712858Y345393I-1490J-198D01*
G01X1712830Y345406D01*
X1712808Y345435D01*
G02X1712770Y345518I158J122D01*
G01X1690017Y460198D01*
G02X1690013Y460234I196J40D01*
G01X1690005Y460922D01*
X1689999Y461445D01*
X1689959Y464872D01*
G02X1690001Y464997I200J2D01*
G01X1690022Y465024D01*
X1690079Y465060D01*
X1690112Y465068D01*
G03X1690639Y465312I-356J1459D01*
G03X1690960Y465628I-881J1216D01*
G01X1690981Y465656D01*
X1691069Y465714D01*
G02X1691134Y465742I110J-167D01*
G01X1691216Y465761D01*
G02X1691296Y465763I45J-195D01*
G02X1691360Y465739I-37J-197D01*
G03X1692251Y465503I892J1567D01*
G01X1692253D01*
G03X1694056Y467306I0J1803D01*
G01Y470706D01*
G03X1692253Y472509I-1803J0D01*
G01X1692251D01*
G03X1691359Y472273I0J-1803D01*
G01X1691348Y472267D01*
G02X1691218Y472251I-88J179D01*
G01X1691134Y472270D01*
G02X1691067Y472298I42J196D01*
G01X1690980Y472356D01*
X1690960Y472384D01*
G03X1690028Y472961I-1202J-901D01*
G01X1690027D01*
G02X1690002Y472967I34J197D01*
G02X1689864Y473155I62J190D01*
G01X1689796Y479014D01*
G02X1689888Y479184I200J2D01*
G02X1689967Y479214I109J-168D01*
G01X1689968D01*
G03X1690960Y479801I-210J1487D01*
G01X1690980Y479829D01*
X1691067Y479887D01*
G02X1691134Y479915I109J-168D01*
G01X1691227Y479936D01*
G02X1691349Y479918I33J-197D01*
G03X1692251Y479676I902J1561D01*
G01X1692253D01*
G03X1694056Y481479I0J1803D01*
G01Y484879D01*
G03X1690450I-1803J0D01*
G01Y482580D01*
G02X1690382Y482430I-200J0D01*
G01X1690259Y482324D01*
X1690150Y482231D01*
G02X1690018Y482183I-130J152D01*
G01X1689989Y482185D01*
G03X1689933Y482193I-240J-1483D01*
G02X1689808Y482258I24J198D01*
G01X1689783Y482285D01*
X1689758Y482351D01*
X1689124Y537188D01*
X1689121Y537441D01*
G02X1689160Y537562I200J2D01*
G02X1689183Y537588I161J-119D01*
G02X1689194Y537598I140J-143D01*
G01X1689435Y537796D01*
G02X1689516Y537836I127J-155D01*
G01X1689559Y537846D01*
X1689582Y537841D01*
G03X1689917Y537804I333J1476D01*
G01X1689920D01*
G03Y540826I0J1511D01*
G01X1689919D01*
G03X1689569Y540784I4J-1511D01*
G01X1689560Y540782D01*
X1689558D01*
X1689525Y540774D01*
X1689483Y540783D01*
G02X1689402Y540821I42J196D01*
G01X1689155Y541014D01*
G02X1689078Y541169I123J158D01*
G01X1688996Y548237D01*
G02X1689048Y548374I200J2D01*
G01X1689230Y548575D01*
G02X1689292Y548621I148J-135D01*
G01X1689325Y548637D01*
X1689363Y548640D01*
G03X1690315Y549091I-126J1497D01*
G01X1690343Y549120D01*
X1690448Y549165D01*
G02X1690525Y549181I78J-184D01*
G01X1690739D01*
G02X1690817Y549165I0J-200D01*
G01X1690922Y549120D01*
X1690950Y549091D01*
G03X1692023Y548635I1078J1046D01*
G01X1692048D01*
G03X1692305Y548661I-22J1502D01*
G03X1692727Y548807I-275J1477D01*
G01X1692731Y548809D01*
G03X1692744Y548816I-706J1326D01*
G01X1692770Y548830D01*
X1695138D01*
G02X1695176Y548826I-2J-200D01*
G02X1695278Y548773I-37J-196D01*
G01X1707561Y536490D01*
G02X1707614Y536388I-143J-139D01*
G02X1707618Y536350I-196J-40D01*
G01Y461719D01*
G03X1708001Y460795I1306J0D01*
G01X1714860Y453936D01*
X1714868Y453912D01*
X1714873Y453898D01*
G03X1716310Y452832I1437J436D01*
G03X1717812Y454334I0J1502D01*
G03X1716756Y455768I-1502J0D01*
G01X1716741Y455773D01*
G02X1716712Y455788I77J185D01*
G02X1716675Y455817I104J171D01*
G01X1710290Y462202D01*
G02X1710254Y462252I142J140D01*
G02X1710232Y462343I178J91D01*
G01Y536974D01*
G03X1710212Y537199I-1307J-3D01*
G03X1710195Y537282I-1288J-221D01*
G01X1710193Y537291D01*
X1710188Y537320D01*
G03X1709821Y538114I-1263J-102D01*
G01X1699629Y548305D01*
G02X1699572Y548456I143J140D01*
G01X1699578Y548576D01*
Y548578D01*
X1699590Y548768D01*
G02X1699609Y548833I198J-23D01*
G01X1699627Y548868D01*
X1699661Y548896D01*
X1699663Y548898D01*
X1699671Y548904D01*
G03X1700219Y550065I-956J1161D01*
G01Y550067D01*
G03X1700185Y550384I-1503J-1D01*
G03X1698716Y551567I-1469J-321D01*
G01X1698673D01*
G03X1697548Y551011I43J-1502D01*
G01X1697531Y550991D01*
X1697501Y550967D01*
X1697484Y550958D01*
G02X1697420Y550939I-88J179D01*
G01X1697227Y550927D01*
X1697225D01*
X1697107Y550921D01*
G02X1696956Y550979I-10J200D01*
G01X1696902Y551033D01*
G03X1696108Y551400I-896J-896D01*
G01X1696079Y551405D01*
X1696070Y551407D01*
G03X1695987Y551424I-304J-1271D01*
G03X1695762Y551444I-228J-1287D01*
G01X1692770D01*
X1692744Y551458D01*
G03X1692731Y551465I-719J-1319D01*
G01X1692727Y551467D01*
G03X1692305Y551613I-697J-1331D01*
G03X1692048Y551639I-279J-1476D01*
G01X1692028D01*
G03X1690950Y551183I0J-1502D01*
G01X1690922Y551154D01*
X1690817Y551109D01*
G02X1690739Y551093I-78J184D01*
G01X1690525D01*
G02X1690447Y551109I0J200D01*
G01X1690342Y551154D01*
X1690314Y551183D01*
G03X1689236Y551639I-1078J-1046D01*
G03X1689178Y551638I-3J-1502D01*
G01X1689155D01*
G02X1688955Y551836I0J200D01*
G01X1688777Y567202D01*
G03X1688745Y567659I-3926J-45D01*
G01X1683276Y610114D01*
G03X1683250Y610286I-3894J-501D01*
G01X1656143Y765937D01*
G02X1656179Y766078I198J24D01*
G01X1656344Y766310D01*
G02X1656431Y766378I162J-117D01*
G01X1656444Y766383D01*
G02X1656468Y766390I68J-188D01*
G01X1656476Y766391D01*
G03X1657743Y767038I-364J2278D01*
G01X1662671Y771966D01*
G03X1663346Y773596I-1631J1630D01*
G01Y904887D01*
G02X1663368Y904978I200J0D01*
G02X1663404Y905028I178J-90D01*
G01X1733642Y975266D01*
G02X1733692Y975302I140J-142D01*
G02X1733783Y975324I91J-178D01*
G01X1749799D01*
G03X1750605Y975468I4J2307D01*
G01X1750639Y975481D01*
X1750772D01*
G03X1750914Y975540I0J200D01*
G01X1751084Y975710D01*
X1751112Y975733D01*
X1751118Y975737D01*
G03X1751430Y975999I-1322J1891D01*
G01X1759001Y983570D01*
G03X1759676Y985200I-1631J1630D01*
G01Y990699D01*
G02X1759701Y990727I161J-119D01*
G01X1759813Y990829D01*
X1759896Y990906D01*
G02X1759902Y990910I113J-163D01*
G01X1759933Y990937D01*
G02X1759992Y990969I123J-157D01*
G01X1760028Y990981D01*
X1760070Y990978D01*
G03X1760179Y990973I123J1497D01*
G01X1760237D01*
G03X1760394Y990985I-36J1502D01*
G01X1760448Y990993D01*
G03X1760469Y990997I-270J1477D01*
G01X1760476Y990998D01*
X1760477D01*
X1760489Y991000D01*
G03X1760511Y991005I-322J1467D01*
G01X1760515Y991006D01*
X1760516D01*
X1760518Y991007D01*
X1760521D01*
X1760525Y991008D01*
X1760532Y991009D01*
X1760577Y991014D01*
G02X1760707Y990964I-2J-200D01*
G01X1760766Y990907D01*
X1760956Y990722D01*
G02X1761004Y990644I-142J-141D01*
G01X1761012Y990621D01*
X1761015Y990571D01*
X1761010Y990545D01*
G03X1760984Y990265I1477J-278D01*
G01Y990252D01*
G03X1762486Y988758I1502J8D01*
G03Y991762I0J1502D01*
G01X1762485D01*
G03X1762163Y991727I0J-1502D01*
G01X1762129Y991720D01*
X1762097Y991724D01*
X1762059Y991728D01*
X1762010Y991754D01*
X1761981Y991768D01*
X1761904Y991844D01*
X1761902Y991846D01*
X1761733Y992010D01*
X1761730Y992013D01*
G02X1761681Y992094I142J141D01*
G01X1761667Y992138D01*
X1761673Y992172D01*
X1761677Y992192D01*
X1761680Y992211D01*
Y992212D01*
X1761681Y992221D01*
X1761682Y992224D01*
Y992225D01*
X1761683Y992228D01*
Y992229D01*
X1761688Y992257D01*
G03X1761703Y992470I-1487J212D01*
G01Y992472D01*
G03Y992478I-1502J3D01*
G01Y992484D01*
G03X1761691Y992673I-1502J0D01*
G01Y992675D01*
G03X1761684Y992719I-1487J-214D01*
G01X1761683Y992730D01*
X1761674Y992783D01*
X1761664Y992824D01*
G03X1761618Y992978I-1461J-353D01*
G01X1761616Y992981D01*
X1761576Y993100D01*
X1761577Y993101D01*
X1761561Y993128D01*
X1761502Y993228D01*
X1761501Y993229D01*
G03X1761495Y993239I-1291J-768D01*
G01X1761490Y993248D01*
G03X1761206Y993592I-1288J-774D01*
G03X1761085Y993690I-1005J-1117D01*
G01X1761033Y993728D01*
X1761006Y993744D01*
G03X1760910Y993800I-804J-1269D01*
G01X1760872Y993820D01*
X1760821Y993885D01*
X1760809Y993932D01*
X1760737Y994223D01*
G02X1760733Y994255I196J41D01*
G01X1760781Y994325D01*
G03X1761165Y995314I-1900J1307D01*
G01X1761180Y995424D01*
G02X1761324Y995486I145J-138D01*
G01X1772574D01*
G02X1772611Y995482I-3J-200D01*
G01X1772613D01*
G02X1772714Y995429I-39J-196D01*
G01X1772718Y995425D01*
X1772924Y995212D01*
G02X1772974Y995080I-150J-132D01*
G01Y995049D01*
G03X1775978I1502J0D01*
G01Y995081D01*
G02X1776028Y995213I200J0D01*
G01X1776073Y995259D01*
X1776075Y995261D01*
X1776234Y995425D01*
G02X1776242Y995432I136J-147D01*
G01Y995433D01*
G02X1776336Y995482I136J-147D01*
G02X1776374Y995486I40J-196D01*
G01X1777245D01*
G02X1777358Y995451I0J-200D01*
G01X1777370Y995443D01*
X1777562Y995262D01*
G02X1777589Y995225I-147J-136D01*
G01X1777643Y995111D01*
X1777646Y995075D01*
G03X1779143Y993701I1497J129D01*
G03X1780642Y995110I0J1502D01*
G01X1780643Y995122D01*
X1780645Y995151D01*
X1780660Y995183D01*
G02X1780704Y995243I180J-86D01*
G01X1780800Y995334D01*
X1780909Y995436D01*
G02X1780924Y995448I132J-150D01*
G01X1780943Y995461D01*
G02X1781036Y995486I97J-175D01*
G01X1782343D01*
G03X1782485Y995545I0J200D01*
G01X1785761Y998821D01*
G02X1785867Y998875I140J-143D01*
G01X1785869D01*
G02X1785901Y998878I35J-197D01*
G01X1806087D01*
G02X1806119Y998875I-3J-200D01*
G01X1806121D01*
G02X1806227Y998821I-34J-197D01*
G01X1818139Y986909D01*
G02X1818193Y986803I-143J-140D01*
G01Y986801D01*
G02X1818196Y986769I-197J-35D01*
G01Y942564D01*
G02X1818155Y942443I-200J0D01*
G01X1818147Y942434D01*
X1818140Y942427D01*
G03X1818127Y942412I143J-137D01*
G01X1816722Y941007D01*
G03X1816663Y940865I141J-142D01*
G01Y448546D01*
G02X1816642Y448457I-200J0D01*
G01X1816630Y448434D01*
X1816593Y448361D01*
X1816579Y448344D01*
X1816562Y448323D01*
X1816541Y448307D01*
G03X1815936Y447068I898J-1206D01*
G03X1816535Y445899I1503J32D01*
G01X1816546Y445891D01*
X1816568Y445869D01*
G02X1816604Y445819I-142J-140D01*
G01X1816630Y445769D01*
Y445767D01*
X1816640Y445749D01*
G02X1816663Y445669I-177J-94D01*
G01Y425650D01*
G02X1816638Y425554I-200J1D01*
G01X1816616Y425518D01*
G03X1816305Y424643I1189J-915D01*
G03X1816615Y423686I1500J-43D01*
G01X1816622Y423677D01*
X1816636Y423654D01*
Y423653D01*
G02X1816663Y423553I-173J-100D01*
G01Y338453D01*
G03X1816722Y338311I200J0D01*
G01X1824330Y330703D01*
G02X1824384Y330597I-143J-140D01*
G01Y330595D01*
G02X1824387Y330563I-197J-35D01*
G01Y326257D01*
G03X1824446Y326115I200J0D01*
G01X1833843Y316718D01*
G02X1833897Y316612I-143J-140D01*
G01Y316610D01*
G02X1833900Y316578I-197J-35D01*
G01Y3883D01*
G02X1833841Y3741I-200J0D01*
G01X1832859Y2759D01*
G02X1832717Y2700I-142J141D01*
G01X1755983D01*
G02X1755841Y2759I0J200D01*
G01X1754211Y4389D01*
G02X1754152Y4531I141J142D01*
G01Y4726D01*
G02X1754167Y4802I200J0D01*
G03Y5946I-1390J572D01*
G02X1754152Y6022I185J76D01*
G01Y50643D01*
X1754161Y50688D01*
X1754166Y50718D01*
X1754211Y50803D01*
Y50829D01*
G03X1754152Y50961I-200J-10D01*
G01X1752508Y52605D01*
G02X1752457Y52791I143J139D01*
G01X1752497Y52910D01*
Y52912D01*
X1752582Y53159D01*
G02X1752598Y53190I185J-76D01*
G01X1752601Y53193D01*
Y53194D01*
X1752663Y53233D01*
G02X1752665Y53235I142J-140D01*
G01X1752692Y53252D01*
X1752706Y53260D01*
G02X1752771Y53286I106J-170D01*
G01X1752785Y53288D01*
X1752786D01*
G03X1760056Y61614I-1133J8326D01*
G03X1743252I-8402J0D01*
G03X1744275Y57596I8402J0D01*
G03X1746782Y54767I7381J4015D01*
G01X1746809Y54747D01*
X1746846Y54698D01*
X1746856Y54667D01*
G02X1746859Y54550I-190J-63D01*
G01X1746793Y54346D01*
X1746788Y54330D01*
X1746787Y54327D01*
X1746747Y54187D01*
G02X1746699Y54104I-192J56D01*
G02X1746555Y54042I-145J138D01*
G01X1744032D01*
G02X1743832Y54242I0J200D01*
G01Y54777D01*
G03X1743773Y54919I-200J0D01*
G01X1743161Y55531D01*
G03X1743019Y55590I-142J-141D01*
G01X1713642D01*
G03X1708666Y54076I0J-8936D01*
G01Y53991D01*
G02X1708625Y53870I-200J0D01*
G01X1708617Y53861D01*
X1708610Y53854D01*
G03X1708597Y53839I143J-137D01*
G01X1704023Y49265D01*
G03X1703964Y49123I141J-142D01*
G01Y5152D01*
X1703945Y5112D01*
G03X1703808Y4619I1358J-643D01*
G02X1703612Y4439I-199J20D01*
G01X1689754D01*
X1689727Y4447D01*
G03X1689321Y4503I-406J-1446D01*
G01X1689317D01*
G03X1688911Y4447I0J-1502D01*
G01X1688884Y4439D01*
X1669754D01*
X1669727Y4447D01*
G03X1669321Y4503I-406J-1446D01*
G01X1669317D01*
G03X1668911Y4447I0J-1502D01*
G01X1668884Y4439D01*
X1654443D01*
G02X1654322Y4480I0J200D01*
G01X1654313Y4488D01*
X1654306Y4495D01*
G03X1654291Y4508I-138J-144D01*
G01X1651065Y7734D01*
G02X1651021Y7801I142J141D01*
G01X1651007Y7835D01*
Y23908D01*
G02X1651012Y23950I200J-3D01*
G01X1651030Y24019D01*
X1651043Y24042D01*
G03Y25504I-1314J731D01*
G01X1651030Y25527D01*
X1651012Y25596D01*
G02X1651007Y25638I195J45D01*
G01Y43908D01*
G02X1651012Y43950I200J-3D01*
G01X1651030Y44019D01*
X1651043Y44042D01*
G03Y45504I-1314J731D01*
G01X1651030Y45527D01*
X1651012Y45596D01*
G02X1651007Y45638I195J45D01*
G01Y53155D01*
G02X1651013Y53203I200J-1D01*
G01X1651015Y53211D01*
G02X1651051Y53285I194J-49D01*
G01X1651113Y53365D01*
G02X1651161Y53409I157J-123D01*
G01X1651191Y53429D01*
X1651226Y53437D01*
G03X1657693Y61614I-1936J8177D01*
G03X1640889I-8402J0D01*
G03X1640891Y61414I8402J-16D01*
G03X1644360Y54810I8400J199D01*
G01X1644380Y54796D01*
X1644426Y54742D01*
X1644443Y54723D01*
X1644473Y54662D01*
G02X1644486Y54519I-179J-88D01*
G02X1644484Y54513I-191J60D01*
G01X1644430Y54345D01*
X1644424Y54327D01*
X1644384Y54187D01*
G02X1644336Y54104I-192J56D01*
G02X1644192Y54042I-145J138D01*
G01X1640800D01*
G02X1640600Y54242I0J200D01*
G01Y54727D01*
G03X1640542Y54868I-200J0D01*
G01X1639879Y55531D01*
G03X1639737Y55590I-142J-141D01*
G01X1611280D01*
G03X1606304Y54076I0J-8936D01*
G01Y52162D01*
G02X1606263Y52041I-200J0D01*
G01X1606255Y52032D01*
X1606248Y52025D01*
G03X1606235Y52010I143J-137D01*
G01X1604349Y50124D01*
G03X1604290Y49982I141J-142D01*
G01Y46454D01*
G02X1604287Y46422I-200J3D01*
G02X1604241Y46328I-197J38D01*
G01X1604218Y46302D01*
X1604153Y46268D01*
X1604115Y46263D01*
G03X1604114Y43283I186J-1490D01*
G01X1604115D01*
X1604122Y43282D01*
G02X1604269Y43174I-32J-197D01*
G02X1604289Y43103I-179J-89D01*
G01Y43101D01*
G02X1604290Y43085I-199J-20D01*
G01Y7096D01*
G02X1604249Y6975I-200J0D01*
G01X1604241Y6966D01*
X1604234Y6959D01*
G03X1604221Y6944I143J-137D01*
G01X1600760Y3483D01*
G02X1600693Y3439I-141J142D01*
G01X1600659Y3425D01*
X1550715D01*
G02X1550594Y3466I0J200D01*
G01X1550585Y3474D01*
X1550578Y3481D01*
G03X1550563Y3494I-138J-144D01*
G01X1548350Y5707D01*
G02X1548306Y5774I142J141D01*
G01X1548292Y5808D01*
Y43466D01*
X1548294Y43480D01*
X1548298Y43510D01*
X1548361Y43645D01*
X1548390Y43672D01*
G03X1548389Y45875I-1022J1101D01*
G01X1548388Y45876D01*
X1548369Y45894D01*
X1548342Y45936D01*
X1548334Y45959D01*
X1548310Y46012D01*
X1548292Y46052D01*
Y53082D01*
G02X1548339Y53211I200J0D01*
G01X1548384Y53264D01*
X1548391Y53273D01*
G02X1548435Y53310I149J-133D01*
G01X1548482Y53337D01*
X1548499Y53347D01*
X1548558Y53371D01*
X1548561D01*
G03X1554846Y58799I-1632J8242D01*
G03X1555331Y61611I-7917J2813D01*
G01Y61614D01*
G03X1538527I-8402J0D01*
G01Y61613D01*
G03X1539990Y56876I8399J0D01*
G01X1540040Y56802D01*
G03X1540044Y56796I168J108D01*
G01X1540081Y56746D01*
Y56744D01*
G03X1540156Y56640I6853J4863D01*
G02X1540158Y56638I-139J-141D01*
G01X1540237Y56526D01*
G03X1541888Y54892I6679J5097D01*
G03X1542041Y54780I5039J6723D01*
G01X1542044Y54778D01*
X1542046Y54777D01*
X1542055Y54770D01*
X1542081Y54744D01*
G02X1542130Y54542I-142J-141D01*
G01X1542073Y54363D01*
Y54361D01*
X1542028Y54224D01*
Y54222D01*
X1542009Y54167D01*
X1542008Y54164D01*
G02X1541941Y54080I-184J78D01*
G01X1541940D01*
G02X1541823Y54042I-117J162D01*
G01X1538600D01*
G02X1538400Y54242I0J200D01*
G01Y54706D01*
G03X1538341Y54848I-200J0D01*
G01X1537658Y55531D01*
G03X1537516Y55590I-142J-141D01*
G01X1508917D01*
G03X1503941Y54076I1J-8937D01*
G01Y51655D01*
G02X1503900Y51534I-200J0D01*
G01X1503892Y51525D01*
X1503885Y51518D01*
G03X1503872Y51503I143J-137D01*
G01X1502103Y49734D01*
G03X1502044Y49592I141J-142D01*
G01Y7174D01*
G02X1502003Y7053I-200J0D01*
G01X1501995Y7044D01*
X1501988Y7037D01*
G03X1501975Y7022I143J-137D01*
G01X1500964Y6011D01*
G02X1500886Y5963I-141J142D01*
G01X1500841Y5948D01*
X1500794Y5955D01*
G03X1500578Y5971I-219J-1485D01*
G03X1499076Y4469I0J-1502D01*
G03X1499092Y4253I1501J3D01*
G01X1499099Y4206D01*
X1499084Y4161D01*
G02X1499036Y4083I-190J63D01*
G01X1497891Y2938D01*
G02X1497824Y2894I-141J142D01*
G01X1497790Y2880D01*
X1448701D01*
G02X1448580Y2921I0J200D01*
G01X1448571Y2929D01*
X1448564Y2936D01*
G03X1448549Y2949I-138J-144D01*
G01X1447060Y4438D01*
G02X1447009Y4614I145J137D01*
G01X1447024Y4677D01*
X1447035Y4699D01*
G03X1447194Y5372I-1344J673D01*
G01Y5374D01*
G03X1445871Y6866I-1503J0D01*
G01X1445837Y6870D01*
X1445718Y6928D01*
X1445693Y6953D01*
X1445631Y7016D01*
G02X1445580Y7119I146J136D01*
G02X1445577Y7153I197J35D01*
G01Y23242D01*
G02X1445580Y23274I200J-3D01*
G01Y23276D01*
G02X1445634Y23382I197J-34D01*
G01X1445685Y23433D01*
X1445712Y23447D01*
G03X1445709Y26101I-707J1326D01*
G01X1445686Y26113D01*
X1445641Y26153D01*
X1445635Y26159D01*
G03X1445633Y26161I-142J-140D01*
G01X1445628Y26166D01*
G02X1445586Y26239I149J134D01*
G01Y26240D01*
X1445577Y26268D01*
Y43242D01*
G02X1445580Y43274I200J-3D01*
G01Y43276D01*
G02X1445634Y43382I197J-34D01*
G01X1445685Y43433D01*
X1445712Y43447D01*
G03X1445709Y46101I-707J1326D01*
G01X1445686Y46113D01*
X1445641Y46153D01*
X1445635Y46159D01*
G03X1445633Y46161I-142J-140D01*
G01X1445628Y46166D01*
G02X1445586Y46239I149J134D01*
G01Y46240D01*
X1445577Y46268D01*
Y53097D01*
G02X1445643Y53245I200J0D01*
G02X1445738Y53293I134J-148D01*
G01X1445749Y53295D01*
G03X1452969Y61613I-1181J8318D01*
G01Y61614D01*
G03X1436165I-8402J0D01*
G01Y61613D01*
G03X1437628Y56876I8399J0D01*
G01X1437678Y56802D01*
G03X1437682Y56796I168J108D01*
G01X1437719Y56746D01*
Y56744D01*
G03X1437794Y56640I6853J4863D01*
G02X1437796Y56638I-139J-141D01*
G01X1437875Y56526D01*
G03X1439526Y54892I6679J5097D01*
G03X1439679Y54780I5039J6723D01*
G01X1439682Y54778D01*
X1439684Y54777D01*
X1439693Y54770D01*
X1439719Y54744D01*
G02X1439768Y54542I-142J-141D01*
G01X1439711Y54363D01*
Y54361D01*
X1439677Y54256D01*
Y54254D01*
X1439656Y54191D01*
G02X1439454Y54042I-194J51D01*
G01X1437092D01*
G02X1436892Y54242I0J200D01*
G01Y54545D01*
G03X1436833Y54687I-200J0D01*
G01X1435989Y55531D01*
G03X1435847Y55590I-142J-141D01*
G01X1406555D01*
G03X1401650Y54122I2J-8936D01*
G01X1401645Y54119D01*
X1401606Y54097D01*
G02X1401518Y54076I-89J179D01*
G01X1400456D01*
G03X1400376Y54059I1J-200D01*
G01X1400337Y54042D01*
X1395395D01*
G03X1395195Y53842I0J-200D01*
G01Y8344D01*
G02X1395154Y8223I-200J0D01*
G01X1395146Y8214D01*
X1395139Y8207D01*
G03X1395126Y8192I143J-137D01*
G01X1394083Y7149D01*
G02X1394016Y7105I-141J142D01*
G01X1393982Y7091D01*
X1299970D01*
G02X1299849Y7132I0J200D01*
G01X1299840Y7140D01*
X1299833Y7147D01*
G03X1299818Y7160I-138J-144D01*
G01X1297684Y9294D01*
G02X1297640Y9361I142J141D01*
G01X1297626Y9395D01*
Y31985D01*
G02X1297629Y32019I200J-1D01*
G02X1297680Y32122I197J-33D01*
G01X1297741Y32184D01*
X1297743Y32186D01*
X1297764Y32208D01*
X1297767Y32211D01*
G02X1297876Y32267I141J-141D01*
G01X1297892Y32269D01*
X1297893D01*
X1297897Y32270D01*
X1297902D01*
G03X1299277Y33592I-117J1498D01*
G01X1299284Y33656D01*
G03X1299288Y33768I-1499J110D01*
G03X1297931Y35264I-1503J0D01*
G01X1297927D01*
X1297914Y35266D01*
X1297880Y35274D01*
X1297858Y35279D01*
X1297812Y35301D01*
X1297799Y35309D01*
X1297793Y35312D01*
X1297763Y35330D01*
X1297695Y35399D01*
G02X1297694Y35401I174J88D01*
G01X1297680Y35415D01*
G02X1297642Y35474I146J136D01*
G02X1297626Y35552I184J78D01*
G01Y51385D01*
G03X1297567Y51527I-200J0D01*
G01X1296321Y52773D01*
G02X1296299Y52800I144J139D01*
G02X1296272Y52959I167J110D01*
G01X1296321Y53130D01*
X1296370Y53303D01*
G02X1296458Y53411I189J-64D01*
G01X1296486Y53426D01*
X1296518Y53441D01*
X1296539Y53446D01*
G03X1302969Y61614I-1973J8168D01*
G03X1286165I-8402J0D01*
G03X1288446Y55858I8403J0D01*
G01X1288447Y55857D01*
X1288503Y55798D01*
G03X1288612Y55687I6049J5831D01*
G03X1289185Y55161I5963J5920D01*
G03X1289692Y54768I5398J6440D01*
G01X1289693Y54767D01*
G02X1289773Y54571I-117J-162D01*
G01X1289770Y54554D01*
X1289767Y54532D01*
X1289712Y54363D01*
Y54361D01*
X1289650Y54168D01*
G02X1289474Y54042I-186J74D01*
G01X1286476D01*
G02X1286276Y54242I0J200D01*
G01Y54872D01*
G03X1286218Y55013I-200J0D01*
G01X1285700Y55531D01*
G03X1285558Y55590I-142J-141D01*
G01X1256555D01*
G03X1251604Y54093I0J-8937D01*
G01X1251580Y54077D01*
X1251496Y54051D01*
G02X1251437Y54042I-59J191D01*
G01X1250602D01*
G03X1250460Y53983I0J-200D01*
G01X1248003Y51526D01*
G02X1247936Y51482I-141J142D01*
G01X1247902Y51468D01*
X1247795D01*
G03X1247653Y51409I0J-200D01*
G01X1247381Y51137D01*
G03X1247322Y50995I141J-142D01*
G01Y8656D01*
G02X1247281Y8535I-200J0D01*
G01X1247273Y8526D01*
X1247266Y8519D01*
G03X1247253Y8504I143J-137D01*
G01X1245430Y6681D01*
G02X1245363Y6637I-141J142D01*
G01X1245329Y6623D01*
X1195696D01*
G02X1195575Y6664I0J200D01*
G01X1195566Y6672D01*
X1195559Y6679D01*
G03X1195544Y6692I-138J-144D01*
G01X1195125Y7111D01*
G02X1195081Y7178I142J141D01*
G01X1195067Y7212D01*
Y49902D01*
G03X1195008Y50044I-200J0D01*
G01X1192504Y52548D01*
G02X1192452Y52639I142J141D01*
G01Y52742D01*
G02X1192454Y52749I193J-51D01*
G01X1192545Y52991D01*
X1192570Y53057D01*
G02X1192630Y53136I184J-78D01*
G01X1192711Y53195D01*
X1192737Y53205D01*
X1192815Y53234D01*
X1192843Y53236D01*
G03X1200607Y61614I-638J8378D01*
G03X1183803I-8402J0D01*
G01Y61613D01*
G03X1185416Y56663I8403J1D01*
G03X1187287Y54801I6789J4951D01*
G01X1187309Y54785D01*
X1187351Y54733D01*
X1187360Y54715D01*
X1187387Y54665D01*
G02X1187407Y54596I-179J-89D01*
G01X1187411Y54556D01*
X1187344Y54345D01*
X1187338Y54327D01*
X1187295Y54178D01*
G02X1187143Y54046I-189J64D01*
G01X1187122Y54042D01*
X1184334D01*
G02X1184134Y54242I0J200D01*
G01Y54482D01*
G03X1184075Y54624I-200J0D01*
G01X1183169Y55531D01*
G03X1183027Y55590I-142J-141D01*
G01X1154193D01*
G03X1149242Y54093I0J-8937D01*
G01X1143459Y48310D01*
G03X1143400Y48168I141J-142D01*
G01Y4483D01*
G02X1143341Y4341I-200J0D01*
G01X1141659Y2659D01*
G02X1141517Y2600I-142J141D01*
G01X1095683D01*
G02X1095541Y2659I0J200D01*
G01X1094854Y3346D01*
G02X1094795Y3488I141J142D01*
G01Y54036D01*
G03X1094785Y54099I-200J1D01*
G01X1094733Y54254D01*
Y54256D01*
X1094699Y54361D01*
Y54363D01*
X1094652Y54511D01*
G02X1094642Y54572I190J62D01*
G01Y54663D01*
G02X1094691Y54744I191J-60D01*
G01X1094714Y54767D01*
X1094728Y54777D01*
G03X1098245Y61613I-4885J6836D01*
G01Y61614D01*
G03X1081441I-8402J0D01*
G01Y61613D01*
G03X1082904Y56876I8399J0D01*
G01X1082954Y56802D01*
G03X1082958Y56796I168J108D01*
G01X1082995Y56746D01*
Y56744D01*
G03X1083070Y56640I6853J4863D01*
G02X1083072Y56638I-139J-141D01*
G01X1083151Y56526D01*
G03X1084802Y54892I6679J5097D01*
G03X1084955Y54780I5039J6723D01*
G01X1084958Y54778D01*
X1084960Y54777D01*
X1084969Y54770D01*
X1084995Y54744D01*
G02X1085044Y54542I-142J-141D01*
G01X1084987Y54363D01*
Y54361D01*
X1084953Y54256D01*
Y54254D01*
X1084932Y54191D01*
G02X1084730Y54042I-194J51D01*
G01X1082302D01*
G02X1082102Y54242I0J200D01*
G01Y54706D01*
G03X1082044Y54847I-200J0D01*
G01X1081360Y55531D01*
G03X1081218Y55590I-142J-141D01*
G01X1051831D01*
G03X1046880Y54093I0J-8937D01*
G01X1046856Y54077D01*
X1046772Y54051D01*
G02X1046713Y54042I-59J191D01*
G01X1042783D01*
G03X1042641Y53983I0J-200D01*
G01X1040701Y52043D01*
G03X1040642Y51901I141J-142D01*
G01Y9358D01*
G02X1040601Y9237I-200J0D01*
G01X1040593Y9228D01*
X1040586Y9221D01*
G03X1040573Y9206I143J-137D01*
G01X1038048Y6681D01*
G02X1037981Y6637I-141J142D01*
G01X1037947Y6623D01*
X994553D01*
G02X994432Y6664I0J200D01*
G01X994423Y6672D01*
X994416Y6679D01*
G03X994401Y6692I-137J-143D01*
G01X991565Y9528D01*
G02X991521Y9595I142J141D01*
G01X991507Y9629D01*
Y50683D01*
G03X991448Y50825I-200J0D01*
G01X989752Y52521D01*
G02X989924Y53188I283J283D01*
G03X996254Y61614I-2443J8426D01*
G03X978706I-8774J0D01*
G03X982449Y54425I8775J0D01*
G01X982452Y54423D01*
X982488Y54396D01*
G02X982546Y54313I-129J-152D01*
G02X982551Y54297I-188J-68D01*
G01Y54190D01*
G02X982368Y54042I-193J52D01*
G01X979986D01*
G02X979786Y54242I0J200D01*
G01Y54780D01*
G03X979728Y54921I-200J0D01*
G01X979118Y55531D01*
G03X978976Y55590I-142J-141D01*
G01X949468D01*
G03X944517Y54093I0J-8936D01*
G01X944493Y54077D01*
X944409Y54051D01*
X944380Y54042D01*
X942146D01*
G03X941946Y53842I0J-200D01*
G01Y51604D01*
G02X941905Y51483I-200J0D01*
G01X941897Y51474D01*
X941890Y51467D01*
G03X941877Y51452I143J-137D01*
G01X939509Y49084D01*
G03X939450Y48942I141J-142D01*
G01Y3933D01*
G02X939391Y3791I-200J0D01*
G01X938559Y2959D01*
G02X938417Y2900I-142J141D01*
G01X841283D01*
G02X841141Y2959I0J200D01*
G01X840234Y3866D01*
G02X840175Y4008I141J142D01*
G01Y51993D01*
G03X840116Y52135I-200J0D01*
G01X839432Y52819D01*
G02X839379Y52917I142J140D01*
G02X839381Y53013I195J44D01*
G01X839435Y53209D01*
Y53211D01*
X839469Y53334D01*
G02X839474Y53346I187J-71D01*
G01X839505Y53409D01*
G02X839536Y53441I158J-122D01*
G01X839586Y53479D01*
X839624Y53489D01*
G03X845882Y61614I-2145J8125D01*
G03X837480Y70016I-8402J0D01*
G03X829078Y61650I0J-8402D01*
G01Y61613D01*
G03X830291Y57264I8402J0D01*
G01X830298Y57253D01*
X830310Y57225D01*
X830318Y57209D01*
X830329Y57164D01*
G02X830320Y57052I-196J-41D01*
G01X830302Y57008D01*
X830272Y56979D01*
G03X830267Y56974I139J-144D01*
G02X830261Y56968I-144J138D01*
G03X830220Y56918I132J-150D01*
G01X830126Y56751D01*
X830106Y56732D01*
X830085Y56711D01*
X830077Y56705D01*
X830074Y56702D01*
X830063Y56692D01*
G02X829942Y56651I-121J159D01*
G01X809616D01*
G03X809474Y56592I0J-200D01*
G01X808759Y55877D01*
G02X808692Y55833I-141J142D01*
G01X808658Y55819D01*
X795058D01*
G03X794916Y55760I0J-200D01*
G01X790320Y51164D01*
G03X790261Y51022I141J-142D01*
G01Y9592D01*
G02X790220Y9471I-200J0D01*
G01X790212Y9462D01*
X790205Y9455D01*
G03X790192Y9440I143J-137D01*
G01X786853Y6101D01*
G02X786786Y6057I-141J142D01*
G01X786752Y6043D01*
X742370D01*
G02X742249Y6084I0J200D01*
G01X742240Y6092D01*
X742233Y6099D01*
G03X742218Y6112I-137J-143D01*
G01X739156Y9174D01*
G02X739112Y9241I142J141D01*
G01X739098Y9275D01*
Y53103D01*
G03X739039Y53245I-200J0D01*
G01X738808Y53476D01*
G02X738752Y53648I142J141D01*
G01Y53649D01*
X738801Y53957D01*
X738821Y53990D01*
X738832Y54009D01*
X738883Y54079D01*
G02X738912Y54109I158J-123D01*
G01X738927Y54121D01*
X738948Y54132D01*
G03X743520Y61614I-3836J7482D01*
G03X735118Y70016I-8402J0D01*
G03X726716Y61650I0J-8402D01*
G01Y61613D01*
G03X727929Y57264I8402J0D01*
G01X727936Y57253D01*
X727948Y57225D01*
X727956Y57209D01*
X727967Y57164D01*
G02X727958Y57052I-196J-41D01*
G01X727940Y57008D01*
X727910Y56979D01*
G03X727905Y56974I139J-144D01*
G02X727899Y56968I-144J138D01*
G03X727858Y56918I132J-150D01*
G01X727764Y56751D01*
X727744Y56732D01*
X727723Y56711D01*
X727715Y56705D01*
X727712Y56702D01*
X727701Y56692D01*
G02X727580Y56651I-121J159D01*
G01X693564D01*
G03X693422Y56592I0J-200D01*
G01X687579Y50749D01*
G03X687520Y50607I141J-142D01*
G01Y4503D01*
G02X687461Y4361I-200J0D01*
G01X686259Y3159D01*
G02X686117Y3100I-142J141D01*
G01X637283D01*
G02X637141Y3159I0J200D01*
G01X636970Y3330D01*
G02X636911Y3472I141J142D01*
G01Y49635D01*
G03X636852Y49777I-200J0D01*
G01X633971Y52658D01*
G02X633920Y52853I142J141D01*
G01X633976Y53028D01*
Y53030D01*
X634031Y53204D01*
G02X634174Y53332I189J-67D01*
G01X634186Y53334D01*
X634187D01*
G03X641158Y61614I-1432J8280D01*
G03X624354I-8402J0D01*
G01Y61526D01*
G03X625722Y57015I8403J85D01*
G01X625741Y56986D01*
X625748Y56961D01*
G02X625755Y56909I-193J-52D01*
G01Y56805D01*
G02X625747Y56784I-191J61D01*
G01X625573Y56463D01*
G02X625422Y56374I-167J111D01*
G01X625420D01*
G02X625405Y56373I-21J199D01*
G01X589159D01*
G03X589017Y56314I0J-200D01*
G01X585808Y53105D01*
G03X585749Y52963I141J-142D01*
G01Y9663D01*
G02X585708Y9542I-200J0D01*
G01X585700Y9533D01*
X585693Y9526D01*
G03X585680Y9511I143J-137D01*
G01X582687Y6518D01*
G02X582620Y6474I-141J142D01*
G01X582586Y6460D01*
X535708D01*
G02X535587Y6501I0J200D01*
G01X535578Y6509D01*
X535571Y6516D01*
G03X535556Y6529I-137J-143D01*
G01X534575Y7510D01*
G02X534531Y7577I142J141D01*
G01X534517Y7611D01*
Y51161D01*
G03X534458Y51303I-200J0D01*
G01X532887Y52874D01*
G03X532846Y52906I-143J-141D01*
G01X532798Y52934D01*
X532788Y52940D01*
X532763Y52998D01*
G02X532752Y53125I183J80D01*
G01X532802Y53332D01*
Y53334D01*
X532829Y53447D01*
G02X532881Y53542I195J-45D01*
G01X532911Y53572D01*
X532918Y53578D01*
G03X532931Y53590I-128J152D01*
G02X532952Y53605I127J-155D01*
G01X532968Y53615D01*
G03X538796Y61614I-2575J7999D01*
G03X530394Y70016I-8402J0D01*
G03X521992Y61624I0J-8402D01*
G01Y61613D01*
G03X522756Y58113I8402J1D01*
G01X522792Y58034D01*
Y58009D01*
X522795Y57996D01*
G02X522767Y57857I-197J-33D01*
G01X522766Y57855D01*
X522633Y57645D01*
X522585Y57570D01*
G02X522537Y57521I-165J113D01*
G02X522425Y57484I-116J163D01*
G01X488637D01*
G03X488495Y57425I0J-200D01*
G01X482650Y51580D01*
G03X482591Y51438I141J-142D01*
G01Y8205D01*
G02X482550Y8084I-200J0D01*
G01X482542Y8075D01*
X482535Y8068D01*
G03X482522Y8053I143J-137D01*
G01X480708Y6239D01*
G02X480641Y6195I-141J142D01*
G01X480607Y6181D01*
X389500D01*
G02X389379Y6222I0J200D01*
G01X389370Y6230D01*
X389363Y6237D01*
G03X389348Y6250I-137J-143D01*
G01X385315Y10283D01*
G02X385271Y10350I142J141D01*
G01X385257Y10384D01*
Y49081D01*
G03X385198Y49223I-200J0D01*
G01X381740Y52681D01*
G02X381688Y52773I142J141D01*
G01Y52846D01*
X381695Y52889D01*
G02X381701Y52917I198J-28D01*
G01X381768Y53132D01*
Y53134D01*
X381794Y53219D01*
G02X381825Y53280I191J-59D01*
G02X381853Y53311I162J-118D01*
G01X381873Y53328D01*
X381922Y53352D01*
X381949Y53357D01*
G03X388796Y61614I-1555J8257D01*
G03X380394Y70016I-8402J0D01*
G03X371992Y61659I0J-8402D01*
G01Y61611D01*
G03X373123Y57403I8402J2D01*
G01X373125Y57400D01*
X373126Y57398D01*
X373135Y57379D01*
X373141Y57366D01*
G02X373156Y57286I-185J-76D01*
G01X373155Y57265D01*
G02X373139Y57208I-199J25D01*
G01X373075Y57095D01*
X372959Y56891D01*
G02X372785Y56790I-174J99D01*
G01X351786D01*
G03X351644Y56731I0J-200D01*
G01X350929Y56016D01*
G02X350862Y55972I-141J142D01*
G01X350828Y55958D01*
X335148D01*
G03X335006Y55899I0J-200D01*
G01X332628Y53521D01*
G03X332569Y53379I141J-142D01*
G01Y29226D01*
G02X332568Y29207I-200J1D01*
G02X332516Y29090I-199J19D01*
G01X332502Y29076D01*
X332500Y29075D01*
G02X332474Y29056I-131J152D01*
G02X332450Y29044I-101J172D01*
G01X332285Y28970D01*
X332283D01*
X332227Y28944D01*
G02X332150Y28928I-78J184D01*
G01X331979D01*
G02X331927Y28935I0J200D01*
G01X331878Y28951D01*
X331848Y28975D01*
G03X330905Y29308I-943J-1169D01*
G03Y26304I0J-1502D01*
G03X331883Y26666I0J1502D01*
G01X331905Y26685D01*
X331964Y26712D01*
G02X332020Y26728I82J-182D01*
G02X332041Y26729I20J-199D01*
G01X332077Y26726D01*
X332121Y26716D01*
X332283Y26642D01*
X332285D01*
X332451Y26568D01*
X332456Y26565D01*
X332477Y26556D01*
X332520Y26519D01*
X332536Y26495D01*
G02X332569Y26385I-167J-110D01*
G01Y21226D01*
G02X332568Y21207I-200J1D01*
G02X332516Y21090I-199J19D01*
G01X332502Y21076D01*
X332500Y21075D01*
G02X332474Y21056I-131J152D01*
G02X332450Y21044I-101J172D01*
G01X332285Y20970D01*
X332283D01*
X332227Y20944D01*
G02X332150Y20928I-78J184D01*
G01X331979D01*
G02X331927Y20935I0J200D01*
G01X331878Y20951D01*
X331848Y20975D01*
G03X330905Y21308I-943J-1169D01*
G03Y18304I0J-1502D01*
G03X331883Y18666I0J1502D01*
G01X331905Y18685D01*
X331964Y18712D01*
G02X332020Y18728I82J-182D01*
G02X332041Y18729I20J-199D01*
G01X332077Y18726D01*
X332121Y18716D01*
X332283Y18642D01*
X332285D01*
X332451Y18568D01*
X332456Y18565D01*
X332477Y18556D01*
X332520Y18519D01*
X332536Y18495D01*
G02X332569Y18385I-167J-110D01*
G01Y17226D01*
G02X332568Y17207I-200J1D01*
G02X332516Y17090I-199J19D01*
G01X332502Y17076D01*
X332500Y17075D01*
G02X332474Y17056I-131J152D01*
G02X332450Y17044I-101J172D01*
G01X332285Y16970D01*
X332283D01*
X332227Y16944D01*
G02X332150Y16928I-78J184D01*
G01X331979D01*
G02X331927Y16935I0J200D01*
G01X331878Y16951D01*
X331848Y16975D01*
G03X330905Y17308I-943J-1169D01*
G03Y14304I0J-1502D01*
G03X331883Y14666I0J1502D01*
G01X331905Y14685D01*
X331964Y14712D01*
G02X332020Y14728I82J-182D01*
G02X332041Y14729I20J-199D01*
G01X332077Y14726D01*
X332121Y14716D01*
X332283Y14642D01*
X332285D01*
X332451Y14568D01*
X332456Y14565D01*
X332477Y14556D01*
X332520Y14519D01*
X332536Y14495D01*
G02X332569Y14385I-167J-110D01*
G01Y8067D01*
G02X332528Y7946I-200J0D01*
G01X332520Y7937D01*
X332513Y7930D01*
G03X332500Y7915I143J-137D01*
G01X330270Y5685D01*
G02X330203Y5641I-141J142D01*
G01X330169Y5627D01*
X284818D01*
G02X284697Y5668I0J200D01*
G01X284688Y5676D01*
X284681Y5683D01*
G03X284666Y5696I-137J-143D01*
G01X281465Y8897D01*
G02X281421Y8964I142J141D01*
G01X281407Y8998D01*
Y17944D01*
G02X281452Y18070I200J0D01*
G01X281474Y18096D01*
X281533Y18132D01*
X281568Y18139D01*
G03X282780Y19613I-290J1474D01*
G03X281691Y21057I-1502J0D01*
G01X281690D01*
X281675Y21061D01*
G02X281567Y21158I71J187D01*
G01Y21160D01*
G02X281545Y21249I178J91D01*
G01Y50052D01*
G03X281486Y50194I-200J0D01*
G01X279102Y52578D01*
G02X279058Y52645I142J141D01*
G01X279044Y52679D01*
Y52913D01*
X279052Y52962D01*
G02X279059Y52993I198J-28D01*
G01X279089Y53085D01*
Y53087D01*
X279116Y53167D01*
G02X279242Y53294I190J-62D01*
G01X279274Y53304D01*
X279291Y53307D01*
G03X286434Y61614I-1259J8307D01*
G03X278032Y70016I-8402J0D01*
G01X278031D01*
G03X269629Y61614I0J-8402D01*
G01Y61613D01*
G03X270550Y57788I8402J0D01*
G01X270553Y57783D01*
Y57782D01*
G02X270572Y57689I-181J-85D01*
G01X270570Y57638D01*
X270364Y57302D01*
G02X270346Y57277I-171J104D01*
G02X270204Y57206I-153J129D01*
G01X237260D01*
G03X237118Y57147I0J-200D01*
G01X230026Y50055D01*
G03X229967Y49913I141J-142D01*
G01Y6820D01*
G02X229926Y6699I-200J0D01*
G01X229918Y6690D01*
X229911Y6683D01*
G03X229898Y6668I145J-138D01*
G01X229331Y6101D01*
G02X229264Y6057I-141J142D01*
G01X229230Y6043D01*
X182630D01*
G02X182509Y6084I0J200D01*
G01X182500Y6092D01*
X182493Y6099D01*
G03X182478Y6112I-137J-143D01*
G01X179971Y8619D01*
G02X179927Y8686I142J141D01*
G01X179913Y8720D01*
Y50606D01*
G03X179854Y50748I-200J0D01*
G01X177749Y52853D01*
G02X177691Y53002I142J141D01*
G01Y53024D01*
X177769Y53319D01*
X177777Y53352D01*
X177809Y53400D01*
G02X177829Y53424I163J-116D01*
G01X177890Y53485D01*
G02X177930Y53516I142J-141D01*
G01X177951Y53528D01*
X177976Y53535D01*
G03X184071Y61614I-2307J8079D01*
G03X175669Y70016I-8402J0D01*
G03X175469Y70014I-16J-8402D01*
G03X167267Y61659I200J-8400D01*
G01Y61611D01*
G03X168398Y57403I8402J2D01*
G01X168400Y57400D01*
X168401Y57398D01*
X168410Y57379D01*
X168416Y57366D01*
G02X168431Y57286I-185J-76D01*
G01X168430Y57265D01*
G02X168414Y57208I-199J25D01*
G01X168350Y57095D01*
X168234Y56891D01*
G02X168060Y56790I-174J99D01*
G01X129250D01*
G03X129108Y56731I0J-200D01*
G01X126453Y54076D01*
G03X126394Y53934I141J-142D01*
G01Y8760D01*
G02X126353Y8639I-200J0D01*
G01X126345Y8630D01*
X126338Y8623D01*
G03X126325Y8608I143J-137D01*
G01X123956Y6239D01*
G02X123889Y6195I-141J142D01*
G01X123855Y6181D01*
X79751D01*
G02X79630Y6222I0J200D01*
G01X79621Y6230D01*
X79614Y6237D01*
G03X79599Y6250I-137J-143D01*
G01X78201Y7648D01*
G02X78157Y7715I142J141D01*
G01X78143Y7749D01*
Y49635D01*
G03X78084Y49777I-200J0D01*
G01X75087Y52774D01*
G02X75035Y52964I142J141D01*
G01Y52966D01*
X75125Y53291D01*
G02X75157Y53349I189J-66D01*
G01X75167Y53360D01*
X75171Y53364D01*
G03X75180Y53374I-143J138D01*
G02X75225Y53406I137J-145D01*
G01X75270Y53428D01*
X75292Y53433D01*
G03X81723Y61614I-1988J8181D01*
G03X64891I-8416J0D01*
G03X66448Y56737I8417J0D01*
G01X66460Y56720D01*
X66463Y56716D01*
X66489Y56645D01*
G02X66496Y56597I-193J-53D01*
G01X66495Y56572D01*
G02X66479Y56511I-199J20D01*
G01X66476Y56506D01*
Y56505D01*
X66318Y56196D01*
G02X66145Y56096I-173J100D01*
G01X31638D01*
G03X31496Y56037I0J-200D01*
G01X30627Y55168D01*
X30612Y55155D01*
G02X30481Y55106I-131J151D01*
G01X30442D01*
X30303Y55160D01*
X30301D01*
X30057Y55256D01*
G02X30050Y55259I75J185D01*
G02X30022Y55277I94J176D01*
G01X29999Y55317D01*
X29944Y55412D01*
X29940Y55454D01*
Y55458D01*
G03X26950Y55520I-1498J-117D01*
G01X26944Y55462D01*
G03X28357Y53840I1498J-122D01*
G01X28388Y53838D01*
X28440Y53819D01*
X28464Y53802D01*
G02X28531Y53716I-118J-161D01*
G01X28627Y53464D01*
X28629Y53459D01*
G03X28632Y53451I189J66D01*
G01Y53450D01*
G03X28649Y53416I187J72D01*
G01X28650Y53414D01*
X28659Y53397D01*
G02X28678Y53312I-181J-85D01*
G01Y53257D01*
X28648Y53199D01*
G02X28634Y53177I-175J96D01*
G02X28618Y53159I-157J124D01*
G01X25514Y50055D01*
G03X25455Y49913I141J-142D01*
G01Y10424D01*
G02X25414Y10303I-200J0D01*
G01X25406Y10294D01*
X25399Y10287D01*
G03X25386Y10272I143J-137D01*
G01X22324Y7210D01*
G02X22257Y7166I-141J142D01*
G01X22223Y7152D01*
X8206D01*
G02X8085Y7193I0J200D01*
G01X8076Y7201D01*
X8069Y7208D01*
G03X8054Y7221I-137J-143D01*
G01X5963Y9312D01*
G02X5919Y9379I142J141D01*
G01X5905Y9413D01*
Y69334D01*
G02X5915Y69397I200J1D01*
G01X5918Y69406D01*
G02X6008Y69516I190J-63D01*
G01X6173Y69612D01*
X6175D01*
X6312Y69690D01*
G02X6403Y69713I93J-177D01*
G01X6461D01*
X6507Y69686D01*
X6508D01*
X6530Y69674D01*
G03X7269Y69479I740J1307D01*
G01X7287D01*
G03X8771Y70903I-16J1502D01*
G01Y70906D01*
X8772Y70921D01*
Y70929D01*
G03X8773Y70980I-1501J55D01*
G01Y71004D01*
G03X7282Y72483I-1502J-23D01*
G01X7268D01*
G03X6527Y72287I1J-1502D01*
G01X6504Y72274D01*
X6450Y72260D01*
G02X6300Y72279I-52J193D01*
G01X6157Y72360D01*
X6155D01*
X6007Y72445D01*
G02X5967Y72475I99J174D01*
G01X5960Y72482D01*
G02X5905Y72620I145J138D01*
G01Y90399D01*
G02X5908Y90431I200J-3D01*
G01Y90433D01*
G02X5962Y90539I197J-34D01*
G01X7295Y91872D01*
G03X7354Y92014I-141J142D01*
G01Y100596D01*
X7358Y100632D01*
X7361Y100660D01*
X7374Y100694D01*
G02X7392Y100725I181J-84D01*
G01X7417Y100759D01*
X7489Y100823D01*
X7491Y100825D01*
X7647Y100961D01*
X7679Y100989D01*
X7760Y101014D01*
X7804Y101009D01*
X7807D01*
X7819Y101008D01*
G03X7995Y100998I173J1492D01*
G01X8000D01*
G03Y104002I0J1502D01*
G03X7807Y103990I-3J-1502D01*
G01X7782Y103987D01*
G02X7722Y103996I-1J200D01*
G01X7685Y104008D01*
X7492Y104174D01*
X7489Y104177D01*
X7390Y104261D01*
X7372Y104302D01*
X7354Y104341D01*
Y134425D01*
G02X7362Y134480I200J-1D01*
G01Y134482D01*
G02X7456Y134601I192J-55D01*
G01X7474Y134611D01*
X7786Y134743D01*
X7806Y134751D01*
X7854Y134761D01*
G02X7949Y134759I43J-195D01*
G01X7977Y134751D01*
X8019Y134727D01*
X8038Y134709D01*
X8039Y134708D01*
G03X9082Y134287I1043J1081D01*
G03X10584Y135789I0J1502D01*
G03X9914Y137039I-1501J0D01*
G01X9910Y137042D01*
X9891Y137055D01*
X9858Y137091D01*
X9848Y137111D01*
G02X9825Y137204I177J93D01*
G01Y137261D01*
X9822Y137529D01*
Y137534D01*
G02X9832Y137595I200J-1D01*
G01X9846Y137634D01*
X9891Y137686D01*
X9912Y137702D01*
X9914Y137704D01*
X9921Y137709D01*
X9923Y137711D01*
X9924D01*
G03X10559Y138938I-869J1227D01*
G01Y138939D01*
G03X9082Y140441I-1502J0D01*
G01X9055D01*
G03X8053Y140057I1J-1502D01*
G01X8026Y140032D01*
X7936Y139998D01*
G02X7873Y139987I-65J189D01*
G01X7828D01*
X7697Y140044D01*
X7479Y140140D01*
G02X7391Y140214I79J184D01*
G01X7373Y140240D01*
X7364Y140268D01*
G02X7354Y140330I190J62D01*
G01Y253409D01*
G02X7403Y253540I200J0D01*
G02X7435Y253570I152J-130D01*
G02X7464Y253587I115J-163D01*
G01X7702Y253698D01*
G03X7735Y253718I-87J180D01*
G01X7768Y253743D01*
X7845Y253762D01*
X7888Y253756D01*
G02X7924Y253746I-35J-197D01*
G01X7925D01*
X8009Y253716D01*
X8035Y253695D01*
G03X8969Y253369I934J1176D01*
G01X8970D01*
G03X10462Y254695I0J1502D01*
G01X10468Y254749D01*
G03X9153Y256363I-1498J122D01*
G01X9089Y256369D01*
G03X8970Y256374I-123J-1498D01*
G01X8969D01*
G03X8032Y256046I0J-1503D01*
G01X8006Y256025D01*
X7916Y255992D01*
G02X7774Y256007I-51J193D01*
G01X7773D01*
X7699Y256045D01*
X7697D01*
X7532Y256124D01*
X7530D01*
X7464Y256155D01*
G02X7395Y256212I90J179D01*
G01X7365Y256252D01*
X7357Y256301D01*
X7354Y256319D01*
Y266731D01*
X7357Y266752D01*
Y266790D01*
X7379Y266833D01*
G02X7434Y266898I177J-94D01*
G01X7492Y266939D01*
X7519Y266948D01*
G03X7520Y269794I-483J1423D01*
G01X7519D01*
X7491Y269804D01*
X7439Y269841D01*
G02X7362Y269947I114J164D01*
G01X7354Y269976D01*
Y270731D01*
X7357Y270752D01*
Y270790D01*
X7379Y270833D01*
G02X7434Y270898I177J-94D01*
G01X7492Y270939D01*
X7519Y270948D01*
G03X7520Y273794I-483J1423D01*
G01X7519D01*
X7491Y273804D01*
X7439Y273841D01*
G02X7362Y273947I114J164D01*
G01X7354Y273976D01*
Y278834D01*
G02X7359Y278878I200J0D01*
G01X7365Y278905D01*
G02X7441Y279017I194J-50D01*
G01X7442Y279018D01*
X7624Y279150D01*
X7688Y279196D01*
G02X7714Y279212I118J-162D01*
G01X7729Y279219D01*
G02X7818Y279240I89J-179D01*
G01X7853D01*
X7914Y279220D01*
G03X8334Y279160I420J1443D01*
G01X8335D01*
G03X9838Y280663I0J1503D01*
G03X8465Y282161I-1504J0D01*
G01X8461D01*
X8452Y282162D01*
G03X8336Y282166I-110J-1499D01*
G01X8334D01*
G03X7893Y282100I0J-1503D01*
G01X7860Y282089D01*
X7811D01*
G02X7756Y282097I1J200D01*
G01X7717Y282109D01*
X7648Y282158D01*
G02X7646Y282160I139J141D01*
G01X7591Y282200D01*
X7589D01*
X7422Y282323D01*
G02X7354Y282465I132J150D01*
G01Y285644D01*
G02X7395Y285765I200J0D01*
G01X7399Y285769D01*
X7408Y285779D01*
G03X7410Y285782I-163J111D01*
G03X7419Y285792I-143J138D01*
G01X7424Y285797D01*
X7426Y285800D01*
G03X7478Y285934I-148J135D01*
G01Y297381D01*
G02X7521Y297495I200J-10D01*
G02X7559Y297531I155J-126D01*
G01X7743Y297647D01*
X7828Y297700D01*
G02X7933Y297730I105J-170D01*
G01X8033D01*
X8072Y297712D01*
G03X8691Y297579I619J1372D01*
G01X8709D01*
G03Y300583I0J1502D01*
G03X8129Y300466I1J-1502D01*
G01X8092Y300450D01*
X8091D01*
X8078Y300444D01*
X8066Y300439D01*
X8051Y300432D01*
X8034Y300425D01*
G02X7999Y300415I-72J186D01*
G02X7967Y300412I-35J197D01*
G01X7933Y300415D01*
G02X7855Y300446I33J197D01*
G01X7832Y300461D01*
X7831Y300462D01*
X7810Y300475D01*
X7570Y300626D01*
X7569Y300627D01*
G02X7502Y300697I107J169D01*
G01X7491Y300718D01*
X7483Y300752D01*
G02X7478Y300793I195J45D01*
G01Y321871D01*
G02X7481Y321903I200J-3D01*
G01Y321905D01*
G02X7535Y322011I197J-34D01*
G01X22464Y336940D01*
G03X22523Y337082I-141J142D01*
G01Y545347D01*
G02X22979Y545742I400J-1D01*
G02X23092Y545686I-28J-198D01*
G01X24176Y544602D01*
X24179Y544596D01*
X24181Y544591D01*
X24189Y544529D01*
Y544528D01*
G03X25819Y543084I1630J198D01*
G03X26312Y543160I-1J1642D01*
G01X26344Y543170D01*
X26374D01*
G02X26412Y543165I-7J-200D01*
G01X26432Y543161D01*
G02X26434Y543160I-88J-178D01*
G01X26490Y543141D01*
X26520Y543125D01*
X26628Y543042D01*
X26645Y543025D01*
G02X26662Y543005I-144J-139D01*
G01Y530739D01*
G02X26640Y530648I-200J0D01*
G02X26604Y530598I-178J90D01*
G01X24976Y528970D01*
X24971Y528966D01*
G03X24317Y527726I849J-1240D01*
G03X25819Y526224I1502J0D01*
G03X27311Y527548I0J1503D01*
G01X27315Y527582D01*
X27344Y527642D01*
X28893Y529191D01*
G03X29276Y530115I-923J924D01*
G01Y532502D01*
X29280Y532508D01*
G02X29315Y532546I163J-115D01*
G01X29375Y532591D01*
X29378Y532594D01*
X29576Y532741D01*
G02X29593Y532752I117J-163D01*
G01X29601Y532756D01*
G02X29657Y532776I95J-176D01*
G01X29700Y532784D01*
G03X30175Y532707I475J1427D01*
G01X30177D01*
G03Y535715I0J1504D01*
G01X30175D01*
G03X29709Y535641I0J-1504D01*
G01X29672Y535644D01*
G02X29622Y535656I21J199D01*
G01X29596Y535666D01*
X29573Y535683D01*
X29409Y535804D01*
G02X29407Y535806I139J141D01*
G01X29374Y535831D01*
X29358Y535843D01*
X29299Y535888D01*
G02X29276Y535914I138J145D01*
G01Y570346D01*
G03X28893Y571270I-1306J0D01*
G01X25588Y574575D01*
G02X25552Y574625I142J140D01*
G02X25530Y574716I178J91D01*
G01Y610603D01*
G02X25534Y610641I200J-2D01*
G02X25587Y610743I196J-37D01*
G01X33128Y618284D01*
G03X33510Y619206I-924J923D01*
G01Y632428D01*
G02X33511Y632447I200J-1D01*
G02X33514Y632470I200J-14D01*
G02X33569Y632570I196J-42D01*
G01X34607Y633607D01*
G02X34635Y633609I28J-198D01*
G01X34868D01*
G02X34896Y633607I0J-200D01*
G01X34938Y633601D01*
X34983Y633588D01*
X35033Y633573D01*
G02X35082Y633551I-57J-192D01*
G01X35104Y633537D01*
X35123Y633517D01*
X35128Y633512D01*
X35179Y633455D01*
G02X35225Y633368I-148J-134D01*
G03X36692Y632214I1467J355D01*
G03X38202Y633724I0J1510D01*
G03X37854Y634688I-1509J0D01*
G02X37839Y634746I184J79D01*
G01X37834Y634798D01*
X37945Y635030D01*
X37964Y635069D01*
X38017Y635178D01*
X38018Y635180D01*
G02X38073Y635246I178J-92D01*
G01X40789D01*
G02X40856Y635171I-111J-166D01*
G02X40858Y635167I-178J-91D01*
G01X40910Y635060D01*
X40969Y634938D01*
G02X40989Y634851I-180J-87D01*
G01Y634712D01*
G02X40968Y634623I-200J0D01*
G01X40958Y634603D01*
X40949Y634590D01*
X40948Y634589D01*
G03X40670Y633724I1225J-871D01*
G01Y633714D01*
G03X40677Y633570I1502J1D01*
G01X40678Y633560D01*
X40680Y633538D01*
G03X42172Y632214I1492J179D01*
G03X43664Y633540I0J1502D01*
G01X43670Y633594D01*
G03X43675Y633716I-1498J122D01*
G03X43373Y634620I-1504J0D01*
G01X43354Y634645D01*
X43325Y634730D01*
G02X43320Y634757I194J50D01*
G01X43319Y634792D01*
G02X43334Y634856I200J-13D01*
G01X43428Y635048D01*
Y635050D01*
X43491Y635177D01*
G02X43547Y635246I179J-88D01*
G01X45788D01*
G02X45838Y635189I-123J-158D01*
G01Y635187D01*
G02X45844Y635177I-168J-108D01*
G01X45924Y635017D01*
Y635015D01*
X46007Y634845D01*
G02X46024Y634748I-182J-82D01*
G01X46022Y634721D01*
X46001Y634669D01*
X45993Y634658D01*
X45982Y634644D01*
G03X45963Y634618I1203J-899D01*
G03X45961Y634616I139J-141D01*
G03X45882Y634494I1220J-877D01*
G03X45881Y634492I178J-90D01*
G03X45677Y633737I1301J-756D01*
G01Y633736D01*
G03X48681I1502J0D01*
G03X48393Y634621I-1504J0D01*
G01X48375Y634646D01*
X48353Y634709D01*
X48347Y634727D01*
X48342Y634754D01*
X48340Y634786D01*
X48338Y634821D01*
X48347Y634854D01*
G02X48378Y634917I192J-55D01*
G01X48393Y634938D01*
G03X48409Y634965I-163J115D01*
G01X48434Y635015D01*
Y635017D01*
X48514Y635177D01*
G02X48517Y635183I180J-86D01*
G02X48570Y635246I176J-95D01*
G01X53044D01*
G02X53103Y635170I-124J-157D01*
G01X53105Y635165D01*
X53174Y634986D01*
Y634984D01*
X53231Y634833D01*
Y634831D01*
X53245Y634797D01*
Y634760D01*
G02X53231Y634692I-200J6D01*
G01X53190Y634594D01*
X53160Y634565D01*
X53159Y634564D01*
G03X52690Y633474I1033J-1090D01*
G01Y633454D01*
G03X54192Y631971I1502J19D01*
G03X55694Y633473I0J1502D01*
G01Y633476D01*
G03X55196Y634593I-1503J0D01*
G01X55172Y634616D01*
X55158Y634639D01*
X55144Y634663D01*
X55138Y634684D01*
X55133Y634706D01*
G02X55140Y634805I196J36D01*
G01X55189Y634933D01*
X55280Y635168D01*
G02X55340Y635246I184J-79D01*
G01X59062D01*
G03X60016Y635660I-1J1308D01*
G02X60020Y635664I143J-139D01*
G01X65039Y640683D01*
G02X65077Y640713I142J-141D01*
G01X65136Y640748D01*
G02X65138Y640749I89J-176D01*
G03X66194Y642184I-447J1435D01*
G03X64692Y643686I-1502J0D01*
G03X63258Y642631I0J-1502D01*
G02X63257Y642629I-177J87D01*
G01X63222Y642570D01*
G02X63192Y642532I-171J104D01*
G01X60424Y639763D01*
X58567Y637907D01*
G02X58466Y637862I-129J153D01*
G01X35706D01*
G03X34752Y637448I1J-1308D01*
G02X34748Y637444I-143J139D01*
G01X31280Y633976D01*
G03X30898Y633054I924J-923D01*
G01Y619832D01*
G02X30896Y619801I-200J-3D01*
G02X30841Y619692I-198J31D01*
G01X26436Y615288D01*
X24267Y613119D01*
G02X24154Y613063I-141J142D01*
G02X24042I-56J396D01*
G02X23783Y613213I56J396D01*
G02X23781Y613215I139J141D01*
G02X23780Y613217I351J177D01*
G03X23779Y613219I-177J-87D01*
G02X23738Y613339I159J121D01*
G01Y619433D01*
G02X23778Y619553I200J0D01*
G01X25630Y621406D01*
G02X25689Y621405I26J-198D01*
G01X25716Y621399D01*
X25966Y621315D01*
X25967D01*
X25998Y621304D01*
G02X26086Y621253I-53J-193D01*
G01X26096Y621243D01*
X26157Y621167D01*
X26178Y621141D01*
X26198Y621097D01*
X26201Y621079D01*
X26202Y621075D01*
X26203Y621068D01*
G03X27686Y619809I1483J244D01*
G03X29178Y621135I0J1502D01*
G01X29184Y621189D01*
G03X27932Y622794I-1498J122D01*
G01X27930D01*
X27902Y622799D01*
X27882Y622808D01*
G02X27858Y622821I83J182D01*
G03X27856Y622823I-139J-137D01*
G02X27841Y622833I103J171D01*
G01X27779Y622882D01*
X27778Y622883D01*
G03X27776Y622885I-141J-139D01*
G03X27766Y622892I-120J-160D01*
G01X27764Y622893D01*
X27744Y622908D01*
X27726Y622931D01*
G02X27697Y622988I161J118D01*
G01X27652Y623120D01*
X27595Y623286D01*
G02X27590Y623365I193J52D01*
G01X28085Y623861D01*
X28106Y623868D01*
X28131Y623875D01*
G03X29188Y625311I-447J1436D01*
G03X27686Y626813I-1502J0D01*
G03X26252Y625757I0J-1502D01*
G01X26248Y625743D01*
G02X26215Y625689I-185J76D01*
G01X23080Y622554D01*
G02X22979Y622509I-129J153D01*
G02X22523Y622904I-56J396D01*
G01Y988804D01*
G02X22526Y988836I200J-3D01*
G01Y988838D01*
G02X22580Y988944I197J-34D01*
G01X27971Y994335D01*
G02X28077Y994389I140J-143D01*
G01X28079D01*
G02X28111Y994392I35J-197D01*
G01X52762D01*
G02X52794Y994389I-3J-200D01*
G01X52796D01*
G02X52902Y994335I-34J-197D01*
G01X59617Y987620D01*
G02X59671Y987514I-143J-140D01*
G01Y987512D01*
G02X59674Y987480I-197J-35D01*
G01Y911872D01*
G02X59587Y911717I-200J10D01*
G02X59535Y911692I-112J166D01*
G01X59489Y911677D01*
G03X59531Y908812I473J-1426D01*
G01X59547Y908807D01*
G02X59635Y908740I-73J-187D01*
G01X59654Y908715D01*
X59664Y908684D01*
G02X59674Y908622I-190J-62D01*
G01Y873889D01*
G03X59733Y873747I200J0D01*
G01X62789Y870691D01*
G02X62847Y870539I-142J-141D01*
G01X62846Y870508D01*
X62837Y870484D01*
G02X62813Y870438I-188J69D01*
G01X62802Y870424D01*
G03X62465Y869476I1167J-949D01*
G01Y869475D01*
G03X63969Y867971I1504J0D01*
G01X63970D01*
G03X64885Y868282I0J1503D01*
G01X64891Y868287D01*
X64898Y868292D01*
X64904Y868295D01*
X64932Y868311D01*
G02X64959Y868323I94J-176D01*
G01X64995Y868337D01*
G02X65118Y868334I57J-192D01*
G01X65129Y868330D01*
G02X65178Y868300I-79J-184D01*
G01X65195Y868285D01*
X66028Y867452D01*
G03X66170Y867393I142J141D01*
G01X102392D01*
G02X102460Y867381I0J-200D01*
G01X102493Y867369D01*
X102520Y867347D01*
X102558Y867315D01*
X102572Y867297D01*
G03X104948Y867274I1197J909D01*
G01X104956Y867284D01*
X104957Y867285D01*
X104964Y867294D01*
X104965Y867295D01*
X104978Y867312D01*
X105028Y867354D01*
G02X105079Y867381I118J-161D01*
G01X105081D01*
G02X105147Y867393I68J-188D01*
G01X135746D01*
G02X135778Y867390I-3J-200D01*
G01X135780D01*
G02X135886Y867336I-34J-197D01*
G01X143659Y859563D01*
G02X143714Y859385I-142J-141D01*
G01Y859384D01*
X110225Y682546D01*
X89395Y572557D01*
G03X89359Y572331I3824J-725D01*
G01X89024Y569738D01*
X79800Y499609D01*
G02X79658Y499464I-194J48D01*
G01X79645Y499461D01*
X79505Y499426D01*
G02X79469Y499422I-40J196D01*
G01X79468D01*
X79457Y499423D01*
X79438Y499424D01*
X79431D01*
G02X79369Y499442I24J199D01*
G01X79261Y499497D01*
X79238Y499532D01*
X79236Y499534D01*
X79227Y499545D01*
G03X78839Y499900I-1193J-915D01*
G03X78241Y500121I-808J-1266D01*
G03X78064Y500135I-207J-1488D01*
G01X78033D01*
G03X76531Y498652I0J-1502D01*
G01Y498633D01*
G03X76535Y498517I1502J-6D01*
G01X76538Y498474D01*
X76523Y498433D01*
G02X76477Y498361I-188J69D01*
G01X76468Y498352D01*
X76464Y498277D01*
G03X76507Y498143I200J-10D01*
G01X76840Y497720D01*
X76841Y497718D01*
X76842Y497717D01*
G02X76848Y497710I-149J-134D01*
G01X76853Y497703D01*
X76854Y497702D01*
G03X76858Y497697I158J122D01*
G01X76860Y497694D01*
X76873Y497676D01*
X76887Y497645D01*
G02X76901Y497572I-186J-73D01*
G01Y497488D01*
G03X76919Y497405I200J0D01*
G01X76943Y497352D01*
G02X76918Y497144I-181J-84D01*
G01X76896Y497116D01*
X76882Y497098D01*
X76880Y497095D01*
X76878Y497093D01*
X76875Y497089D01*
G03X76531Y496149I1158J-957D01*
G01Y496137D01*
G03X76647Y495553I1502J-5D01*
G03X76857Y495197I1387J578D01*
G01X76872Y495178D01*
X76882Y495157D01*
G02X76901Y495072I-181J-85D01*
G01Y494988D01*
G03X76919Y494905I200J0D01*
G01X76943Y494852D01*
G02X76918Y494644I-181J-84D01*
G01X76896Y494616D01*
X76882Y494598D01*
X76880Y494595D01*
X76878Y494593D01*
X76875Y494589D01*
G03X76531Y493649I1158J-957D01*
G01Y493637D01*
G03X76647Y493053I1502J-5D01*
G03X76857Y492697I1387J578D01*
G01X76872Y492678D01*
X76882Y492657D01*
G02X76901Y492572I-181J-85D01*
G01Y492488D01*
G03X76919Y492405I200J0D01*
G01X76943Y492352D01*
G02X76918Y492144I-181J-84D01*
G01X76896Y492116D01*
X76882Y492098D01*
X76880Y492095D01*
X76874Y492088D01*
G03X76533Y491210I1159J-955D01*
G03X76531Y491137I1500J-78D01*
G01Y491133D01*
G03X78033Y489631I1502J0D01*
G03X78187Y489639I-1J1502D01*
G01X78198Y489640D01*
X78215D01*
G02X78358Y489580I0J-200D01*
G01X78432Y489504D01*
X78449Y489486D01*
X78467Y489468D01*
X77909Y485231D01*
G02X77856Y485120I-198J26D01*
G01X77836Y485098D01*
X77781Y485068D01*
X77749Y485062D01*
G03X76541Y483762I284J-1475D01*
G01X76537Y483725D01*
G03X76532Y483648I1496J-136D01*
G03X76531Y483586I1501J-55D01*
G03Y483584I1502J-1D01*
G01Y483583D01*
G03X76535Y483470I1502J-3D01*
G01X76538Y483427D01*
X76523Y483386D01*
G02X76477Y483314I-188J69D01*
G01X76468Y483305D01*
X76464Y483230D01*
G03X76507Y483096I200J-10D01*
G01X76840Y482673D01*
X76841Y482671D01*
X76842Y482670D01*
G02X76848Y482663I-149J-134D01*
G01X76853Y482656D01*
X76854Y482655D01*
G03X76858Y482650I158J122D01*
G01X76860Y482647D01*
X76873Y482629D01*
X76887Y482598D01*
G02X76901Y482525I-186J-73D01*
G01Y482438D01*
G03X76917Y482360I200J0D01*
G01X76944Y482298D01*
X76945Y482295D01*
X76955Y482273D01*
X76959Y482243D01*
G02Y482193I-198J-25D01*
G01X76954Y482157D01*
X76930Y482107D01*
X76909Y482083D01*
G03X76903Y482076I1137J-981D01*
G01X76898Y482070D01*
X76892Y482064D01*
X76883Y482053D01*
X76858Y482022D01*
G03X76841Y482000I1180J-929D01*
G03X76826Y481980I1194J-911D01*
G03X76531Y481086I1207J-894D01*
G03Y481075I1502J-5D01*
G01Y481047D01*
G03X76535Y480971I1501J41D01*
G01X76536Y480959D01*
G03X76559Y480797I1496J130D01*
G03X76736Y480328I1474J288D01*
G03X76770Y480273I1294J762D01*
G01Y480271D01*
G03X76846Y480165I1258J821D01*
G01X76849Y480162D01*
X76871Y480129D01*
G02X76901Y480025I-170J-105D01*
G01Y479941D01*
G03X76919Y479858I200J0D01*
G01X76943Y479805D01*
G02X76918Y479597I-181J-84D01*
G01X76896Y479569D01*
X76882Y479551D01*
X76880Y479548D01*
X76878Y479546D01*
X76875Y479542D01*
G03X76531Y478602I1158J-957D01*
G01Y478590D01*
G03X76633Y478042I1502J-4D01*
G01Y478040D01*
G03X76647Y478007I1390J570D01*
G01Y478005D01*
G03X76659Y477979I1370J616D01*
G02X76663Y477971I-177J-93D01*
G03X76675Y477942I1394J560D01*
G03X76677Y477940I134J132D01*
G03X76852Y477656I1359J641D01*
G01X76872Y477630D01*
X76882Y477610D01*
G02X76899Y477552I-181J-85D01*
G01X76849Y477172D01*
X76824Y476978D01*
X76803Y476948D01*
G03X76793Y476933I1244J-840D01*
G02X76790Y476929I-161J118D01*
G03X76575Y476445I1244J-842D01*
G03X76533Y476172I1456J-364D01*
G01Y476170D01*
G03X76531Y476095I1500J-78D01*
G01Y476078D01*
G03X76542Y475901I1501J4D01*
G03X76618Y475582I1492J187D01*
G01X76626Y475559D01*
X76631Y475514D01*
X76447Y474117D01*
X76325Y473186D01*
G02X76318Y473154I-198J27D01*
G01X75876Y471696D01*
X75586Y470739D01*
X74224Y466247D01*
G02X74133Y466132I-192J58D01*
G01X74100Y466114D01*
X74025Y466103D01*
X73987Y466112D01*
G03X73918Y466127I-354J-1460D01*
G03X73630Y466155I-289J-1475D01*
G01X73628D01*
G03X73294Y466117I2J-1503D01*
G01X73272Y466112D01*
X73258Y466109D01*
X73256Y466108D01*
X73251Y466107D01*
X73249D01*
G03X73234Y466103I44J-195D01*
G01X73180Y466086D01*
G03X72829Y465924I449J-1434D01*
G03X72694Y465828I802J-1270D01*
G01X72692Y465827D01*
X72684Y465820D01*
G02X72583Y465784I-115J164D01*
G01X72485D01*
G03X72402Y465766I0J-200D01*
G01X72349Y465742D01*
G02X72141Y465767I-84J181D01*
G01X72113Y465789D01*
X72095Y465803D01*
X72092Y465805D01*
G03X71131Y466154I-962J-1152D01*
G01X71130D01*
G03X71075Y466153I0J-1502D01*
G01X71062D01*
G03X69628Y464671I68J-1501D01*
G01Y464652D01*
G03X69632Y464536I1502J-6D01*
G01X69635Y464493D01*
X69620Y464452D01*
G02X69574Y464380I-188J69D01*
G01X69565Y464371D01*
X69561Y464296D01*
G03X69604Y464162I200J-10D01*
G01X69937Y463739D01*
X69938Y463737D01*
X69939Y463736D01*
G02X69945Y463729I-149J-134D01*
G01X69950Y463722D01*
X69951Y463721D01*
G03X69955Y463716I158J122D01*
G01X69957Y463713D01*
X69970Y463695D01*
X69984Y463664D01*
G02X69998Y463591I-186J-73D01*
G01Y463507D01*
G03X70016Y463424I200J0D01*
G01X70040Y463371D01*
G02X70015Y463163I-181J-84D01*
G01X69993Y463135D01*
X69979Y463117D01*
X69977Y463114D01*
X69975Y463112D01*
X69972Y463108D01*
G03X69628Y462168I1158J-957D01*
G01Y462156D01*
G03X69744Y461572I1502J-5D01*
G03X69954Y461216I1387J578D01*
G01X69969Y461197D01*
X69979Y461176D01*
G02X69998Y461091I-181J-85D01*
G01Y461007D01*
G03X70016Y460924I200J0D01*
G01X70040Y460871D01*
G02X70015Y460663I-181J-84D01*
G01X69993Y460635D01*
X69979Y460617D01*
X69977Y460614D01*
X69971Y460607D01*
G03X69630Y459729I1159J-955D01*
G03X69628Y459656I1500J-78D01*
G01Y459652D01*
G03X71130Y458150I1502J0D01*
G01X71163D01*
G03X71226Y458153I-40J1502D01*
G01X71234D01*
X71260Y458154D01*
X71302Y458135D01*
G02X71379Y458076I-80J-184D01*
G01X71581Y457818D01*
G02X71619Y457651I-157J-124D01*
G01X68969Y448906D01*
G02X68888Y448797I-192J58D01*
G01X68859Y448778D01*
X68793Y448762D01*
X68758Y448765D01*
G03X68620Y448771I-134J-1496D01*
G01X68619D01*
G03X67117Y447269I0J-1502D01*
G01Y447240D01*
X67118Y447186D01*
X67065Y447091D01*
X66667Y446861D01*
X66558Y446862D01*
X66511Y446890D01*
G03X65737Y447105I-774J-1286D01*
G03X67239Y445603I0J-1502D01*
G01Y445632D01*
X67238Y445686D01*
X67291Y445781D01*
X67689Y446011D01*
X67798Y446010D01*
X67845Y445982D01*
G03X67904Y445948I779J1284D01*
G01X67907Y445947D01*
G02X67995Y445848I-97J-175D01*
G01X68008Y445818D01*
X68011Y445749D01*
X66796Y441741D01*
X66010Y439150D01*
G02X65935Y439045I-192J58D01*
G01X65909Y439027D01*
X65847Y439008D01*
X65813Y439009D01*
G03X65778Y439010I-60J-1501D01*
G01X65759D01*
G03X64257Y437508I0J-1502D01*
G03X64931Y436254I1504J0D01*
G01X64951Y436241D01*
X64984Y436206D01*
X65066Y436059D01*
G02X65061Y436015I-200J0D01*
G01X55960Y405991D01*
X55957Y405981D01*
G03X55956Y405978I3724J-1243D01*
G03X55952Y405966I3722J-1247D01*
G01X35413Y338207D01*
G03X35244Y337072I3758J-1140D01*
G01Y337064D01*
G03X35245Y337038I3923J138D01*
G01Y337035D01*
X35544Y300774D01*
X35558Y299137D01*
X35603Y293628D01*
G02X35531Y293472I-200J-2D01*
G01X35294Y293273D01*
G02X35215Y293233I-128J154D01*
G01X35174Y293222D01*
X35129Y293231D01*
G03X34846Y293258I-284J-1475D01*
G01X34845D01*
G03Y290254I0J-1502D01*
G03X35152Y290286I-1J1502D01*
G01X35153D01*
G02X35315Y290249I40J-196D01*
G01X35565Y290046D01*
G02X35634Y289906I-131J-151D01*
G01X35640Y289115D01*
X35711Y280520D01*
G03X35700Y280488I1415J-504D01*
G01X35699Y280487D01*
G03X35615Y279991I1418J-495D01*
G01Y279990D01*
G03X35708Y279470I1502J0D01*
G01X35720Y279437D01*
X35992Y246471D01*
Y240222D01*
G02X35973Y240210I-116J163D01*
G01X35960Y240203D01*
X35840Y240173D01*
G03X35618Y237329I362J-1459D01*
G03X35752Y237280I582J1385D01*
G01X35789Y237269D01*
X35818Y237246D01*
G02X35894Y237078I-124J-157D01*
G01X35798Y235369D01*
X35781Y235070D01*
Y235069D01*
X35460Y231528D01*
G02X35432Y231442I-199J17D01*
G01X35410Y231406D01*
X35370Y231380D01*
G03X34683Y230117I817J-1263D01*
G01Y230116D01*
G03X35159Y229020I1502J1D01*
G01X35174Y229006D01*
X35199Y228968D01*
X35207Y228947D01*
G02X35219Y228859I-187J-70D01*
G01X35207Y228729D01*
X35172Y228347D01*
X34938Y225762D01*
G03X34922Y225409I3911J-354D01*
G01Y225407D01*
G03X34923Y225348I3926J37D01*
G01Y225347D01*
X34991Y220982D01*
Y220968D01*
X34681Y215444D01*
X34018Y203621D01*
G02X34011Y203581I-199J14D01*
G01Y203579D01*
G02X33907Y203453I-193J53D01*
G01X33659Y203329D01*
G02X33570Y203308I-89J179D01*
G01X33458D01*
G02X33406Y203315I0J200D01*
G01X33381Y203322D01*
X33357Y203336D01*
G03X32586Y203550I-773J-1288D01*
G01X32585D01*
G03X31342Y202891I0J-1502D01*
G01X31331Y202875D01*
X31292Y202836D01*
G02X31260Y202810I-141J141D01*
G01X31160Y202747D01*
X31112Y202743D01*
X31003Y202732D01*
X31001D01*
X30847Y202716D01*
G02X30779Y202721I-20J199D01*
G01X30771Y202723D01*
G02X30766Y202725I72J186D01*
G01X30759Y202727D01*
X30734Y202736D01*
X30694Y202762D01*
X30678Y202779D01*
G03X30558Y202893I-1093J-1030D01*
G03X29687Y203247I-973J-1145D01*
G03X29610Y203250I-97J-1499D01*
G01X29583D01*
G03X29578I-2J-1502D01*
G01X29577D01*
G03X29503Y203248I4J-1502D01*
G01X29489Y203247D01*
X29488D01*
G03X28093Y201924I97J-1499D01*
G01X28089Y201887D01*
G03X28084Y201810I1496J-136D01*
G03X28083Y201748I1501J-55D01*
G03Y201746I1502J-1D01*
G01Y201745D01*
G03X28087Y201632I1502J-3D01*
G01X28090Y201589D01*
X28075Y201548D01*
G02X28029Y201476I-188J69D01*
G01X28020Y201467D01*
X28016Y201392D01*
G03X28059Y201258I200J-10D01*
G01X28392Y200835D01*
X28393Y200833D01*
X28394Y200832D01*
G02X28400Y200825I-149J-134D01*
G01X28405Y200818D01*
X28406Y200817D01*
G03X28410Y200812I158J122D01*
G01X28412Y200809D01*
X28425Y200791D01*
X28439Y200760D01*
G02X28453Y200687I-186J-73D01*
G01Y200603D01*
G03X28471Y200520I200J0D01*
G01X28495Y200467D01*
G02X28470Y200259I-181J-84D01*
G01X28448Y200231D01*
X28434Y200213D01*
X28426Y200203D01*
G03X28086Y199349I1159J-956D01*
G03X28085Y199332I1498J-97D01*
G01Y199325D01*
G03X28083Y199252I1500J-78D01*
G01Y199246D01*
G03X29583Y197746I1502J2D01*
G01X29631D01*
G03X30738Y198283I-45J1502D01*
G01X30754Y198306D01*
X30779Y198325D01*
X30798Y198340D01*
X30895Y198384D01*
X30896D01*
G02X30972Y198402I83J-182D01*
G01X31176D01*
G02X31224Y198396I-1J-200D01*
G01X31288Y198380D01*
X31307Y198371D01*
X31351Y198350D01*
X31370Y198341D01*
X31407Y198313D01*
X31423Y198294D01*
X31424Y198293D01*
X31436Y198279D01*
G03X31569Y198141I1146J972D01*
G03X32585Y197745I1016J1105D01*
G01X32598D01*
X32649Y197747D01*
G03X33097Y197836I-65J1501D01*
G01X33131Y197848D01*
X33236D01*
G02X33268Y197845I-3J-200D01*
G01X33270D01*
G02X33376Y197791I-34J-197D01*
G01X33405Y197762D01*
G03X33429Y197742I140J143D01*
G01X33601Y197618D01*
G02X33654Y197550I-128J-154D01*
G01X33662Y197529D01*
G02X33672Y197467I-190J-62D01*
G01Y197454D01*
X33664Y197326D01*
Y197323D01*
X33655Y197169D01*
X33647Y197032D01*
G02X33627Y196965I-199J23D01*
G01X33610Y196931D01*
X33590Y196914D01*
X33578Y196904D01*
X33490Y196829D01*
G03X33446Y196776I130J-152D01*
G01X33445Y196774D01*
X33442Y196769D01*
X33441Y196768D01*
G02X33370Y196697I-172J101D01*
G01X33346Y196684D01*
X33325Y196678D01*
X33323D01*
G02X33269Y196670I-56J192D01*
G01X33231Y196671D01*
X33215Y196672D01*
G03X33205Y196673I-155J-1495D01*
G01X33201D01*
G03X33190Y196674I-142J-1496D01*
G01X33186Y196675D01*
X33182D01*
X33175Y196676D01*
X33168D01*
G03X33067Y196679I-95J-1500D01*
G03X32723Y196639I0J-1503D01*
G01X32722D01*
G03X32719Y196638I473J-1423D01*
G01X32718D01*
X32711Y196636D01*
G03X32618Y196610I358J-1459D01*
G03X32355Y196499I450J-1434D01*
G01X32353D01*
G03X32343Y196493I767J-1290D01*
G03X32338Y196490I100J-173D01*
G01X32337Y196489D01*
G03X32333Y196487I670J-1345D01*
G03X32330Y196486I61J-188D01*
G03X32130Y196352I734J-1312D01*
G01X32128Y196350D01*
X32116Y196341D01*
G02X32097Y196330I-110J168D01*
G01X32072Y196318D01*
X32029Y196308D01*
X31922D01*
G03X31839Y196290I0J-200D01*
G01X31786Y196266D01*
G02X31578Y196291I-84J181D01*
G01X31550Y196313D01*
X31532Y196327D01*
X31529Y196329D01*
G03X30568Y196678I-962J-1152D01*
G01X30529D01*
G03X29685Y196392I38J-1502D01*
G01X29651Y196368D01*
X29631Y196351D01*
G02X29602Y196333I-120J161D01*
G01X29594Y196329D01*
G02X29505Y196308I-89J179D01*
G01X29422D01*
G03X29339Y196290I0J-200D01*
G01X29286Y196266D01*
G02X29078Y196291I-84J181D01*
G01X29050Y196313D01*
X29032Y196327D01*
X29029Y196329D01*
G03X28068Y196678I-962J-1152D01*
G01X28029D01*
G03X27185Y196392I38J-1502D01*
G01X27151Y196368D01*
X27131Y196351D01*
G02X27102Y196333I-120J161D01*
G01X27094Y196329D01*
G02X27005Y196308I-89J179D01*
G01X26922D01*
G03X26839Y196290I0J-200D01*
G01X26786Y196266D01*
G02X26578Y196291I-84J181D01*
G01X26550Y196313D01*
X26532Y196327D01*
X26529Y196329D01*
G03X25568Y196678I-962J-1152D01*
G01X25567D01*
G03Y193674I0J-1502D01*
G01X25568D01*
G03X26502Y194000I0J1502D01*
G01X26521Y194015D01*
X26550Y194028D01*
G02X26628Y194044I78J-184D01*
G01X26712D01*
G03X26795Y194062I0J200D01*
G01X26848Y194086D01*
G02X27056Y194061I84J-181D01*
G01X27084Y194039D01*
X27102Y194025D01*
X27105Y194023D01*
G03X28066Y193674I962J1152D01*
G01X28105D01*
G03X29001Y193999I-38J1502D01*
G01X29021Y194015D01*
X29052Y194029D01*
G02X29128Y194044I76J-185D01*
G01X29212D01*
G03X29295Y194062I0J200D01*
G01X29348Y194086D01*
G02X29556Y194061I84J-181D01*
G01X29584Y194039D01*
X29602Y194025D01*
X29605Y194023D01*
G03X30566Y193674I962J1152D01*
G01X30605D01*
G03X31501Y193999I-38J1502D01*
G01X31521Y194015D01*
X31552Y194029D01*
G02X31628Y194044I76J-185D01*
G01X31712D01*
G03X31795Y194062I0J200D01*
G01X31840Y194083D01*
X31842D01*
X31878Y194101D01*
X31923Y194102D01*
G02X32007Y194084I1J-200D01*
G01X32027Y194075D01*
X32062Y194057D01*
X32080Y194041D01*
G03X32492Y193788I982J1137D01*
G03X33045Y193673I577J1388D01*
G01X33087Y193672D01*
X33121Y193658D01*
G02X33183Y193615I-81J-183D01*
G01X33258Y193535D01*
X33383Y193400D01*
G02X33436Y193253I-147J-136D01*
G01X33206Y189163D01*
X32815Y182205D01*
G02X32616Y182016I-200J11D01*
G01X32596D01*
G03X32507Y182019I-95J-1499D01*
G01X32506D01*
G03X31005Y180517I1J-1502D01*
G03X32435Y179017I1502J0D01*
G01X32436D01*
X32458Y179016D01*
X32461Y179015D01*
G02X32587Y178938I-34J-197D01*
G01Y178937D01*
G02X32626Y178813I-161J-119D01*
G01X32481Y176219D01*
X32379Y174434D01*
G02X32378Y174418I-200J4D01*
G01X31881Y170737D01*
X30290Y158959D01*
G03X30255Y158493I3891J-527D01*
G01X30231Y156950D01*
X30223Y156399D01*
G02X30202Y156324I-199J15D01*
G01Y156323D01*
G03X29795Y154641I3519J-1742D01*
G01X29790Y154317D01*
X29765Y152691D01*
Y152690D01*
G03X29764Y152632I3925J-97D01*
G01Y152630D01*
G03X29968Y151382I3928J1D01*
G02X29970Y151262I-190J-63D01*
G02X29966Y151249I-193J52D01*
G03X29721Y149942I3681J-1366D01*
G01X29711Y149321D01*
X29707Y149032D01*
X29691Y147991D01*
Y147990D01*
G03X29690Y147932I3925J-97D01*
G01Y147930D01*
G03X29776Y147115I3927J2D01*
G03X29798Y147018I3840J820D01*
G01X29806Y146986D01*
X29777Y146694D01*
X29756Y146657D01*
G03X29374Y145714I3385J-1920D01*
G01Y145712D01*
X29352Y145630D01*
X29346Y145597D01*
Y145596D01*
X29345Y145593D01*
X29344Y145588D01*
X29343Y145582D01*
X29341Y145577D01*
X29340Y145571D01*
X29338Y145563D01*
G03X29269Y145122I3804J-821D01*
G01X29098Y143390D01*
G03X29080Y143008I3873J-374D01*
G03X29159Y142227I3891J-1D01*
G01X29167Y142188D01*
X29149Y142101D01*
X29141Y142083D01*
G03X28858Y140961I3590J-1502D01*
G01Y140960D01*
X28851Y140893D01*
Y140891D01*
X28761Y139973D01*
G02X28715Y139874I-198J32D01*
G02X28705Y139863I-153J129D01*
G01X28704Y139862D01*
G02X28667Y139833I-141J142D01*
G01X28557Y139838D01*
G03X28408Y139842I-180J-3923D01*
G01X28359D01*
G03X26284Y139230I30J-3927D01*
G01X26276Y139232D01*
X26260Y139235D01*
G03X25990Y139259I-267J-1478D01*
G01X25988D01*
G03X24486Y137772I0J-1502D01*
G01Y137756D01*
G03X24622Y137132I1502J1D01*
G01X24631Y137112D01*
X24638Y137080D01*
G03X24462Y135917I3750J-1162D01*
G01Y135915D01*
G03X24814Y134289I3928J-1D01*
G02Y134141I-186J-74D01*
G03X24462Y132515I3576J-1625D01*
G01Y132511D01*
G03X24638Y131351I3926J2D01*
G01X24634Y131333D01*
X24620Y131292D01*
X24616Y131283D01*
G03X24486Y130685I1372J-611D01*
G01Y130664D01*
G03X25988Y129168I1502J6D01*
G01X26006D01*
G03X26258Y129192I-16J1502D01*
G01X26287Y129197D01*
G03X28355Y128588I2101J3318D01*
G01X28403D01*
G03X30489Y129198I-16J3927D01*
G01X30493Y129197D01*
G03X30514Y129193I292J1474D01*
G03X30525Y129191I274J1477D01*
G03X30575Y129183I262J1479D01*
G01X30577D01*
G03X30801Y129167I219J1486D01*
G01X30808D01*
G03X30920Y129173I-24J1504D01*
G01X30922D01*
G03X31264Y129243I-128J1497D01*
G01X31276Y129247D01*
X31331Y129257D01*
G02X31499Y129202I28J-198D01*
G01X31547Y129152D01*
G03X31562Y129138I144J139D01*
G01X31722Y129021D01*
G02X31742Y129002I-127J-154D01*
G02X31764Y128974I-146J-137D01*
G01X31762Y128887D01*
Y128828D01*
G03X32114Y127202I3928J-1D01*
G02Y127054I-186J-74D01*
G03X31762Y125430I3576J-1625D01*
G01Y125285D01*
G02X31721Y125235I-173J100D01*
G01X31714Y125229D01*
X31701Y125217D01*
X31451Y125036D01*
X31449D01*
X31416Y125010D01*
X31368Y125001D01*
G02X31274Y125006I-37J197D01*
G01X31258Y125011D01*
G03X30803Y125086I-469J-1427D01*
G01X30797D01*
X30782Y125087D01*
X30760D01*
X30705Y125084D01*
X30704D01*
G03X30623Y125078I70J-1501D01*
G01X30621D01*
G03X30575Y125073I139J-1497D01*
G01X30549Y125070D01*
G02X30532Y125069I-20J199D01*
G01X30428Y125098D01*
X30405Y125112D01*
G03X29573Y125486I-2015J-3370D01*
G03X28399Y125668I-1182J-3745D01*
G01X28372D01*
X28371Y125669D01*
G03X26376Y125114I18J-3927D01*
G01X26362Y125105D01*
G02X26276Y125086I-85J181D01*
G01X25988D01*
G03X24486Y123593I0J-1502D01*
G01Y123582D01*
G03X24631Y122937I1503J-1D01*
G01X24638Y122908D01*
G03X24462Y121759I3751J-1162D01*
G01Y121742D01*
G03X24814Y120116I3928J-1D01*
G02Y119968I-186J-74D01*
G03X24462Y118342I3576J-1625D01*
G01Y118340D01*
G03X24639Y117176I3926J2D01*
G01X24632Y117146D01*
X24623Y117127D01*
G03X24486Y116500I1365J-627D01*
G01Y116497D01*
G03X25988Y114995I1502J0D01*
G01X25992D01*
G03X26250Y115017I2J1502D01*
G01X26288Y115024D01*
G03X28388Y114415I2100J3318D01*
G03X30488Y115024I0J3927D01*
G01X30513Y115019D01*
G03X30788Y114995I268J1478D01*
G01X30804D01*
G03X31256Y115069I-14J1502D01*
G01X31258Y115070D01*
X31271Y115074D01*
X31294Y115079D01*
G02X31456Y115041I39J-196D01*
G01X31457Y115040D01*
X31461Y115038D01*
X31721Y114850D01*
G02X31764Y114803I-124J-157D01*
G01X31762Y114730D01*
Y114655D01*
G03X32114Y113029I3928J-1D01*
G02Y112881I-186J-74D01*
G03X31762Y111255I3576J-1625D01*
G03X31831Y110517I3926J-5D01*
G03X31898Y110228I3856J742D01*
G03X31938Y110090I3790J1024D01*
G01Y110089D01*
X31931Y110056D01*
G03X31922Y110036I1366J-627D01*
G01X31921Y110034D01*
G03X31786Y109430I1367J-623D01*
G01Y109409D01*
G03X33288Y107908I1502J1D01*
G03X33563Y107932I7J1503D01*
G01X33571Y107934D01*
G03X33581Y107936I-290J1474D01*
G01X33584D01*
X33589Y107937D01*
G03X33758Y107835I2113J3310D01*
G03X33762Y107833I91J178D01*
G03X33775Y107826I1868J3453D01*
G01X33844Y107788D01*
G02X33856Y107759I-179J-91D01*
G01X33936Y107462D01*
X33935Y107408D01*
X33928Y107382D01*
X33911Y107321D01*
X33899Y107300D01*
G03X33705Y106562I1308J-738D01*
G01Y106526D01*
X33706Y106510D01*
Y106507D01*
G03X33715Y106388I1501J54D01*
G03X33882Y105854I1492J173D01*
G03X34280Y105379I1325J706D01*
G01X34288Y105373D01*
X34316Y105346D01*
X34367Y105284D01*
X34377Y105263D01*
X34387Y105217D01*
X34371Y104911D01*
X34369Y104862D01*
X34297Y104738D01*
X34279Y104720D01*
X34235Y104675D01*
X34210Y104658D01*
G03X33546Y103411I839J-1247D01*
G03X36550I1502J0D01*
G03X35962Y104603I-1502J0D01*
G01X35951Y104611D01*
X35925Y104637D01*
X35907Y104660D01*
G02X35871Y104771I164J114D01*
G01X35886Y105105D01*
X35905Y105142D01*
X35909Y105151D01*
X35959Y105235D01*
X35976Y105252D01*
X36020Y105297D01*
X36045Y105314D01*
G03X36709Y106557I-838J1247D01*
G01Y106580D01*
G03X36695Y106768I-1502J-17D01*
G01Y106770D01*
G03X36693Y106782I-1483J-241D01*
G01Y106783D01*
X36690Y106800D01*
Y106801D01*
G03X36688Y106813I-1482J-241D01*
G03X36684Y106835I-1480J-258D01*
G01Y106837D01*
G03X36681Y106852I-1474J-287D01*
G01X36677Y106870D01*
G03X36630Y107042I-1470J-309D01*
G01X36617Y107080D01*
X36621Y107154D01*
X36633Y107181D01*
X36755Y107425D01*
X36767Y107444D01*
G02X36791Y107471I161J-119D01*
G01X36818Y107494D01*
X36865Y107509D01*
G03X37761Y107920I-1176J3746D01*
G01X37795D01*
G03X37988Y107907I197J1490D01*
G03X38064Y107909I-2J1503D01*
G01X38102Y107912D01*
G03X39191Y108510I-114J1498D01*
G01X39199Y108520D01*
G03X41374Y109624I-602J3880D01*
G01X44961Y113211D01*
G03X45450Y113805I-2772J2781D01*
G01X45568Y113982D01*
G02X45591Y114010I165J-112D01*
G01X46592Y115011D01*
G02X46603Y115021I140J-143D01*
G02X46649Y115049I126J-156D01*
G01X46668Y115056D01*
X46671Y115057D01*
X46672D01*
X46674Y115058D01*
G03X46680Y115060I-60J190D01*
G01X46681D01*
X46682D01*
G02X46686Y115062I90J-176D01*
G03X46758Y115086I-439J1436D01*
G01X46760D01*
G03X46865Y115130I-528J1406D01*
G01X46900Y115146D01*
G03X47081Y115251I-662J1349D01*
G01X47094Y115260D01*
G03X47741Y116442I-854J1236D01*
G01X47743Y116498D01*
Y116499D01*
X49325Y118867D01*
G02X49350Y118897I165J-112D01*
G01X49746Y119293D01*
X53732Y123280D01*
G03X54574Y124532I-2776J2776D01*
G01X55773Y127376D01*
X56076Y128096D01*
X56524Y129159D01*
G02X56569Y129224I184J-79D01*
G01X56597Y129252D01*
X56637Y129267D01*
G03X57590Y130494I-540J1403D01*
G01X57596Y130552D01*
G03X57601Y130670I-1498J123D01*
G01Y130672D01*
G03X57479Y131267I-1504J2D01*
G01Y131268D01*
G02X57478Y131424I183J79D01*
G01X63978Y146854D01*
G03X64286Y148378I-3618J1524D01*
G01Y148443D01*
Y148447D01*
X64209Y153087D01*
X64189Y154275D01*
G03X64106Y155015I-3926J-66D01*
G01X63401Y158385D01*
X62967Y160457D01*
G02X62970Y160533I198J30D01*
G01X62971Y160537D01*
G02X63028Y160635I194J-47D01*
G01X63276Y160867D01*
G02X63314Y160895I137J-146D01*
G02X63467Y160914I99J-174D01*
G01X63492Y160907D01*
G03X63876Y160858I382J1463D01*
G01X63879D01*
G03X64907Y161262I-1J1513D01*
G01X64923Y161277D01*
X64961Y161299D01*
G02X65005Y161316I93J-176D01*
G01X65033Y161323D01*
X65061Y161326D01*
X65318D01*
G02X65341Y161325I3J-200D01*
G03X66478Y160825I1137J1043D01*
G03Y163911I0J1543D01*
G03X65341Y163411I0J-1543D01*
G02X65318Y163410I-20J199D01*
G01X65068D01*
G02X65021Y163416I2J200D01*
G01X64997Y163422D01*
G02X64949Y163442I52J193D01*
G01X64930Y163453D01*
X64913Y163468D01*
X64910Y163471D01*
G03X63878Y163878I-1032J-1105D01*
G01X63877D01*
G03X62920Y163536I0J-1511D01*
G01X62918Y163534D01*
G02X62825Y163492I-126J155D01*
G01X62777Y163484D01*
X62404Y163615D01*
G02X62275Y163762I67J189D01*
G01X61947Y165329D01*
X61770Y166173D01*
X60808Y170765D01*
G02X60806Y170775I195J44D01*
G01X56817Y196999D01*
Y197001D01*
X56802Y197095D01*
X56801Y197102D01*
X56798Y197122D01*
X55578Y205143D01*
G02X55576Y205170I198J28D01*
G01X55553Y206611D01*
G02X55573Y206702I200J4D01*
G01X55583Y206723D01*
X55613Y206759D01*
X55633Y206774D01*
G03X56236Y207978I-901J1204D01*
G03X56232Y208094I-1503J6D01*
G01X56225Y208154D01*
Y208155D01*
G03X56179Y208385I-1491J-179D01*
G03X55912Y208909I-1446J-407D01*
G01X55901Y208923D01*
X55875Y208972D01*
X55865Y209016D01*
Y209123D01*
G03X55847Y209206I-200J0D01*
G01X55823Y209259D01*
G02X55848Y209467I181J84D01*
G01X55870Y209495D01*
X55884Y209513D01*
X55886Y209516D01*
X55888Y209518D01*
X55891Y209522D01*
G03X56235Y210462I-1158J957D01*
G01Y210474D01*
G03X56119Y211058I-1502J5D01*
G01Y211059D01*
X56118Y211061D01*
G03X56113Y211072I-1370J-616D01*
G01X56111Y211076D01*
X56101Y211099D01*
G03X56083Y211137I-1366J-624D01*
G03X56063Y211175I-1339J-680D01*
G01Y211177D01*
G03X56043Y211214I-1332J-696D01*
G03X56041Y211216I-137J-135D01*
G03X56003Y211280I-1310J-735D01*
G02X56001Y211282I137J139D01*
G03X55949Y211360I-1275J-794D01*
G01X55925Y211393D01*
X55907Y211416D01*
G02X55890Y211443I160J120D01*
G01X55886Y211451D01*
G02X55865Y211540I179J89D01*
G01Y211623D01*
G03X55847Y211706I-200J0D01*
G01X55823Y211759D01*
G02X55848Y211967I181J84D01*
G01X55870Y211995D01*
X55884Y212013D01*
X55886Y212016D01*
X55888Y212018D01*
X55891Y212022D01*
G03X56235Y212962I-1158J957D01*
G01Y212974D01*
G03X56119Y213558I-1502J5D01*
G01Y213559D01*
X56118Y213561D01*
G03X56113Y213572I-1370J-616D01*
G01X56111Y213576D01*
X56101Y213599D01*
G03X56083Y213637I-1366J-624D01*
G03X56063Y213675I-1339J-680D01*
G01Y213677D01*
G03X56043Y213714I-1332J-696D01*
G03X56041Y213716I-137J-135D01*
G03X56003Y213780I-1310J-735D01*
G02X56001Y213782I137J139D01*
G03X55949Y213860I-1275J-794D01*
G01X55925Y213893D01*
X55907Y213916D01*
G02X55890Y213943I160J120D01*
G01X55886Y213951D01*
G02X55865Y214040I179J89D01*
G01Y214123D01*
G03X55847Y214206I-200J0D01*
G01X55823Y214259D01*
G02X55848Y214467I181J84D01*
G01X55870Y214495D01*
X55884Y214513D01*
X55886Y214516D01*
X55892Y214523D01*
G03X56233Y215401I-1159J955D01*
G03X56235Y215474I-1500J78D01*
G01Y215478D01*
G03X56222Y215678I-1502J3D01*
G03X55491Y216776I-1489J-199D01*
G01X55465Y216791D01*
X55458Y216795D01*
X55445Y216802D01*
X55419Y216846D01*
G02X55391Y216945I172J102D01*
G01X55309Y222208D01*
G02X55338Y222314I200J2D01*
G01X55367Y222363D01*
X55395Y222377D01*
G03X56235Y223726I-663J1349D01*
G03X55911Y224658I-1502J0D01*
G01X55896Y224678D01*
X55886Y224699D01*
X55875Y224720D01*
X55865Y224764D01*
Y224874D01*
G03X55849Y224952I-200J0D01*
G01X55822Y225014D01*
X55821Y225017D01*
X55811Y225039D01*
X55807Y225069D01*
G02Y225119I198J25D01*
G01X55812Y225155D01*
X55836Y225205D01*
X55857Y225229D01*
G03X55863Y225236I-1137J981D01*
G01X55868Y225242D01*
X55874Y225248D01*
X55883Y225259D01*
X55908Y225290D01*
X55912Y225294D01*
X55918Y225302D01*
G03X56235Y226202I-1185J923D01*
G01Y226234D01*
G03X55912Y227158I-1502J-7D01*
G01X55907Y227164D01*
X55890Y227186D01*
X55871Y227243D01*
G02X55865Y227290I194J49D01*
G01Y227374D01*
G03X55849Y227452I-200J0D01*
G01X55822Y227514D01*
X55821Y227517D01*
X55811Y227539D01*
X55807Y227569D01*
G02Y227619I198J25D01*
G01X55812Y227655D01*
X55836Y227705D01*
X55857Y227729D01*
G03X55863Y227736I-1137J981D01*
G01X55868Y227742D01*
X55874Y227748D01*
X55883Y227759D01*
X55908Y227790D01*
X55912Y227794D01*
X55918Y227802D01*
G03X56235Y228702I-1185J923D01*
G01Y228734D01*
G03X55912Y229658I-1502J-7D01*
G01X55907Y229664D01*
X55890Y229686D01*
X55871Y229743D01*
G02X55865Y229790I194J49D01*
G01Y229871D01*
G03X55847Y229954I-200J0D01*
G01X55823Y230007D01*
G02X55848Y230215I181J84D01*
G01X55870Y230243D01*
X55884Y230261D01*
X55886Y230264D01*
G03X56116Y230640I-1152J963D01*
G03X56205Y230926I-1382J587D01*
G03X56224Y231043I-1472J299D01*
G03X56235Y231201I-1491J183D01*
G01Y231261D01*
G03X56234Y231277I-1499J-86D01*
G01Y231292D01*
X56231Y231350D01*
Y231354D01*
G03X56229Y231379I-200J-3D01*
G01X56218Y231454D01*
G03X56178Y231635I-1484J-233D01*
G01Y231639D01*
G03X56172Y231659I-1442J-422D01*
G01X56157Y231709D01*
X56145Y231738D01*
G03X55927Y232139I-1413J-509D01*
G01X55911Y232161D01*
X56096Y234033D01*
X56297Y236070D01*
G03X56316Y236455I-3908J386D01*
G01Y243508D01*
G03X56315Y243537I-3923J-121D01*
G01Y243540D01*
X56268Y249385D01*
Y257634D01*
G03X56267Y257656I-3887J-166D01*
G01Y257735D01*
Y257737D01*
X56266Y257805D01*
Y257807D01*
X56265Y257868D01*
Y257870D01*
X56264Y257961D01*
Y257963D01*
X56263Y258039D01*
Y258055D01*
G02X56322Y258196I200J-1D01*
G02X56463Y258255I142J-141D01*
G01X56507D01*
X56523Y258253D01*
G02X56643Y258189I-29J-198D01*
G01X56661Y258169D01*
X56672Y258149D01*
G03X57987Y257378I1315J736D01*
G03X59489Y258880I0J1502D01*
G03X58163Y260372I-1502J0D01*
G01X58109Y260378D01*
G03X56944Y259962I-122J-1498D01*
G01X56916Y259935D01*
X56857Y259911D01*
G02X56831Y259903I-72J187D01*
G01X56800Y259895D01*
X56798D01*
G02X56753Y259889I-49J194D01*
G01X56733Y259890D01*
X56697Y259896D01*
X56488Y259979D01*
X56486D01*
X56353Y260035D01*
G02X56237Y260196I83J182D01*
G01X56225Y261086D01*
X56214Y261980D01*
X56209Y262389D01*
X56203Y262859D01*
Y262951D01*
X56205Y262969D01*
X56206Y262977D01*
X56208Y262994D01*
G02X56310Y263135I197J-35D01*
G01X56342Y263151D01*
X56373Y263162D01*
X56670Y263270D01*
G02X56734Y263281I65J-189D01*
G01X56761D01*
X56843Y263263D01*
G02X56846Y263262I-61J-189D01*
G01X56885Y263244D01*
X56895Y263232D01*
X56918Y263205D01*
G03X57334Y262866I1142J977D01*
G03X57532Y262774I730J1313D01*
G01X57533D01*
X57549Y262768D01*
G03X57571Y262760I524J1407D01*
G01X57620Y262743D01*
X57647Y262735D01*
G03X58038Y262677I414J1445D01*
G01X58058Y262678D01*
X58068D01*
G03X58997Y263004I-5J1502D01*
G01X59016Y263019D01*
X59045Y263032D01*
G02X59123Y263048I78J-184D01*
G01X59207D01*
G03X59290Y263066I0J200D01*
G01X59343Y263090D01*
G02X59551Y263065I84J-181D01*
G01X59579Y263043D01*
X59597Y263029D01*
X59600Y263027D01*
G03X60561Y262678I962J1152D01*
G01X60562D01*
G03X62064Y264180I0J1502D01*
G03X60577Y265682I-1502J0D01*
G01X60560D01*
G03X59679Y265396I1J-1502D01*
G01X59646Y265371D01*
X59627Y265356D01*
G02X59593Y265335I-122J159D01*
G01X59589Y265333D01*
G02X59500Y265312I-89J179D01*
G01X59417D01*
G03X59334Y265294I0J-200D01*
G01X59281Y265270D01*
G02X59073Y265295I-84J181D01*
G01X59045Y265317D01*
X59027Y265331D01*
X59024Y265333D01*
G03X58063Y265682I-962J-1152D01*
G01X58014D01*
G03X57358Y265508I47J-1502D01*
G03X57026Y265268I706J-1326D01*
G01X57018Y265260D01*
G03X56908Y265144I1034J-1091D01*
G01X56894Y265127D01*
X56878Y265114D01*
G02X56847Y265094I-123J157D01*
G01X56810Y265076D01*
G02X56726Y265057I-85J181D01*
G01X56671D01*
G02X56611Y265067I2J200D01*
G01X56505Y265102D01*
X56503D01*
X56301Y265172D01*
G02X56174Y265323I70J187D01*
G01X56172Y265335D01*
X56094Y271603D01*
X56077Y272971D01*
X55576Y334733D01*
G02X55585Y334792I200J0D01*
G01X83492Y426861D01*
X95711Y466883D01*
G03X95848Y467521I-3723J1133D01*
G01X95870Y467690D01*
G02X95877Y467722I198J-27D01*
G01X96186Y468741D01*
G03X96321Y469368I-3758J1137D01*
G01X109256Y567700D01*
X109257Y567706D01*
X150732Y787033D01*
X162047Y846772D01*
X163135Y852518D01*
G02X163320Y852666I193J-52D01*
G01X172363D01*
G02X172761Y852234I-1J-400D01*
G01X168342Y797515D01*
X166306Y772313D01*
X165627Y763904D01*
X164906Y754982D01*
X159438Y687284D01*
Y687279D01*
X159436Y687263D01*
X159435Y687254D01*
X159434Y687242D01*
Y687239D01*
X159433Y687230D01*
G03X159431Y687205I3878J-323D01*
G01X159173Y684013D01*
X158511Y675813D01*
X157954Y668919D01*
X157753Y666426D01*
X156873Y655526D01*
X155984Y644510D01*
G03X155979Y644436I3880J-299D01*
G01X154533Y620901D01*
X153656Y606632D01*
Y606629D01*
X153543Y605190D01*
X150515Y566696D01*
Y566690D01*
X149372Y555832D01*
G03X149351Y555434I3870J-404D01*
G01X149328Y545370D01*
Y545361D01*
G03X149345Y544990I3891J-8D01*
G03X149363Y544835I3874J371D01*
G01X149420Y544415D01*
X149984Y540276D01*
G02X149985Y540257I-199J-20D01*
G01Y540243D01*
G02X149905Y540083I-200J0D01*
G01X149825Y540023D01*
X149650Y539892D01*
X149637Y539882D01*
X149623Y539872D01*
X149594Y539862D01*
G02X149532Y539852I-62J190D01*
G01X149490D01*
G02X149457Y539855I2J200D01*
G01X149397Y539867D01*
X149380Y539874D01*
G03X148859Y540001I-683J-1669D01*
G03X148692Y540008I-159J-1795D01*
G03X146890Y538206I0J-1802D01*
G01Y534806D01*
G03X148692Y533004I1802J0D01*
G03X149168Y533067I4J1802D01*
G03X149330Y533120I-479J1738D01*
G03X149564Y533228I-636J1687D01*
G01X149586Y533240D01*
X149624Y533250D01*
X149636Y533253D01*
X149661Y533261D01*
X149715Y533264D01*
X149811Y533242D01*
X149849Y533234D01*
X149964Y533156D01*
X149985Y533128D01*
G03X150313Y532807I1202J900D01*
G03X150873Y532558I878J1219D01*
G01X150874D01*
X150901Y532552D01*
X150957Y532522D01*
X150973Y532509D01*
X150974Y532508D01*
G03X150983Y532501I123J148D01*
G02X151063Y532367I-118J-161D01*
G01X151130Y531878D01*
X151207Y531313D01*
X151416Y529777D01*
X151453Y529508D01*
X151913Y526132D01*
Y526130D01*
X151919Y526087D01*
X152357Y522869D01*
X152360Y522845D01*
Y522844D01*
X152683Y519855D01*
X152739Y519336D01*
G02X152740Y519320I-199J-20D01*
G01X153113Y484727D01*
X153262Y470890D01*
Y470882D01*
X152713Y452759D01*
X151737Y420525D01*
X151574Y415550D01*
X151518Y413864D01*
Y413854D01*
X151292Y411035D01*
G02X151232Y410908I-199J16D01*
G01X151206Y410882D01*
X151141Y410854D01*
X151104Y410852D01*
G03X149971Y410232I85J-1500D01*
G01X149964Y410223D01*
X149875Y410165D01*
G02X149810Y410137I-110J167D01*
G01X149728Y410118D01*
G02X149672Y410114I-42J195D01*
G02X149597Y410133I11J200D01*
G01X149585Y410140D01*
G03X148695Y410376I-892J-1566D01*
G01X148692D01*
G03X146890Y408574I0J-1802D01*
G01Y405174D01*
G03X148692Y403372I1802J0D01*
G01X148705D01*
G03X149562Y403595I-11J1802D01*
G01X149565Y403597D01*
X149584Y403607D01*
X149674Y403632D01*
X149727Y403630D01*
X149809Y403611D01*
X149845Y403603D01*
X149964Y403525D01*
X149985Y403497D01*
G03X150554Y403034I1204J898D01*
G02X150558Y403032I-87J-180D01*
G01X150565Y403029D01*
X150580Y403021D01*
X150610Y402968D01*
G02X150635Y402854I-174J-98D01*
G01X150588Y402273D01*
X150389Y399795D01*
X150179Y397181D01*
X150107Y396285D01*
G02X150061Y396173I-199J16D01*
G01X150041Y396149D01*
G03X150031Y396137I1149J-968D01*
G01X150027Y396132D01*
X150018Y396121D01*
X150015Y396118D01*
G03X149987Y396081I1184J-925D01*
G01X149965Y396051D01*
X149880Y395995D01*
G02X149770Y395962I-110J167D01*
G01X149660D01*
G02X149646Y395963I7J200D01*
G01X149611Y395967D01*
G02X149562Y395982I34J197D01*
G01X149544Y395992D01*
X149509Y396010D01*
G03X148915Y396190I-812J-1611D01*
G03X148549Y396199I-227J-1789D01*
G01X148536Y396198D01*
G03X146983Y394974I156J-1795D01*
G03X146890Y394404I1709J-571D01*
G01Y392702D01*
X146889Y391001D01*
G03X148691Y389198I1803J0D01*
G01X148692D01*
G03X148860Y389206I-2J1802D01*
G01X148867Y389207D01*
X148871D01*
G03X148902Y389211I-215J1789D01*
G01X148907D01*
G03X148941Y389216I-245J1786D01*
G01X148947D01*
X148953Y389217D01*
X148957Y389218D01*
X148975Y389220D01*
X148977D01*
X148993Y389223D01*
X148995D01*
G03X149188Y389268I-312J1776D01*
G01X149202Y389272D01*
X149231Y389276D01*
G02X149384Y389233I27J-198D01*
G01X149519Y389123D01*
X149532Y389112D01*
X149131Y384119D01*
G02X149083Y384015I-198J28D01*
G02X149030Y383973I-149J134D01*
G01X148953Y383930D01*
X148901Y383929D01*
X148784D01*
X148738Y383941D01*
X148720Y383950D01*
G03X148062Y384102I-658J-1350D01*
G01X148035D01*
G03X146559Y382600I26J-1502D01*
G03X148061Y381098I1502J0D01*
G01X148067D01*
G03X148542Y381177I-6J1502D01*
G01X148574Y381181D01*
X148612D01*
G02X148701Y381160I0J-200D01*
G01X148717Y381152D01*
X148736Y381143D01*
X148800Y381091D01*
G02X148853Y381028I-123J-158D01*
G02X148875Y380933I-178J-91D01*
G01X148818Y380225D01*
G02X148730Y380081I-199J23D01*
G01X148724Y380077D01*
X148694Y380058D01*
G02X148651Y380039I-102J172D01*
G01X148630Y380034D01*
G02X148593Y380030I-40J196D01*
G01X148521D01*
X148493Y380038D01*
G03X148061Y380102I-434J-1438D01*
G03Y377098I0J-1502D01*
G01X148096D01*
G03X148273Y377113I-38J1502D01*
G01X148277Y377114D01*
X148287Y377115D01*
X148306Y377116D01*
X148348Y377119D01*
X148387Y377105D01*
G02X148453Y377066I-67J-189D01*
G01X148472Y377048D01*
X148487Y377034D01*
G02X148549Y376872I-137J-145D01*
G01X143029Y308112D01*
X142321Y299298D01*
X138947Y257272D01*
G03X138945Y257245I3915J-304D01*
G03X138938Y257115I3917J-276D01*
G01X138386Y243323D01*
G02X138344Y243209I-200J9D01*
G01X138326Y243185D01*
X138274Y243150D01*
X138257Y243145D01*
G03X137162Y241699I407J-1446D01*
G03X137716Y240534I1502J0D01*
G02X137718Y240532I-140J-142D01*
G01X137730Y240522D01*
X137748Y240480D01*
G02X137765Y240392I-183J-81D01*
G01X137762Y240303D01*
X137753Y240069D01*
G02X137714Y239965I-199J15D01*
G01X137673Y239924D01*
X137662Y239916D01*
G03X138011Y237317I901J-1202D01*
G01X138040Y237306D01*
X138088Y237267D01*
X138105Y237241D01*
G02X138137Y237123I-168J-109D01*
G01X138079Y235673D01*
X137916Y231592D01*
G02X137888Y231497I-200J7D01*
G01X137863Y231455D01*
X137839Y231442D01*
G03X137533Y229008I708J-1325D01*
G03X137711Y228868I1015J1107D01*
G01X137713Y228867D01*
G02X137780Y228792I-111J-167D01*
G01X137790Y228771D01*
X137801Y228722D01*
X137780Y228189D01*
X137396Y218596D01*
Y218594D01*
G03X137393Y218527I3921J-209D01*
G01Y218525D01*
G03X137392Y218441I3926J-89D01*
G01Y218439D01*
G03Y218436I200J-1D01*
G03X137393Y218378I3926J39D01*
G01Y218377D01*
X137418Y216756D01*
X137562Y207565D01*
Y207555D01*
X137468Y204858D01*
X137176Y196505D01*
G02X137038Y196321I-200J6D01*
G01X136833Y196239D01*
X136831D01*
X136780Y196219D01*
X136778D01*
X136739Y196204D01*
X136704D01*
G02X136640Y196217I7J200D01*
G01X136632Y196220D01*
X136543Y196258D01*
X136516Y196284D01*
X136515Y196285D01*
G03X135430Y196728I-1085J-1108D01*
G01X135429D01*
G03X134421Y196356I0J-1552D01*
G01X134394Y196333D01*
X134326Y196308D01*
X134284D01*
G03X134201Y196290I0J-200D01*
G01X134148Y196266D01*
G02X133940Y196291I-84J181D01*
G01X133912Y196313D01*
X133894Y196327D01*
X133891Y196329D01*
G03X132930Y196678I-962J-1152D01*
G01X132891D01*
G03X132047Y196392I38J-1502D01*
G01X132013Y196368D01*
X131993Y196351D01*
G02X131964Y196333I-120J161D01*
G01X131956Y196329D01*
G02X131867Y196308I-89J179D01*
G01X131784D01*
G03X131701Y196290I0J-200D01*
G01X131648Y196266D01*
G02X131440Y196291I-84J181D01*
G01X131412Y196313D01*
X131394Y196327D01*
X131391Y196329D01*
G03X130430Y196678I-962J-1152D01*
G01X130391D01*
G03X129547Y196392I38J-1502D01*
G01X129513Y196368D01*
X129493Y196351D01*
G02X129464Y196333I-120J161D01*
G01X129456Y196329D01*
G02X129367Y196308I-89J179D01*
G01X129284D01*
G03X129201Y196290I0J-200D01*
G01X129148Y196266D01*
G02X128940Y196291I-84J181D01*
G01X128912Y196313D01*
X128894Y196327D01*
X128891Y196329D01*
G03X127930Y196678I-962J-1152D01*
G01X127929D01*
G03Y193674I0J-1502D01*
G01X127930D01*
G03X128864Y194000I0J1502D01*
G01X128883Y194015D01*
X128912Y194028D01*
G02X128990Y194044I78J-184D01*
G01X129074D01*
G03X129157Y194062I0J200D01*
G01X129210Y194086D01*
G02X129418Y194061I84J-181D01*
G01X129446Y194039D01*
X129464Y194025D01*
X129467Y194023D01*
G03X130428Y193674I962J1152D01*
G01X130467D01*
G03X131363Y193999I-38J1502D01*
G01X131383Y194015D01*
X131414Y194029D01*
G02X131490Y194044I76J-185D01*
G01X131574D01*
G03X131657Y194062I0J200D01*
G01X131710Y194086D01*
G02X131918Y194061I84J-181D01*
G01X131946Y194039D01*
X131964Y194025D01*
X131967Y194023D01*
G03X132928Y193674I962J1152D01*
G01X132967D01*
G03X133863Y193999I-38J1502D01*
G01X133883Y194015D01*
X133914Y194029D01*
G02X133990Y194044I76J-185D01*
G01X134287D01*
G02X134307Y194043I0J-200D01*
G02X134349Y194034I-21J-199D01*
G01X134396Y194018D01*
X134426Y193993D01*
X134427Y193992D01*
G03X135429Y193624I1003J1184D01*
G03X136463Y194019I-1J1552D01*
G01X136468Y194023D01*
G02X136569Y194069I130J-152D01*
G01X136597Y194073D01*
X136626Y194068D01*
G02X136672Y194055I-31J-197D01*
G01X136823Y193984D01*
X136825D01*
X136979Y193909D01*
G02X137050Y193839I-100J-173D01*
G01X137056Y193829D01*
G02X137080Y193735I-176J-95D01*
G01X137079Y193706D01*
X137078Y193675D01*
X137066Y193340D01*
X136911Y188899D01*
Y188893D01*
X132624Y157164D01*
G03X132589Y156699I3891J-527D01*
G01X132547Y153984D01*
X132537Y153941D01*
X132527Y153921D01*
X132526Y153920D01*
Y153919D01*
G03X132317Y153410I3519J-1742D01*
G03X132119Y152236I3728J-1232D01*
G01X132118Y152178D01*
X132095Y150702D01*
X132089Y150286D01*
Y150285D01*
G03X132088Y150227I3925J-97D01*
G01Y150225D01*
G03Y150221I3927J-2D01*
G03X132118Y149734I3927J-2D01*
G01X132120Y149722D01*
Y149668D01*
G03Y149658I3891J-5D01*
G01Y149573D01*
G03Y149570I200J-2D01*
G01X132145Y148356D01*
X132140Y148332D01*
G03X132046Y147537I3832J-856D01*
G01X132016Y145583D01*
X132005Y145550D01*
X131989Y145507D01*
X131979Y145480D01*
G03X131968Y145451I3633J-1395D01*
G01Y145449D01*
X131955Y145416D01*
G03X131940Y145375I3647J-1358D01*
G01X131930Y145352D01*
G02X131852Y145270I-178J91D01*
G03X131483Y145315I-371J-1508D01*
G01X131481D01*
G03Y142209I0J-1553D01*
G03X131622Y142216I-6J1553D01*
G02X131633Y142207I-121J-159D01*
G01X131691Y142157D01*
X131721Y142131D01*
X131763Y142048D01*
X131771Y142032D01*
X131792Y141964D01*
X131794Y141945D01*
G03X131804Y141862I3868J424D01*
G01Y141860D01*
G03X131814Y141794I3853J550D01*
G01X131817Y141773D01*
G03X131966Y141162I3843J613D01*
G03X132228Y140549I3696J1217D01*
G01X132245Y140517D01*
X132250Y140480D01*
G02X132247Y140413I-199J-25D01*
G01X132237Y140373D01*
X132227Y140334D01*
X132197Y140225D01*
Y140223D01*
X132126Y139966D01*
G02X132057Y139874I-187J69D01*
G01X131860Y139756D01*
X131858D01*
X131812Y139729D01*
G02X131782Y139714I-104J171D01*
G01X131780D01*
G02X131767Y139709I-78J184D01*
G01X131696Y139726D01*
X131672Y139732D01*
G03X131339Y139797I-918J-3818D01*
G01X131337D01*
G03X131203Y139816I-618J-3878D01*
G01X131201D01*
G03X130771Y139842I-452J-3901D01*
G01X130721D01*
G03X128646Y139230I30J-3927D01*
G01X128638Y139232D01*
X128622Y139235D01*
G03X128352Y139259I-267J-1478D01*
G01X128350D01*
G03X126848Y137772I0J-1502D01*
G01Y137756D01*
G03X126984Y137132I1502J1D01*
G01X126993Y137112D01*
X127000Y137080D01*
G03X126824Y135917I3750J-1162D01*
G01Y135915D01*
G03X127176Y134289I3928J-1D01*
G02Y134141I-186J-74D01*
G03X126824Y132515I3576J-1625D01*
G01Y132511D01*
G03X127000Y131351I3926J2D01*
G01X126996Y131333D01*
X126982Y131292D01*
X126978Y131283D01*
G03X126848Y130685I1372J-611D01*
G01Y130664D01*
G03X128350Y129168I1502J6D01*
G01X128368D01*
G03X128620Y129192I-16J1502D01*
G01X128649Y129197D01*
G03X130717Y128588I2101J3318D01*
G01X130765D01*
G03X132851Y129198I-16J3927D01*
G01X132855Y129197D01*
G03X132876Y129193I292J1474D01*
G03X132887Y129191I274J1477D01*
G03X132937Y129183I262J1479D01*
G01X132939D01*
G03X133163Y129167I219J1486D01*
G01X133170D01*
G03X133237Y129169I-11J1504D01*
G03X133601Y129235I-84J1500D01*
G03X133609Y129237I-44J194D01*
G03X133619Y129241I-553J1397D01*
G01X133634Y129246D01*
X133666Y129251D01*
G02X133813Y129216I31J-198D01*
G01X133994Y129087D01*
X134091Y129018D01*
X134103Y129005D01*
G02X134126Y128976I-145J-138D01*
G01X134124Y128902D01*
Y128828D01*
G03X134476Y127202I3928J-1D01*
G02Y127054I-186J-74D01*
G03X134124Y125428I3576J-1625D01*
G01Y125427D01*
G03X134135Y125135I3926J2D01*
G01Y125133D01*
X134140Y125059D01*
G02X134139Y125057I-178J88D01*
G03X134137Y125055I137J-139D01*
G02X134133Y125049I-168J108D01*
G01X134092Y124995D01*
X134076Y124975D01*
G02X133987Y124915I-152J130D01*
G01X133961Y124906D01*
X133904Y124905D01*
X133830Y124924D01*
X133810Y124934D01*
G03X133755Y124960I-670J-1345D01*
G01X133727Y124971D01*
X133725Y124972D01*
X133688Y124987D01*
X131182Y125970D01*
G03X130914Y125830I-73J-186D01*
G01X130899Y125768D01*
G02X130877Y125717I-193J53D01*
G01X130860Y125690D01*
X130845Y125678D01*
G02X130834Y125669I-132J150D01*
G01X130719Y125668D01*
G03X128646Y125057I31J-3926D01*
G01X128607Y125064D01*
G03X128526Y125076I-261J-1479D01*
G01X128507Y125078D01*
X128506D01*
X128496Y125079D01*
G03X128411Y125085I-148J-1495D01*
G03X128370Y125086I-57J-1501D01*
G01X128358D01*
G03X128350I-4J-1502D01*
G03X126848Y123593I0J-1502D01*
G01Y123582D01*
G03X126993Y122937I1503J-1D01*
G01X127000Y122908D01*
G03X126824Y121759I3751J-1162D01*
G01Y121742D01*
G03X127176Y120116I3928J-1D01*
G02Y119968I-186J-74D01*
G03X126824Y118342I3576J-1625D01*
G01Y118340D01*
G03X127001Y117176I3926J2D01*
G01X126994Y117146D01*
X126985Y117127D01*
G03X126848Y116500I1365J-627D01*
G01Y116497D01*
G03X128350Y114995I1502J0D01*
G01X128354D01*
G03X128612Y115017I2J1502D01*
G01X128650Y115024D01*
G03X130750Y114415I2100J3318D01*
G03X132850Y115024I0J3927D01*
G01X132875Y115019D01*
G03X133150Y114995I268J1478D01*
G01X133166D01*
G03X133618Y115069I-14J1502D01*
G01X133620Y115070D01*
X133633Y115074D01*
X133656Y115079D01*
G02X133818Y115041I39J-196D01*
G01X133819Y115040D01*
X133823Y115038D01*
X134083Y114850D01*
G02X134126Y114803I-124J-157D01*
G01X134124Y114730D01*
Y114655D01*
G03X134476Y113029I3928J-1D01*
G02Y112881I-186J-74D01*
G03X134124Y111255I3576J-1625D01*
G03X134193Y110517I3926J-5D01*
G03X134260Y110228I3856J742D01*
G03X134300Y110090I3790J1024D01*
G01Y110089D01*
X134293Y110056D01*
G03X134284Y110036I1366J-627D01*
G01X134283Y110034D01*
G03X134148Y109430I1367J-623D01*
G01Y109409D01*
G03X135650Y107908I1502J1D01*
G03X135925Y107932I7J1503D01*
G01X135933Y107934D01*
G03X135943Y107936I-290J1474D01*
G01X135946D01*
X135951Y107937D01*
G03X136120Y107835I2113J3310D01*
G03X136124Y107833I91J178D01*
G03X136137Y107826I1868J3453D01*
G01X136206Y107788D01*
G02X136218Y107759I-179J-91D01*
G01X136298Y107462D01*
X136297Y107408D01*
X136290Y107382D01*
X136273Y107321D01*
X136261Y107300D01*
G03X136067Y106562I1308J-738D01*
G01Y106526D01*
X136068Y106510D01*
Y106507D01*
G03X136077Y106388I1501J54D01*
G03X136244Y105854I1492J173D01*
G03X136642Y105379I1325J706D01*
G01X136650Y105373D01*
X136678Y105346D01*
X136729Y105284D01*
X136739Y105263D01*
X136749Y105217D01*
X136733Y104911D01*
X136731Y104862D01*
X136672Y104761D01*
G02X136641Y104720I-174J99D01*
G01X136612Y104691D01*
X136580Y104664D01*
X136571Y104658D01*
G03X135907Y103411I839J-1247D01*
G03X138913I1503J0D01*
G03X138318Y104609I-1504J0D01*
G01X138305Y104619D01*
X138290Y104634D01*
X138266Y104665D01*
G02X138233Y104771I167J110D01*
G01X138248Y105105D01*
X138267Y105142D01*
X138271Y105151D01*
X138306Y105210D01*
X138320Y105233D01*
X138382Y105297D01*
X138407Y105314D01*
G03X139071Y106557I-838J1247D01*
G01Y106575D01*
G03X138992Y107043I-1502J-13D01*
G01X138979Y107082D01*
X138981Y107120D01*
G02X139002Y107197I200J-13D01*
G01X139054Y107301D01*
X139112Y107416D01*
G02X139114Y107419I167J-109D01*
G01X139117Y107425D01*
G02X139133Y107449I174J-99D01*
G02X139160Y107477I157J-124D01*
G01X139180Y107494D01*
X139227Y107509D01*
G03X140123Y107920I-1176J3746D01*
G01X140157D01*
G03X140350Y107907I197J1490D01*
G03X140426Y107909I-2J1503D01*
G01X140464Y107912D01*
G03X141553Y108510I-114J1498D01*
G01X141561Y108520D01*
G03X143736Y109624I-602J3880D01*
G01X149256Y115143D01*
X149268Y115149D01*
G03X149280Y115155I-666J1347D01*
G01X149284Y115157D01*
G03X149941Y115814I-682J1339D01*
G01X149943Y115818D01*
G03X149949Y115830I-1341J678D01*
G01X149955Y115842D01*
X150425Y116312D01*
X155149Y121037D01*
G03X155512Y121454I-2773J2780D01*
G03X155736Y121785I-3136J2363D01*
G01X155740Y121792D01*
X155764Y121825D01*
G03X155973Y122072I-2864J2635D01*
G03X156169Y122346I-3064J2399D01*
G03X156234Y122450I-3267J2114D01*
G01X156238Y122458D01*
X156244Y122467D01*
G03X156268Y122507I-3325J2022D01*
G03X156300Y122562I-3348J1985D01*
G01Y122563D01*
X156324Y122607D01*
X156328Y122615D01*
G03X156500Y122977I-3424J1849D01*
G01X158824Y128586D01*
X159105Y129263D01*
G02X159138Y129316I184J-78D01*
G01X159157Y129339D01*
X159191Y129358D01*
G03X159962Y130665I-731J1312D01*
G01Y130681D01*
G03X159959Y130771I-1502J-5D01*
G01Y130773D01*
G03X159917Y131035I-1499J-106D01*
G01X159911Y131059D01*
X159901Y131102D01*
G02X159898Y131133I197J35D01*
G01X159901Y131183D01*
X163005Y138679D01*
X166048Y146026D01*
G03X166232Y146590I-3596J1485D01*
G01X166235Y146601D01*
G02X166238Y146611I193J-52D01*
G01X166273Y146693D01*
Y146695D01*
X166319Y146805D01*
X166320D01*
X166340Y146853D01*
Y146855D01*
G03X166648Y148378I-3618J1524D01*
G01Y148443D01*
Y148447D01*
X166602Y151228D01*
X166590Y151942D01*
G03X166507Y152682I-3926J-66D01*
G01X166310Y153623D01*
X164833Y160680D01*
X164832Y160683D01*
G02X164915Y160884I197J36D01*
G01X165217Y161093D01*
G02X165328Y161129I114J-164D01*
G01X165357Y161130D01*
X165412Y161114D01*
X165438Y161098D01*
G03X166240Y160866I802J1270D01*
G03X167267Y161272I0J1502D01*
G01X167268Y161273D01*
G02X167339Y161315I135J-147D01*
G02X167404Y161326I65J-189D01*
G01X167676D01*
G02X167741Y161315I0J-200D01*
G02X167812Y161273I-64J-189D01*
G01X167813Y161272D01*
G03X168840Y160866I1027J1096D01*
G03Y163870I0J1502D01*
G03X167813Y163464I0J-1502D01*
G01X167812Y163463D01*
G02X167741Y163421I-135J147D01*
G02X167676Y163410I-65J189D01*
G01X167404D01*
G02X167339Y163421I0J200D01*
G02X167268Y163463I64J189D01*
G01X167267Y163464D01*
G03X166240Y163870I-1027J-1096D01*
G03X164996Y163210I0J-1502D01*
G01Y163209D01*
G02X164907Y163137I-165J113D01*
G02X164792Y163126I-76J185D01*
G01X164431Y163196D01*
G02X164397Y163206I39J196D01*
G02X164273Y163352I72J187D01*
G01X162118Y173644D01*
Y173648D01*
X160013Y184782D01*
X158960Y190353D01*
X158202Y194363D01*
X158100Y194901D01*
G02X158097Y194935I197J35D01*
G01X157915Y206610D01*
G02X157935Y206701I200J4D01*
G01X157945Y206722D01*
X157975Y206758D01*
X157995Y206773D01*
G03X158311Y208860I-902J1204D01*
G01X158286Y208894D01*
X158271Y208913D01*
G02X158250Y208947I159J122D01*
G01X158248Y208951D01*
G02X158227Y209040I179J89D01*
G01Y209123D01*
G03X158209Y209206I-200J0D01*
G01X158185Y209259D01*
G02X158210Y209467I181J84D01*
G01X158232Y209495D01*
X158246Y209513D01*
X158248Y209516D01*
X158250Y209518D01*
X158253Y209522D01*
G03X158597Y210462I-1158J957D01*
G01Y210474D01*
G03X158481Y211058I-1502J5D01*
G01Y211059D01*
X158476Y211069D01*
G03X158311Y211360I-1381J-591D01*
G01X158287Y211393D01*
X158269Y211416D01*
G02X158252Y211443I160J120D01*
G01X158248Y211451D01*
G02X158227Y211540I179J89D01*
G01Y211623D01*
G03X158209Y211706I-200J0D01*
G01X158185Y211759D01*
G02X158210Y211967I181J84D01*
G01X158232Y211995D01*
X158246Y212013D01*
X158248Y212016D01*
X158250Y212018D01*
X158253Y212022D01*
G03X158597Y212962I-1158J957D01*
G01Y212974D01*
G03X158481Y213558I-1502J5D01*
G01Y213559D01*
X158476Y213569D01*
G03X158311Y213860I-1381J-591D01*
G01X158287Y213893D01*
X158269Y213916D01*
G02X158252Y213943I160J120D01*
G01X158248Y213951D01*
G02X158227Y214040I179J89D01*
G01Y214124D01*
X158232Y214176D01*
X158283Y214300D01*
X158309Y214327D01*
G03X158768Y215478I-1213J1151D01*
G03X158051Y216852I-1675J0D01*
G01X158037Y216862D01*
X158031Y216866D01*
X158008Y216892D01*
G02X157995Y216910I155J126D01*
G01X157938Y217012D01*
G02X157929Y217037I184J80D01*
G03X157928Y217041I-194J-46D01*
G02X157924Y217060I194J51D01*
G01X157921Y217094D01*
X157981Y218860D01*
X158015Y219838D01*
X158038Y220501D01*
X158040Y220548D01*
X158042Y220612D01*
X158092Y222038D01*
X158103Y222340D01*
X158110Y222548D01*
G02X158118Y222583I198J-27D01*
G01X158129Y222616D01*
G02X158166Y222673I184J-79D01*
G01X158171Y222678D01*
G03X158597Y223726I-1076J1048D01*
G01Y223730D01*
G03X158259Y224677I-1502J-2D01*
G01X158238Y224703D01*
X158190Y224832D01*
X158191Y224871D01*
Y224872D01*
X158201Y225136D01*
X158202Y225166D01*
X158225Y225235D01*
X158249Y225264D01*
X158250Y225265D01*
G03X158264Y225282I-1153J963D01*
G01X158625Y225718D01*
G03X158604Y225995I-154J128D01*
G01X158585Y226014D01*
X158589Y226069D01*
Y226075D01*
G03X158597Y226229I-1494J155D01*
G01Y226264D01*
G03X158328Y227085I-1502J-38D01*
G01X158316Y227101D01*
X158295Y227130D01*
X158290Y227145D01*
X158280Y227178D01*
X158272Y227204D01*
X158277Y227333D01*
Y227335D01*
X158288Y227640D01*
Y227642D01*
X158292Y227771D01*
G02X158321Y227857I199J-19D01*
G01X158328Y227868D01*
G03X158333Y227875I-1219J876D01*
G01X158336Y227879D01*
X158337Y227880D01*
X158347Y227895D01*
X158352Y227902D01*
X158356Y227909D01*
X158363Y227919D01*
X158372Y227933D01*
G03X158597Y228712I-1278J791D01*
G01Y228727D01*
G03X158397Y229476I-1502J0D01*
G01X158384Y229498D01*
X158356Y229598D01*
X158357Y229630D01*
X158370Y230002D01*
X158384Y230405D01*
G02X158393Y230456I200J-9D01*
G01X158399Y230477D01*
X158409Y230497D01*
X158411Y230500D01*
X158412Y230502D01*
X158414Y230505D01*
G03X158597Y231224I-1321J719D01*
G01Y231245D01*
G03X158594Y231326I-1502J-15D01*
G01Y231328D01*
G03X158590Y231372I-1498J-114D01*
G01Y231376D01*
G03X158555Y231582I-1495J-148D01*
G03X158474Y231821I-1458J-361D01*
G01Y231823D01*
G03X158471Y231829I-1343J-668D01*
G01X158470Y231831D01*
G03X158469Y231833I-1343J-670D01*
G03X158460Y231853I-1374J-606D01*
G01X158456Y231862D01*
X158437Y231917D01*
X158438Y231952D01*
Y231956D01*
X158539Y234847D01*
X158798Y242259D01*
X159083Y250425D01*
X159126Y251656D01*
Y251658D01*
X159307Y256183D01*
Y256187D01*
X159344Y256654D01*
X159388Y257190D01*
G02X159479Y257342I199J-16D01*
G01X159509Y257361D01*
X159511D01*
X159606Y257423D01*
X159617Y257431D01*
G02X159639Y257442I100J-173D01*
G01X159641D01*
G02X159697Y257458I82J-182D01*
G01X159699D01*
G02X159723Y257460I29J-198D01*
G01X159805D01*
G02X159829Y257458I-5J-200D01*
G01X159880Y257450D01*
X159890Y257447D01*
X159896Y257445D01*
G03X160343Y257378I444J1436D01*
G01X160360D01*
G03X161851Y258880I-11J1502D01*
G03X160349Y260382I-1502J0D01*
G03X160057Y260354I-3J-1502D01*
G01X160010Y260345D01*
X159966Y260357D01*
G02X159884Y260401I51J193D01*
G01X159768Y260506D01*
X159735Y260536D01*
G02X159670Y260700I134J148D01*
G01X159758Y261802D01*
X159770Y261953D01*
X159807Y262421D01*
G02X159883Y262558I199J-21D01*
G01X159989Y262641D01*
X159994Y262644D01*
X160019Y262669D01*
X160055Y262684D01*
G02X160131Y262699I76J-185D01*
G01X160169D01*
X160185Y262696D01*
G03X160387Y262678I234J1484D01*
G01X160432D01*
G03X160499Y262679I11J1501D01*
G03X160501Y262680I-81J164D01*
G03X160739Y262711I-74J1499D01*
G03X160989Y262788I-316J1469D01*
G03X161359Y263004I-564J1391D01*
G01X161361Y263005D01*
G02X161484Y263048I124J-157D01*
G01X161569D01*
G03X161652Y263066I0J200D01*
G01X161705Y263090D01*
G02X161913Y263065I84J-181D01*
G01X161941Y263043D01*
X161959Y263029D01*
X161962Y263027D01*
G03X162923Y262678I962J1152D01*
G01X162924D01*
G03X164426Y264180I0J1502D01*
G03X162939Y265682I-1502J0D01*
G01X162922D01*
G03X162041Y265396I1J-1502D01*
G01X162008Y265371D01*
X161989Y265356D01*
G02X161955Y265335I-122J159D01*
G01X161951Y265333D01*
G02X161862Y265312I-89J179D01*
G01X161779D01*
G03X161696Y265294I0J-200D01*
G01X161643Y265270D01*
G02X161435Y265295I-84J181D01*
G01X161407Y265317D01*
X161389Y265331D01*
X161386Y265333D01*
G03X160425Y265682I-962J-1152D01*
G01X160398D01*
G02X160367Y265685I4J200D01*
G02X160267Y265736I37J197D01*
G01X160198Y265809D01*
G02X160196Y265811I140J142D01*
G01X160148Y265863D01*
G02X160096Y266014I147J135D01*
G01X160765Y274354D01*
X163451Y307806D01*
G02X163548Y307957I199J-21D01*
G01X163673Y308029D01*
G02X163814Y308052I101J-173D01*
G01X163861Y308042D01*
X163881Y308033D01*
G03X164464Y307903I612J1372D01*
G01X164512D01*
G03X165998Y309405I-16J1502D01*
G03X164496Y310907I-1502J0D01*
G01X164495D01*
G03X164115Y310858I1J-1502D01*
G01X164111Y310857D01*
X164102Y310855D01*
X164080Y310849D01*
G02X163904Y310889I-48J194D01*
G01X163791Y310982D01*
G02X163717Y311141I126J155D01*
G01X166753Y348959D01*
X171678Y410316D01*
G03X171689Y410511I-3914J319D01*
G01X173511Y470607D01*
G03X173512Y470652I-3925J110D01*
G01Y470674D01*
G03Y470725I-3926J26D01*
G01Y470768D01*
X173299Y490564D01*
X173209Y498941D01*
X172761Y540537D01*
G02X172790Y540644I200J3D01*
G02X172897Y540729I170J-105D01*
G01X173263Y540852D01*
G02X173320Y540861I59J-191D01*
G01X173439Y540802D01*
G02X173507Y540746I-90J-179D01*
G03X174197Y540212I1415J1116D01*
G03X174808Y540063I726J1650D01*
G01X174850Y540060D01*
G03X174922Y540059I61J1802D01*
G01X174924D01*
G03X176726Y541861I-1J1803D01*
G01Y545262D01*
G03X173120I-1803J0D01*
G01Y544427D01*
Y544426D01*
G02X172921Y544227I-200J1D01*
G01X172918D01*
G02X172719Y544425I1J200D01*
G01X172710Y545269D01*
X172686Y547465D01*
X172666Y549254D01*
X172672Y549260D01*
X172789Y549365D01*
G02X172862Y549407I134J-148D01*
G01X172901Y549420D01*
X172945Y549415D01*
G03X173115Y549405I173J1492D01*
G03X173315Y549418I3J1502D01*
G03X174049Y549730I-200J1489D01*
G01X174069Y549746D01*
X174100Y549760D01*
G02X174176Y549775I76J-185D01*
G01X174260D01*
G03X174343Y549793I0J200D01*
G01X174396Y549817D01*
G02X174604Y549792I84J-181D01*
G01X174632Y549770D01*
X174650Y549756D01*
X174653Y549754D01*
G03X175614Y549405I962J1152D01*
G01X175615D01*
G03X175617I1J1502D01*
G03X176877Y550091I-1J1502D01*
G01X176881Y550097D01*
G03X177115Y550825I-1266J809D01*
G03X177117Y550890I-1500J79D01*
G01Y550943D01*
X177116Y550954D01*
G03X176831Y551790I-1502J-45D01*
G01X176806Y551823D01*
X176791Y551842D01*
G02X176770Y551876I159J122D01*
G01X176768Y551880D01*
G02X176747Y551969I179J89D01*
G01Y552052D01*
G03X176729Y552135I-200J0D01*
G01X176705Y552188D01*
G02X176730Y552396I181J84D01*
G01X176752Y552424D01*
X176766Y552442D01*
X176768Y552445D01*
X176774Y552452D01*
G03X177115Y553330I-1159J955D01*
G03X177117Y553403I-1500J78D01*
G01Y553407D01*
G03X175630Y554909I-1502J0D01*
G01X175613D01*
G03X174732Y554623I1J-1502D01*
G01X174699Y554598D01*
X174680Y554583D01*
G02X174646Y554562I-122J159D01*
G01X174642Y554560D01*
G02X174553Y554539I-89J179D01*
G01X174470D01*
G03X174387Y554521I0J-200D01*
G01X174334Y554497D01*
G02X174126Y554522I-84J181D01*
G01X174098Y554544D01*
X174080Y554558D01*
X174077Y554560D01*
G03X173118Y554909I-962J-1152D01*
G03X173112I-3J-1502D01*
G37*
G36*
G01X76244Y1011614D02*
X93119D01*
G02X93259Y1011557I0J-200D01*
G01X93260Y1011556D01*
X97937Y1006879D01*
G03X98079Y1006820I142J141D01*
G01X109183D01*
G02X109324Y1006762I0J-200D01*
G01X112028Y1004059D01*
G02X112030Y1004057I-140J-142D01*
G02X112087Y1003917I-143J-140D01*
G01Y999756D01*
G02X112034Y999620I-200J0D01*
G01X111823Y999392D01*
X111756Y999360D01*
X111718Y999357D01*
G03Y996363I118J-1497D01*
G01X111756Y996360D01*
X111823Y996328D01*
X112034Y996100D01*
G02X112087Y995964I-147J-136D01*
G01Y990709D01*
G02X112034Y990573I-200J0D01*
G01X111823Y990345D01*
X111756Y990313D01*
X111718Y990310D01*
G03Y987316I118J-1497D01*
G01X111756Y987313D01*
X111823Y987281D01*
X112034Y987053D01*
G02X112087Y986917I-147J-136D01*
G01Y916612D01*
G03X112146Y916470I200J0D01*
G01X129923Y898693D01*
G02X129925Y898691I-140J-142D01*
G02X129982Y898551I-143J-140D01*
G01Y872985D01*
G02X129923Y872843I-200J0D01*
G01X126022Y868942D01*
X125994Y868913D01*
X125920Y868883D01*
X105228D01*
G02X105057Y868980I0J200D01*
G03X102483I-1287J-774D01*
G02X102312Y868883I-171J103D01*
G01X66872D01*
G02X66730Y868942I0J200D01*
G01X62161Y873511D01*
X62132Y873539D01*
X62102Y873613D01*
Y874195D01*
G02X62302Y874395I200J0D01*
G01X62369D01*
X62474Y874317D01*
X62493Y874254D01*
G03X63930Y873192I1437J441D01*
G03X65432Y874694I0J1502D01*
G03X63962Y876196I-1502J0D01*
G01X63929D01*
G03X62802Y875687I0J-1502D01*
G01Y875686D01*
X62801Y875685D01*
G02X62581Y875631I-149J133D01*
G01X62232Y875763D01*
G02X62207Y875774I68J188D01*
G02X62102Y875948I95J176D01*
G01Y911111D01*
G02X62130Y911213I200J0D01*
G01X62144Y911237D01*
X62183Y911274D01*
X62207Y911287D01*
X62521Y911488D01*
X62623Y911494D01*
X62670Y911473D01*
G03X63302Y911333I633J1362D01*
G01X63303D01*
G03Y914337I0J1502D01*
G01X63301D01*
G03X62670Y914197I2J-1502D01*
G01X62623Y914176D01*
X62521Y914182D01*
X62150Y914419D01*
X62102Y914508D01*
Y997472D01*
G02X62159Y997612I200J0D01*
G01X62160Y997613D01*
X76102Y1011555D01*
G02X76104Y1011557I142J-140D01*
G02X76244Y1011614I140J-143D01*
G37*
G36*
G01X137657Y54588D02*
X166715D01*
X166891Y54412D01*
Y52762D01*
X166720Y52591D01*
X137657D01*
G03X131720Y46654I0J-5937D01*
G01Y7874D01*
G02X125846Y2000I-5874J0D01*
G01X78602D01*
G02X72728Y7874I0J5874D01*
G01Y45793D01*
X74726D01*
Y7874D01*
G03X78602Y3998I3876J0D01*
G01X125846D01*
G03X129722Y7874I0J3876D01*
G01Y46654D01*
G02X137657Y54588I7935J-1D01*
G37*
G36*
G01X96775Y1183062D02*
X106879D01*
G02X107021Y1183003I0J-200D01*
G01X110128Y1179896D01*
G02X110187Y1179754I-141J-142D01*
G01Y1179390D01*
G02X110092Y1179220I-200J0D01*
G01X109757Y1179014D01*
X109654Y1179009D01*
X109607Y1179033D01*
G03X108933Y1179193I-675J-1342D01*
G03Y1176189I0J-1502D01*
G03X109772Y1176445I0J1503D01*
G02X109971Y1176459I112J-166D01*
G01X110074Y1176409D01*
G02X110187Y1176229I-87J-180D01*
G01Y1176219D01*
X110260Y1176092D01*
G02X110287Y1175992I-173J-100D01*
G01Y1166736D01*
G02X110187Y1166563I-200J0D01*
G01X109839Y1166363D01*
X109733D01*
X109686Y1166390D01*
G03X108933Y1166593I-754J-1299D01*
G03Y1163589I0J-1502D01*
G03X109686Y1163792I-1J1502D01*
G01X109733Y1163819D01*
X109839D01*
X110187Y1163619D01*
G02X110287Y1163446I-100J-173D01*
G01Y1154136D01*
G02X110187Y1153963I-200J0D01*
G01X109839Y1153763D01*
X109733D01*
X109686Y1153790D01*
G03X108933Y1153993I-754J-1299D01*
G03Y1150989I0J-1502D01*
G03X109686Y1151192I-1J1502D01*
G01X109733Y1151219D01*
X109839D01*
X110187Y1151019D01*
G02X110287Y1150846I-100J-173D01*
G01Y1128936D01*
G02X110187Y1128763I-200J0D01*
G01X109839Y1128563D01*
X109733D01*
X109686Y1128590D01*
G03X108933Y1128793I-754J-1299D01*
G03Y1125789I0J-1502D01*
G03X109686Y1125992I-1J1502D01*
G01X109733Y1126019D01*
X109839D01*
X110187Y1125819D01*
G02X110287Y1125646I-100J-173D01*
G01Y1116336D01*
G02X110187Y1116163I-200J0D01*
G01X109839Y1115963D01*
X109733D01*
X109686Y1115990D01*
G03X108933Y1116193I-754J-1299D01*
G03Y1113189I0J-1502D01*
G03X109686Y1113392I-1J1502D01*
G01X109733Y1113419D01*
X109839D01*
X110187Y1113219D01*
G02X110287Y1113046I-100J-173D01*
G01Y1103736D01*
G02X110187Y1103563I-200J0D01*
G01X109839Y1103363D01*
X109733D01*
X109686Y1103390D01*
G03X108933Y1103593I-754J-1299D01*
G03Y1100589I0J-1502D01*
G03X109686Y1100792I-1J1502D01*
G01X109733Y1100819D01*
X109839D01*
X110187Y1100619D01*
G02X110287Y1100446I-100J-173D01*
G01Y1097974D01*
G02X110228Y1097832I-200J0D01*
G01X96438Y1084042D01*
G03X96379Y1083900I141J-142D01*
G01Y1058194D01*
G03X96438Y1058052I200J0D01*
G01X122554Y1031936D01*
G02X122556Y1031934I-140J-142D01*
G02X122613Y1031794I-143J-140D01*
G01Y1022282D01*
X122609Y1022261D01*
G03X122577Y1021954I1470J-308D01*
G03X122609Y1021647I1502J1D01*
G01X122613Y1021626D01*
Y1016231D01*
G02X122554Y1016089I-200J0D01*
G01X120781Y1014316D01*
X120753Y1014287D01*
X120679Y1014257D01*
X109840D01*
G03X109698Y1014198I0J-200D01*
G01X108001Y1012501D01*
G03X107942Y1012359I141J-142D01*
G01Y1009436D01*
G02X107883Y1009294I-200J0D01*
G01X107094Y1008505D01*
G02X106952Y1008446I-142J141D01*
G01X99606D01*
G02X99464Y1008505I0J200D01*
G01X93771Y1014198D01*
G03X93629Y1014257I-142J-141D01*
G01X89463D01*
X89369Y1014315D01*
X89342Y1014365D01*
G03X86672I-1335J-686D01*
G01X86645Y1014315D01*
X86551Y1014257D01*
X85164D01*
G02X85022Y1014316I0J200D01*
G01X82529Y1016809D01*
X82500Y1016837D01*
X82470Y1016911D01*
Y1171847D01*
G02X82527Y1171987I200J0D01*
G01X82528Y1171988D01*
X85313Y1174773D01*
X85341Y1174787D01*
G03X90446Y1179347I-6011J11867D01*
G02X90613Y1179437I167J-110D01*
G01X92984D01*
G03X93126Y1179496I0J200D01*
G01X96633Y1183003D01*
G02X96775Y1183062I142J-141D01*
G37*
G36*
G01X110723Y1012798D02*
X125464D01*
G02X125606Y1012739I0J-200D01*
G01X129569Y1008776D01*
G03X129711Y1008717I142J141D01*
G01X135089D01*
G02X135263Y1008615I0J-200D01*
G03X137879I1308J740D01*
G02X138053Y1008717I174J-98D01*
G01X162024D01*
G02X162166Y1008658I0J-200D01*
G01X163713Y1007111D01*
G02X163772Y1006969I-141J-142D01*
G01Y992920D01*
G02X163771Y992901I-200J1D01*
G01X158635Y938179D01*
G02X158633Y938161I-199J13D01*
G01X153675Y911980D01*
G02X153620Y911876I-197J37D01*
G01X149452Y907708D01*
G02X149310Y907649I-142J141D01*
G01X123492D01*
G02X123350Y907708I0J200D01*
G01X114253Y916805D01*
G02X114194Y916947I141J142D01*
G01Y987373D01*
G02X114311Y987554I200J-1D01*
G01X114695Y987731D01*
X114810Y987714D01*
X114855Y987675D01*
G03X115836Y987311I980J1138D01*
G03Y990315I0J1502D01*
G03X114855Y989951I-1J-1502D01*
G01X114810Y989912D01*
X114695Y989895D01*
X114311Y990072D01*
G02X114194Y990253I83J182D01*
G01Y1003391D01*
G03X114135Y1003533I-200J0D01*
G01X109700Y1007968D01*
G02X109641Y1008110I141J142D01*
G01Y1011716D01*
G02X109700Y1011858I200J0D01*
G01X110581Y1012739D01*
G02X110723Y1012798I142J-141D01*
G37*
G36*
G01X147924Y1175736D02*
X149341Y1177153D01*
G02X149458Y1177203I133J-150D01*
G01X149745Y1177210D01*
G02X149820Y1177197I4J-200D01*
G01X149854Y1177184D01*
X149883Y1177158D01*
G03X150688Y1176849I805J894D01*
G03X151890Y1178051I0J1202D01*
G03X151464Y1178969I-1202J0D01*
G01X151457Y1178975D01*
X151451Y1178981D01*
G02Y1179263I142J141D01*
G01X151592Y1179404D01*
G02X151733Y1179462I141J-142D01*
G01X153187D01*
G02X153362Y1179357I-1J-200D01*
G01X153446Y1179184D01*
Y1179182D01*
X153475Y1179122D01*
G02X153490Y1179079I-180J-87D01*
G02X153445Y1178905I-196J-42D01*
G03X153127Y1178053I984J-853D01*
G01Y1178051D01*
G03X154429Y1176748I1303J0D01*
G01X154605D01*
G02X154754Y1176682I1J-200D01*
G01X154981Y1176431D01*
X155007Y1176351D01*
X155003Y1176309D01*
G03X154996Y1176181I1296J-135D01*
G01Y1176179D01*
G03X155014Y1175966I1303J3D01*
G01X155022Y1175920D01*
X154994Y1175830D01*
X154739Y1175563D01*
G02X154573Y1175503I-144J139D01*
G01X154572D01*
G03X154429Y1175512I-147J-1193D01*
G03X155631Y1174310I0J-1202D01*
G03X155622Y1174452I-1202J-5D01*
G01Y1174454D01*
X155617Y1174500D01*
X155649Y1174588D01*
X155949Y1174875D01*
X156039Y1174903D01*
X156085Y1174895D01*
G03X156299Y1174878I210J1285D01*
G01X156576D01*
G02X156725Y1174812I0J-200D01*
G01X156952Y1174558D01*
X156978Y1174478D01*
X156974Y1174436D01*
G03X156967Y1174310I1195J-130D01*
G03X159371I1202J0D01*
G03X159364Y1174435I-1202J-5D01*
G01Y1174437D01*
X159360Y1174478D01*
X159386Y1174558D01*
X159613Y1174812D01*
G02X159762Y1174878I149J-134D01*
G01X160039D01*
G03X160253Y1174895I4J1302D01*
G01X160299Y1174903D01*
X160389Y1174875D01*
X160656Y1174620D01*
G02X160716Y1174454I-139J-144D01*
G01Y1174453D01*
G03X160707Y1174310I1193J-147D01*
G03X161909Y1175512I1202J0D01*
G03X161767Y1175503I5J-1202D01*
G01X161765D01*
X161719Y1175498D01*
X161631Y1175530D01*
X161344Y1175830D01*
X161316Y1175920D01*
X161324Y1175966D01*
G03X161342Y1176180I-1285J216D01*
G03X161324Y1176395I-1303J-1D01*
G01X161316Y1176441D01*
X161344Y1176531D01*
X161632Y1176832D01*
X161718Y1176864D01*
X161742Y1176861D01*
G03X161909Y1176849I169J1190D01*
G03X163111Y1178051I0J1202D01*
G01Y1178053D01*
G03X162857Y1178791I-1202J-1D01*
G01X162841Y1178811D01*
X162797Y1178914D01*
X162794Y1178939D01*
X162803Y1178996D01*
X162822Y1179035D01*
X162971Y1179348D01*
G02X163151Y1179462I180J-86D01*
G01X163182D01*
G03X165747Y1180460I-1J3797D01*
G01X165773Y1180485D01*
X165872Y1180525D01*
G02X165910Y1180536I74J-186D01*
G02X165946Y1180539I35J-197D01*
G01X187442D01*
G02X187479Y1180535I-3J-200D01*
G01X187481D01*
G02X187582Y1180482I-39J-196D01*
G01X188033Y1180031D01*
G02X188086Y1179930I-143J-140D01*
G01Y1179928D01*
G02X188090Y1179891I-196J-40D01*
G01Y1179438D01*
G02X188041Y1179307I-200J0D01*
G01X188019Y1179280D01*
X187954Y1179246D01*
X187915Y1179241D01*
G03X187223Y1177218I176J-1190D01*
G03X187918Y1176861I867J833D01*
G01X187924Y1176860D01*
X187942Y1176858D01*
G02X188052Y1176793I-42J-196D01*
G01X188090Y1176749D01*
G03X188445Y1176799I-2J1302D01*
G01X188491Y1176812D01*
X188535Y1176804D01*
G02X188575Y1176792I-37J-197D01*
G03X188582Y1176785I868J861D01*
G01X188642Y1176725D01*
G03X188663Y1176706I144J139D01*
G01X188864Y1176556D01*
G02X188934Y1176414I-109J-142D01*
G01Y1172207D01*
G02X188863Y1172065I-179J1D01*
G01X188775Y1171998D01*
G02X188773Y1171996I-141J139D01*
G01X188710Y1171949D01*
G03X188572Y1171828I735J-977D01*
G02X188535Y1171817I-75J185D01*
G01X188491Y1171809D01*
X188445Y1171822D01*
G03X188090Y1171872I-357J-1252D01*
G03X186788Y1170570I0J-1302D01*
G03X186936Y1169968I1302J1D01*
G01Y1169967D01*
X186937Y1169966D01*
G02X186959Y1169869I-178J-91D01*
G01X186957Y1169816D01*
X186898Y1169719D01*
X186747Y1169470D01*
G02X186605Y1169383I-166J111D01*
G01X186593Y1169382D01*
X185854D01*
G02X185836Y1169383I2J200D01*
G01X185835D01*
G02X185692Y1169472I24J198D01*
G01X185650Y1169541D01*
X185506Y1169778D01*
G02X185481Y1169869I175J97D01*
G01X185480Y1169919D01*
X185510Y1169978D01*
X185524Y1170007D01*
G03X185652Y1170570I-1174J563D01*
G03X183048I-1302J0D01*
G03X183196Y1169968I1302J1D01*
G01Y1169967D01*
X183197Y1169966D01*
G02X183219Y1169869I-178J-91D01*
G01X183217Y1169816D01*
X183158Y1169719D01*
X183007Y1169470D01*
G02X182865Y1169383I-166J111D01*
G01X182853Y1169382D01*
X182114D01*
G02X182096Y1169383I2J200D01*
G01X182095D01*
G02X181952Y1169472I24J198D01*
G01X181910Y1169541D01*
X181766Y1169778D01*
G02X181741Y1169869I175J97D01*
G01X181740Y1169919D01*
X181770Y1169978D01*
X181784Y1170007D01*
G03X181912Y1170570I-1174J563D01*
G03X179308I-1302J0D01*
G03X179456Y1169968I1302J1D01*
G01Y1169967D01*
X179457Y1169966D01*
G02X179479Y1169869I-178J-91D01*
G01X179477Y1169816D01*
X179418Y1169719D01*
X179267Y1169470D01*
G02X179125Y1169383I-166J111D01*
G01X179113Y1169382D01*
X178374D01*
G02X178356Y1169383I2J200D01*
G01X178355D01*
G02X178212Y1169472I24J198D01*
G01X178170Y1169541D01*
X178026Y1169778D01*
G02X178001Y1169869I175J97D01*
G01X178000Y1169919D01*
X178030Y1169978D01*
X178044Y1170007D01*
G03X178172Y1170570I-1174J563D01*
G03X175568I-1302J0D01*
G03X175716Y1169968I1302J1D01*
G01Y1169967D01*
X175717Y1169966D01*
G02X175739Y1169869I-178J-91D01*
G01X175737Y1169816D01*
X175678Y1169719D01*
X175527Y1169470D01*
G02X175385Y1169383I-166J111D01*
G01X175373Y1169382D01*
X174633D01*
G02X174615Y1169383I2J200D01*
G01X174614D01*
G02X174471Y1169472I24J198D01*
G01X174429Y1169541D01*
X174285Y1169778D01*
G02X174260Y1169869I175J97D01*
G01X174259Y1169919D01*
X174289Y1169978D01*
X174303Y1170007D01*
G03X174431Y1170570I-1174J563D01*
G03X171827I-1302J0D01*
G03X171975Y1169968I1302J1D01*
G01Y1169967D01*
X171976Y1169966D01*
G02X171998Y1169869I-178J-91D01*
G01X171996Y1169816D01*
X171937Y1169719D01*
X171786Y1169470D01*
G02X171644Y1169383I-166J111D01*
G01X171632Y1169382D01*
X167153D01*
G02X167135Y1169383I2J200D01*
G01X167134D01*
G02X166991Y1169472I24J198D01*
G01X166949Y1169541D01*
X166805Y1169778D01*
G02X166780Y1169869I175J97D01*
G01X166779Y1169919D01*
X166809Y1169978D01*
X166823Y1170007D01*
G03X166951Y1170570I-1174J563D01*
G03X164347I-1302J0D01*
G03X164892Y1169511I1301J0D01*
G01X164893Y1169510D01*
G02X164973Y1169382I-117J-162D01*
G02X164974Y1169378I-193J-50D01*
G01X164988Y1169213D01*
Y1169211D01*
X165000Y1169060D01*
G02X164942Y1168902I-199J-16D01*
G01X152357Y1156317D01*
G02X152199Y1156259I-142J141D01*
G01X152048Y1156271D01*
X152046D01*
X151881Y1156285D01*
G02X151877Y1156286I46J194D01*
G02X151749Y1156366I34J197D01*
G01X151748Y1156367D01*
G03X150689Y1156912I-1059J-756D01*
G03X149387Y1155610I0J-1302D01*
G03X149932Y1154551I1301J0D01*
G01X149933Y1154550D01*
G02X150013Y1154422I-117J-162D01*
G02X150014Y1154418I-193J-50D01*
G01X150028Y1154253D01*
Y1154251D01*
X150040Y1154100D01*
G02X149982Y1153942I-199J-16D01*
G01X148616Y1152576D01*
G02X148458Y1152518I-142J141D01*
G01X148154Y1152543D01*
G02X148137Y1152545I15J199D01*
G02X148070Y1152569I33J197D01*
G01X148063Y1152573D01*
G02X148019Y1152610I106J170D01*
G01X148008Y1152626D01*
G03X146948Y1153172I-1060J-756D01*
G03X145646Y1151870I0J-1302D01*
G03X146180Y1150819I1301J0D01*
G02X146203Y1150799I-119J-161D01*
G01X146238Y1150764D01*
G02X146249Y1150747I-162J-117D01*
G01X146260Y1150728D01*
X146273Y1150687D01*
X146300Y1150360D01*
G02X146242Y1150202I-199J-16D01*
G01X144876Y1148836D01*
G02X144718Y1148778I-142J141D01*
G01X144413Y1148803D01*
G02X144331Y1148829I18J199D01*
G01X144293Y1148850D01*
X144267Y1148887D01*
G03X143208Y1149431I-1059J-759D01*
G03X141906Y1148129I0J-1302D01*
G03X142450Y1147070I1303J0D01*
G01X142487Y1147044D01*
X142508Y1147006D01*
G02X142534Y1146924I-173J-100D01*
G01X142559Y1146619D01*
G02X142501Y1146461I-199J-16D01*
G01X135271Y1139231D01*
G03X135212Y1139089I141J-142D01*
G01Y1131933D01*
G02X135122Y1131775I-200J9D01*
G01X135112Y1131770D01*
X134808Y1131593D01*
G02X134714Y1131570I-93J177D01*
G01X134615Y1131596D01*
X134593Y1131608D01*
G03X133871Y1131793I-723J-1319D01*
G01X133870D01*
G03Y1128789I0J-1502D01*
G01X133871D01*
G03X134593Y1128974I-1J1504D01*
G01X134615Y1128986D01*
X134714Y1129012D01*
G02X134808Y1128989I1J-200D01*
G01X135093Y1128823D01*
X135113Y1128811D01*
G02X135120Y1128807I-96J-175D01*
G01X135121D01*
X135124Y1128805D01*
G02X135212Y1128647I-112J-166D01*
G01Y1119333D01*
G02X135122Y1119175I-200J9D01*
G01X135112Y1119170D01*
X134808Y1118993D01*
G02X134714Y1118970I-93J177D01*
G01X134615Y1118996D01*
X134593Y1119008D01*
G03X133871Y1119193I-723J-1319D01*
G01X133870D01*
G03Y1116189I0J-1502D01*
G01X133871D01*
G03X134593Y1116374I-1J1504D01*
G01X134615Y1116386D01*
X134714Y1116412D01*
G02X134808Y1116389I1J-200D01*
G01X135093Y1116223D01*
X135113Y1116211D01*
G02X135120Y1116207I-96J-175D01*
G01X135121D01*
X135124Y1116205D01*
G02X135212Y1116047I-112J-166D01*
G01Y1106733D01*
G02X135122Y1106575I-200J9D01*
G01X135112Y1106570D01*
X134808Y1106393D01*
G02X134714Y1106370I-93J177D01*
G01X134615Y1106396D01*
X134593Y1106408D01*
G03X133871Y1106593I-723J-1319D01*
G01X133870D01*
G03Y1103589I0J-1502D01*
G01X133871D01*
G03X134593Y1103774I-1J1504D01*
G01X134615Y1103786D01*
X134714Y1103812D01*
G02X134808Y1103789I1J-200D01*
G01X135093Y1103623D01*
X135113Y1103611D01*
G02X135120Y1103607I-96J-175D01*
G01X135121D01*
X135124Y1103605D01*
G02X135212Y1103447I-112J-166D01*
G01Y1102537D01*
G02X135168Y1102412I-200J0D01*
G03X135166Y1102410I140J-142D01*
G02X135154Y1102396I-158J123D01*
G01X134157Y1101399D01*
G02X134090Y1101355I-141J142D01*
G01X134056Y1101341D01*
X126781D01*
G02X126774Y1101342I25J198D01*
G02X126641Y1101413I21J199D01*
G01X126572Y1101496D01*
X126444Y1101651D01*
G02X126404Y1101728I153J128D01*
G01X126393Y1101770D01*
X126401Y1101815D01*
G03X126427Y1102091I-1476J278D01*
G03X123423I-1502J0D01*
G01Y1102088D01*
G03X123503Y1101605I1502J1D01*
G01X123514Y1101574D01*
Y1101541D01*
G02X123314Y1101341I-200J0D01*
G01X123172D01*
G02X122972Y1101541I0J200D01*
G01Y1141447D01*
G02X123080Y1141625I200J0D01*
G01X123397Y1141788D01*
G02X123603Y1141774I91J-178D01*
G01X123604Y1141773D01*
G03X123812Y1141649I871J1224D01*
G01X123813D01*
G02X123922Y1141498I-89J-179D01*
G01X123970Y1141171D01*
G02X123908Y1140995I-198J-29D01*
G01X123907D01*
G03X123423Y1139891I1017J-1104D01*
G03X126427I1502J0D01*
G03X125587Y1141239I-1502J0D01*
G01X125586D01*
G02X125477Y1141390I89J179D01*
G01X125429Y1141717D01*
G02X125491Y1141893I198J29D01*
G01X125492D01*
G03X125976Y1142997I-1017J1104D01*
G03X124474Y1144499I-1502J0D01*
G03X123605Y1144221I1J-1502D01*
G01X123603D01*
Y1144220D01*
G02X123397Y1144206I-115J164D01*
G01X123080Y1144369D01*
G02X122972Y1144547I92J178D01*
G01Y1150701D01*
G02X122976Y1150738I200J-3D01*
G01Y1150740D01*
G02X123029Y1150841I196J-39D01*
G01X123542Y1151354D01*
G02X123545Y1151357I143J-140D01*
G01X123550Y1151361D01*
G02X123681Y1151412I133J-149D01*
G01X123766D01*
G02X123836Y1151399I-1J-200D01*
G01X123932Y1151363D01*
X123958Y1151341D01*
G03X124924Y1150989I966J1151D01*
G01X124925D01*
G03X126427Y1152491I0J1502D01*
G03X126027Y1153512I-1503J0D01*
G01X126002Y1153539D01*
X125947Y1153675D01*
G02Y1153678I200J1D01*
G01Y1153717D01*
X125962Y1153752D01*
G02X126005Y1153817I185J-76D01*
G01X141783Y1169595D01*
G02X141811Y1169618I141J-143D01*
G02X141911Y1169651I111J-167D01*
G01X142196Y1169658D01*
G02X142269Y1169645I2J-200D01*
G01X142302Y1169632D01*
X142331Y1169606D01*
G03X143206Y1169268I875J964D01*
G01X146947D01*
G03Y1171872I0J1302D01*
G01X144543D01*
G02X144359Y1171995I1J200D01*
G02X144402Y1172214I184J78D01*
G01X145523Y1173335D01*
G02X145551Y1173358I141J-143D01*
G02X145651Y1173391I111J-167D01*
G01X145921Y1173398D01*
X145933D01*
G02X146009Y1173385I5J-200D01*
G01X146043Y1173372D01*
X146072Y1173346D01*
G03X146947Y1173008I875J964D01*
G03X148249Y1174310I0J1302D01*
G03X147911Y1175185I-1302J0D01*
G01X147885Y1175214D01*
X147872Y1175248D01*
G02X147859Y1175318I187J71D01*
G01X147861Y1175387D01*
X147867Y1175612D01*
G02X147898Y1175704I199J-16D01*
G01X147910Y1175720D01*
G02X147924Y1175736I157J-123D01*
G37*
G36*
G01X185449Y1157310D02*
X187870D01*
G02X188012Y1157251I0J-200D01*
G01X188971Y1156292D01*
X188959Y1156272D01*
X188986Y1156245D01*
X188987Y1156244D01*
G02X189044Y1156104I-143J-140D01*
G01Y1153484D01*
G02X188958Y1153320I-200J0D01*
G01X188756Y1153179D01*
X188753Y1153176D01*
X188738Y1153166D01*
G03X188701Y1153139I704J-1003D01*
G01X188682Y1153124D01*
X188651Y1153110D01*
G02X188508Y1153102I-82J183D01*
G01X188506Y1153103D01*
G03X188092Y1153172I-418J-1232D01*
G01X188090D01*
G03Y1150568I0J-1302D01*
G01X188092D01*
G03X188505Y1150637I-5J1301D01*
G01X188507D01*
X188508Y1150638D01*
G02X188651Y1150630I61J-191D01*
G01X188682Y1150616D01*
X188701Y1150601D01*
G03X188754Y1150563I740J976D01*
G01X188920Y1150451D01*
X188918Y1150448D01*
X188958Y1150420D01*
G02X188961Y1150418I-109J-167D01*
G02X189044Y1150256I-117J-162D01*
G01Y1149743D01*
G02X188958Y1149579I-200J0D01*
G01X188756Y1149438D01*
X188753Y1149435D01*
X188738Y1149425D01*
G03X188701Y1149398I704J-1003D01*
G01X188682Y1149383D01*
X188651Y1149369D01*
G02X188508Y1149361I-82J183D01*
G01X188506Y1149362D01*
G03X188092Y1149431I-418J-1232D01*
G01X188090D01*
G03Y1146827I0J-1302D01*
G01X188092D01*
G03X188505Y1146896I-5J1301D01*
G01X188507D01*
X188508Y1146897D01*
G02X188651Y1146889I61J-191D01*
G01X188682Y1146875D01*
X188701Y1146860D01*
G03X188754Y1146822I740J976D01*
G01X188920Y1146710D01*
X188918Y1146707D01*
X188958Y1146679D01*
G02X188961Y1146677I-109J-167D01*
G02X189044Y1146515I-117J-162D01*
G01Y1146003D01*
G02X188958Y1145839I-200J0D01*
G01X188756Y1145698D01*
X188753Y1145695D01*
X188738Y1145685D01*
G03X188701Y1145658I704J-1003D01*
G01X188682Y1145643D01*
X188651Y1145629D01*
G02X188508Y1145621I-82J183D01*
G01X188506Y1145622D01*
G03X188092Y1145691I-418J-1232D01*
G01X188090D01*
G03Y1143087I0J-1302D01*
G01X188092D01*
G03X188505Y1143156I-5J1301D01*
G01X188507D01*
X188508Y1143157D01*
G02X188651Y1143149I61J-191D01*
G01X188682Y1143135D01*
X188701Y1143120D01*
G03X188754Y1143082I740J976D01*
G01X188920Y1142970D01*
X188918Y1142967D01*
X188958Y1142939D01*
G02X188961Y1142937I-109J-167D01*
G02X189044Y1142775I-117J-162D01*
G01Y1142437D01*
G02X188985Y1142295I-200J0D01*
G01X188603Y1141913D01*
X188498Y1141886D01*
X188446Y1141901D01*
G03X188091Y1141951I-357J-1252D01*
G01X188090D01*
G03X186788Y1140649I0J-1302D01*
G01Y1140648D01*
G03X186844Y1140273I1302J3D01*
G01Y1140272D01*
X186845Y1140270D01*
G02X186846Y1140163I-193J-55D01*
G01X186838Y1140135D01*
X186812Y1140090D01*
X186793Y1140071D01*
X184928Y1138206D01*
X184909Y1138187D01*
X184864Y1138161D01*
X184836Y1138153D01*
G02X184729Y1138154I-52J194D01*
G01X184727Y1138155D01*
X184726D01*
G03X184351Y1138211I-378J-1246D01*
G01X184350D01*
G03X183048Y1136909I0J-1302D01*
G01Y1136908D01*
G03X183104Y1136533I1302J3D01*
G01Y1136532D01*
X183105Y1136530D01*
G02X183106Y1136423I-193J-55D01*
G01X183098Y1136395D01*
X183072Y1136350D01*
X183053Y1136331D01*
X181188Y1134466D01*
X181169Y1134447D01*
X181124Y1134421D01*
X181096Y1134413D01*
G02X180989Y1134414I-52J194D01*
G01X180987Y1134415D01*
X180986D01*
G03X180611Y1134471I-378J-1246D01*
G01X180610D01*
G03X179308Y1133169I0J-1302D01*
G01Y1133168D01*
G03X179364Y1132793I1302J3D01*
G01Y1132792D01*
X179365Y1132790D01*
G02X179366Y1132683I-193J-55D01*
G01X179358Y1132655D01*
X179332Y1132610D01*
X179313Y1132591D01*
X177448Y1130726D01*
X177429Y1130707D01*
X177384Y1130681D01*
X177356Y1130673D01*
G02X177249Y1130674I-52J194D01*
G01X177247Y1130675D01*
X177246D01*
G03X176871Y1130731I-378J-1246D01*
G01X176870D01*
G03X175568Y1129429I0J-1302D01*
G01Y1129428D01*
G03X175624Y1129053I1302J3D01*
G01Y1129052D01*
X175625Y1129050D01*
G02X175626Y1128943I-193J-55D01*
G01X175618Y1128915D01*
X175592Y1128870D01*
X175573Y1128851D01*
X169967Y1123245D01*
X169948Y1123226D01*
X169903Y1123200D01*
X169875Y1123192D01*
G02X169768Y1123193I-52J194D01*
G01X169766Y1123194D01*
X169765D01*
G03X169390Y1123250I-378J-1246D01*
G01X169389D01*
G03X168087Y1121948I0J-1302D01*
G01Y1121947D01*
G03X168143Y1121572I1302J3D01*
G01Y1121571D01*
X168144Y1121569D01*
G02X168145Y1121462I-193J-55D01*
G01X168137Y1121434D01*
X168111Y1121389D01*
X168092Y1121370D01*
X166227Y1119505D01*
X166208Y1119486D01*
X166163Y1119460D01*
X166135Y1119452D01*
G02X166028Y1119453I-52J194D01*
G01X166026Y1119454D01*
X166025D01*
G03X165650Y1119510I-378J-1246D01*
G01X165649D01*
G03X164347Y1118208I0J-1302D01*
G03X164834Y1117193I1301J0D01*
G01X164835Y1117192D01*
X164852Y1117178D01*
X164879Y1117145D01*
X164927Y1117048D01*
Y1117047D01*
G02X164948Y1116959I-179J-89D01*
G01Y1115717D01*
G02X164927Y1115628I-200J0D01*
G01X164878Y1115530D01*
X164851Y1115497D01*
X164834Y1115483D01*
G03Y1113453I815J-1015D01*
G01X164851Y1113439D01*
X164878Y1113406D01*
X164927Y1113308D01*
G02X164948Y1113219I-179J-89D01*
G01Y1111977D01*
G02X164927Y1111888I-200J0D01*
G01X164878Y1111790D01*
X164851Y1111757D01*
X164834Y1111743D01*
G03Y1109713I815J-1015D01*
G01X164851Y1109699D01*
X164878Y1109666D01*
X164927Y1109568D01*
G02X164948Y1109479I-179J-89D01*
G01Y1108237D01*
G02X164927Y1108148I-200J0D01*
G01X164878Y1108050D01*
X164851Y1108017D01*
X164834Y1108003D01*
G03Y1105973I815J-1015D01*
G01X164851Y1105959D01*
X164878Y1105926D01*
X164927Y1105828D01*
G02X164948Y1105739I-179J-89D01*
G01Y1104496D01*
G02X164927Y1104407I-200J0D01*
G01X164878Y1104309D01*
X164851Y1104276D01*
X164834Y1104262D01*
G03Y1102232I815J-1015D01*
G01X164851Y1102218D01*
X164878Y1102185D01*
X164927Y1102087D01*
G02X164948Y1101998I-179J-89D01*
G01Y1100756D01*
G02X164927Y1100667I-200J0D01*
G01X164878Y1100569D01*
X164851Y1100536D01*
X164834Y1100522D01*
G03Y1098492I815J-1015D01*
G01X164851Y1098478D01*
X164878Y1098445D01*
X164927Y1098347D01*
G02X164948Y1098258I-179J-89D01*
G01Y1097016D01*
G02X164927Y1096927I-200J0D01*
G01X164878Y1096829D01*
X164851Y1096796D01*
X164834Y1096782D01*
G03Y1094752I815J-1015D01*
G01X164851Y1094738D01*
X164878Y1094705D01*
X164927Y1094607D01*
G02X164948Y1094518I-179J-89D01*
G01Y1093276D01*
G02X164927Y1093187I-200J0D01*
G01X164878Y1093089D01*
X164851Y1093056D01*
X164834Y1093042D01*
G03Y1091012I815J-1015D01*
G01X164851Y1090998D01*
X164878Y1090965D01*
X164927Y1090867D01*
G02X164948Y1090778I-179J-89D01*
G01Y1089536D01*
G02X164927Y1089447I-200J0D01*
G01X164878Y1089349D01*
X164851Y1089316D01*
X164834Y1089302D01*
G03Y1087272I815J-1015D01*
G01X164851Y1087258D01*
X164878Y1087225D01*
X164927Y1087127D01*
G02X164948Y1087038I-179J-89D01*
G01Y1085796D01*
G02X164927Y1085707I-200J0D01*
G01X164878Y1085609D01*
X164851Y1085576D01*
X164834Y1085562D01*
G03Y1083532I815J-1015D01*
G01X164851Y1083518D01*
X164878Y1083485D01*
X164927Y1083387D01*
G02X164948Y1083298I-179J-89D01*
G01Y1082056D01*
G02X164927Y1081967I-200J0D01*
G01X164878Y1081869D01*
X164851Y1081836D01*
X164834Y1081822D01*
G03Y1079792I815J-1015D01*
G01X164851Y1079778D01*
X164878Y1079745D01*
X164927Y1079647D01*
G02X164948Y1079558I-179J-89D01*
G01Y1078315D01*
G02X164927Y1078226I-200J0D01*
G01X164878Y1078128D01*
X164851Y1078095D01*
X164834Y1078081D01*
G03Y1076051I815J-1015D01*
G01X164851Y1076037D01*
X164878Y1076004D01*
X164927Y1075906D01*
G02X164948Y1075817I-179J-89D01*
G01Y1074575D01*
G02X164927Y1074486I-200J0D01*
G01X164878Y1074388D01*
X164851Y1074355D01*
X164834Y1074341D01*
G03Y1072311I815J-1015D01*
G01X164851Y1072297D01*
X164878Y1072264D01*
X164927Y1072166D01*
G02X164948Y1072077I-179J-89D01*
G01Y1067458D01*
G02X164917Y1067352I-200J1D01*
G03X164705Y1066788I1271J-800D01*
G01X164696Y1066736D01*
X164633Y1066655D01*
X164220Y1066484D01*
X164117Y1066496D01*
X164075Y1066528D01*
G03X163191Y1066815I-883J-1215D01*
G03Y1063811I0J-1502D01*
G03X164263Y1064261I0J1502D01*
G01X164306Y1064304D01*
X164424Y1064329D01*
X164824Y1064165D01*
G02X164948Y1063980I-76J-185D01*
G01Y1044613D01*
G02X164947Y1044596I-200J3D01*
G01X164833Y1043291D01*
G02X164811Y1043215I-199J17D01*
G02X164752Y1043147I-177J94D01*
G01X164475Y1042944D01*
X164391Y1042926D01*
X164349Y1042935D01*
G03X164028Y1042970I-322J-1467D01*
G03Y1039966I0J-1502D01*
G03X164087Y1039967I4J1502D01*
G01X164131Y1039969D01*
X164210Y1039937D01*
X164447Y1039688D01*
G02X164502Y1039538I-145J-138D01*
G01Y1039532D01*
X162635Y1018338D01*
G02X162577Y1018214I-199J18D01*
G01X154410Y1010047D01*
X154382Y1010018D01*
X154308Y1009988D01*
X138109D01*
G02X138008Y1010015I-1J200D01*
G01X137904Y1010077D01*
X137869Y1010111D01*
X137856Y1010132D01*
G03X136571Y1010856I-1285J-778D01*
G03X135613Y1010511I0J-1503D01*
G01X135553Y1010461D01*
X135399Y1010469D01*
X133825Y1012043D01*
X133796Y1012071D01*
X133766Y1012145D01*
Y1018472D01*
G02X133825Y1018614I200J0D01*
G01X135377Y1020166D01*
X135405Y1020194D01*
X135478Y1020225D01*
X146033D01*
G03X146175Y1020284I0J200D01*
G01X151397Y1025506D01*
G03X151456Y1025648I-141J142D01*
G01Y1025745D01*
G02X151464Y1025800I200J-1D01*
G01X151471Y1025825D01*
X151485Y1025849D01*
X151486Y1025850D01*
G03X151514Y1025952I-172J102D01*
G01Y1038650D01*
X151573Y1038746D01*
X151624Y1038771D01*
G03X152455Y1040115I-671J1344D01*
G03X151952Y1041236I-1503J-1D01*
G01X151948Y1041240D01*
X151940Y1041248D01*
G03X151935Y1041253I-1064J-1059D01*
G01X151930Y1041258D01*
X151929Y1041259D01*
G03X151608Y1041511I-1079J-1045D01*
G02X151510Y1041699I101J172D01*
G03X151514Y1041807I-1255J101D01*
G01Y1058593D01*
G02X151605Y1058761I200J0D01*
G01X151873Y1058936D01*
X151973Y1058944D01*
X152020Y1058923D01*
G03X152629Y1058794I609J1373D01*
G03Y1061798I0J1502D01*
G03X152020Y1061669I0J-1502D01*
G01X151973Y1061648D01*
X151873Y1061656D01*
X151821Y1061690D01*
X151605Y1061831D01*
G02X151514Y1061999I109J168D01*
G01Y1071889D01*
G03X151487Y1072146I-1258J-2D01*
G01X151480Y1072179D01*
X151487Y1072241D01*
X151527Y1072328D01*
X151558Y1072356D01*
G03Y1074296I-869J970D01*
G01X151527Y1074324D01*
X151487Y1074411D01*
X151480Y1074473D01*
X151487Y1074506D01*
G03X151514Y1074763I-1231J259D01*
G01Y1075631D01*
G03X151490Y1075872I-1258J-4D01*
G01X151484Y1075903D01*
X151491Y1075964D01*
X151547Y1076089D01*
X151577Y1076116D01*
G03X151990Y1077066I-889J951D01*
G03X151577Y1078016I-1302J-1D01*
G01X151547Y1078043D01*
X151491Y1078168D01*
X151484Y1078229D01*
X151490Y1078260D01*
G03X151514Y1078501I-1234J245D01*
G01Y1079370D01*
G03X151487Y1079627I-1258J-2D01*
G01X151480Y1079660D01*
X151487Y1079722D01*
X151527Y1079809D01*
X151558Y1079837D01*
G03Y1081777I-869J970D01*
G01X151527Y1081805D01*
X151487Y1081892D01*
X151480Y1081954D01*
X151487Y1081987D01*
G03X151514Y1082244I-1231J259D01*
G01Y1083110D01*
G03X151487Y1083367I-1258J-2D01*
G01X151480Y1083400D01*
X151487Y1083462D01*
X151527Y1083549D01*
X151558Y1083577D01*
G03Y1085517I-869J970D01*
G01X151527Y1085545D01*
X151487Y1085632D01*
X151480Y1085694D01*
X151487Y1085727D01*
G03X151514Y1085984I-1231J259D01*
G01Y1086850D01*
G03X151487Y1087107I-1258J-2D01*
G01X151480Y1087140D01*
X151487Y1087202D01*
X151527Y1087289D01*
X151558Y1087317D01*
G03Y1089257I-869J970D01*
G01X151527Y1089285D01*
X151487Y1089372D01*
X151480Y1089434D01*
X151487Y1089467D01*
G03X151514Y1089724I-1231J259D01*
G01Y1090590D01*
G03X151487Y1090847I-1258J-2D01*
G01X151480Y1090880D01*
X151487Y1090942D01*
X151527Y1091029D01*
X151558Y1091057D01*
G03Y1092997I-869J970D01*
G01X151527Y1093025D01*
X151487Y1093112D01*
X151480Y1093174D01*
X151487Y1093207D01*
G03X151514Y1093464I-1231J259D01*
G01Y1094330D01*
G03X151487Y1094587I-1258J-2D01*
G01X151480Y1094620D01*
X151487Y1094682D01*
X151527Y1094769D01*
X151558Y1094797D01*
G03Y1096737I-869J970D01*
G01X151527Y1096765D01*
X151487Y1096852D01*
X151480Y1096914D01*
X151487Y1096947D01*
G03X151514Y1097204I-1231J259D01*
G01Y1098070D01*
G03X151487Y1098327I-1258J-2D01*
G01X151480Y1098360D01*
X151487Y1098422D01*
X151527Y1098509D01*
X151558Y1098537D01*
G03Y1100477I-869J970D01*
G01X151527Y1100505D01*
X151487Y1100592D01*
X151480Y1100654D01*
X151487Y1100687D01*
G03X151514Y1100944I-1231J259D01*
G01Y1101810D01*
G03X151487Y1102067I-1258J-2D01*
G01X151480Y1102100D01*
X151487Y1102162D01*
X151527Y1102249D01*
X151558Y1102277D01*
G03Y1104217I-869J970D01*
G01X151527Y1104245D01*
X151487Y1104332D01*
X151480Y1104394D01*
X151487Y1104427D01*
G03X151514Y1104684I-1231J259D01*
G01Y1105551D01*
G03X151487Y1105808I-1258J-2D01*
G01X151480Y1105841D01*
X151487Y1105903D01*
X151527Y1105990D01*
X151558Y1106018D01*
G03Y1107958I-869J970D01*
G01X151527Y1107986D01*
X151487Y1108073D01*
X151480Y1108135D01*
X151487Y1108168D01*
G03X151514Y1108425I-1231J259D01*
G01Y1109291D01*
G03X151487Y1109548I-1258J-2D01*
G01X151480Y1109581D01*
X151487Y1109643D01*
X151527Y1109730D01*
X151558Y1109758D01*
G03Y1111698I-869J970D01*
G01X151527Y1111726D01*
X151487Y1111813D01*
X151480Y1111875D01*
X151487Y1111908D01*
G03X151514Y1112165I-1231J259D01*
G01Y1113031D01*
G03X151487Y1113288I-1258J-2D01*
G01X151480Y1113321D01*
X151487Y1113383D01*
X151527Y1113470D01*
X151558Y1113498D01*
G03Y1115438I-869J970D01*
G01X151527Y1115466D01*
X151487Y1115553D01*
X151480Y1115615D01*
X151487Y1115648D01*
G03X151514Y1115905I-1231J259D01*
G01Y1116771D01*
G03X151487Y1117028I-1258J-2D01*
G01X151480Y1117061D01*
X151487Y1117123D01*
X151527Y1117210D01*
X151558Y1117238D01*
G03Y1119178I-869J970D01*
G01X151527Y1119206D01*
X151487Y1119293D01*
X151480Y1119355D01*
X151487Y1119388D01*
G03X151514Y1119645I-1231J259D01*
G01Y1120511D01*
G03X151487Y1120768I-1258J-2D01*
G01X151480Y1120801D01*
X151487Y1120863D01*
X151527Y1120950D01*
X151558Y1120978D01*
G03Y1122918I-869J970D01*
G01X151527Y1122946D01*
X151487Y1123033D01*
X151480Y1123095D01*
X151487Y1123128D01*
G03X151514Y1123385I-1231J259D01*
G01Y1124251D01*
G03X151487Y1124508I-1258J-2D01*
G01X151480Y1124541D01*
X151487Y1124603D01*
X151527Y1124690D01*
X151558Y1124718D01*
G03Y1126658I-869J970D01*
G01X151527Y1126686D01*
X151487Y1126773D01*
X151480Y1126835D01*
X151487Y1126868D01*
G03X151514Y1127125I-1231J259D01*
G01Y1127992D01*
G03X151487Y1128249I-1258J-2D01*
G01X151480Y1128282D01*
X151487Y1128344D01*
X151527Y1128431D01*
X151558Y1128459D01*
G03X151991Y1129429I-870J970D01*
G03X151895Y1129919I-1302J-1D01*
G01X151879Y1129959D01*
G02X151869Y1130080I185J76D01*
G01X151870Y1130083D01*
G02X151923Y1130179I195J-45D01*
G01X153550Y1131805D01*
G02X153692Y1131864I142J-141D01*
G01X154429D01*
G03X155732Y1133167I0J1303D01*
G03X155620Y1133695I-1303J0D01*
G01X155595Y1133752D01*
X155617Y1133873D01*
X157419Y1135675D01*
G02X157512Y1135727I140J-142D01*
G01X157548Y1135737D01*
X157614Y1135731D01*
X157645Y1135717D01*
G03X158167Y1135607I524J1192D01*
G01X158169D01*
G03X159471Y1136909I0J1302D01*
G03X159375Y1137399I-1302J-1D01*
G01X159359Y1137439D01*
G02X159349Y1137560I185J76D01*
G01X159350Y1137563D01*
G02X159403Y1137659I195J-45D01*
G01X161159Y1139415D01*
G02X161252Y1139467I140J-142D01*
G01X161288Y1139477D01*
X161354Y1139471D01*
X161385Y1139457D01*
G03X161907Y1139347I524J1192D01*
G01X161909D01*
G03X163211Y1140649I0J1302D01*
G03X163115Y1141139I-1302J-1D01*
G01X163099Y1141179D01*
G02X163089Y1141300I185J76D01*
G01X163090Y1141303D01*
G02X163143Y1141399I195J-45D01*
G01X164899Y1143155D01*
G02X164992Y1143207I140J-142D01*
G01X165028Y1143217D01*
X165094Y1143211D01*
X165125Y1143197D01*
G03X165647Y1143087I524J1192D01*
G01X165649D01*
G03X166951Y1144389I0J1302D01*
G03X166855Y1144879I-1302J-1D01*
G01X166839Y1144919D01*
G02X166829Y1145040I185J76D01*
G01X166830Y1145043D01*
G02X166883Y1145139I195J-45D01*
G01X168639Y1146895D01*
G02X168732Y1146947I140J-142D01*
G01X168768Y1146957D01*
X168834Y1146951D01*
X168865Y1146937D01*
G03X169387Y1146827I524J1192D01*
G01X169389D01*
G03X170691Y1148129I0J1302D01*
G03X170595Y1148619I-1302J-1D01*
G01X170579Y1148659D01*
G02X170569Y1148780I185J76D01*
G01X170570Y1148783D01*
G02X170623Y1148879I195J-45D01*
G01X172364Y1150620D01*
G02X172506Y1150679I142J-141D01*
G01X172602D01*
X172638Y1150664D01*
G03X173129Y1150568I491J1206D01*
G03X174431Y1151870I0J1302D01*
G03X174320Y1152395I-1302J-1D01*
G01X174295Y1152452D01*
X174318Y1152574D01*
X178548Y1156804D01*
G03X178607Y1156946I-141J142D01*
G01Y1157063D01*
G02X178666Y1157205I200J0D01*
G01X178712Y1157251D01*
G02X178714Y1157253I142J-140D01*
G02X178854Y1157310I140J-143D01*
G01X179511D01*
G02X179699Y1157178I0J-200D01*
G01X179812Y1156869D01*
X179849Y1156766D01*
X179817Y1156645D01*
X179769Y1156605D01*
G03X179308Y1155611I842J-994D01*
G01Y1155610D01*
G03X181912I1302J0D01*
G01Y1155611D01*
G03X181472Y1156587I-1303J0D01*
G01X181450Y1156606D01*
X181415Y1156661D01*
G02X181396Y1156836I169J107D01*
G01X181408Y1156869D01*
X181521Y1157178D01*
G02X181709Y1157310I188J-68D01*
G01X183251D01*
G02X183439Y1157178I0J-200D01*
G01X183552Y1156869D01*
X183589Y1156766D01*
X183557Y1156645D01*
X183509Y1156605D01*
G03X183048Y1155611I842J-994D01*
G01Y1155610D01*
G03X185652I1302J0D01*
G01Y1155611D01*
G03X185212Y1156587I-1303J0D01*
G01X185190Y1156606D01*
X185155Y1156661D01*
G02X185136Y1156836I169J107D01*
G01X185148Y1156869D01*
X185261Y1157178D01*
G02X185449Y1157310I188J-68D01*
G37*
G36*
G01X133814Y1034540D02*
G03X133772Y1034893I-1502J0D01*
G01X133766Y1034917D01*
Y1042062D01*
G02X133825Y1042204I200J0D01*
G01X136377Y1044756D01*
G03X136436Y1044898I-141J142D01*
G01Y1076332D01*
G03X136377Y1076474I-200J0D01*
G01X136272Y1076579D01*
X136243Y1076607D01*
X136213Y1076681D01*
Y1102039D01*
X136214D01*
Y1138200D01*
G02X136273Y1138342I200J0D01*
G01X141571Y1143640D01*
G02X141581Y1143649I139J-144D01*
G02X141690Y1143697I131J-151D01*
G02X141726Y1143698I24J-199D01*
G01X141814Y1143692D01*
X142027Y1143678D01*
G02X142172Y1143600I-14J-200D01*
G03X143208Y1143087I1036J790D01*
G03X144510Y1144389I0J1302D01*
G03X143997Y1145425I-1303J0D01*
G02X143919Y1145570I122J159D01*
G01X143905Y1145783D01*
X143899Y1145871D01*
G02X143900Y1145907I200J12D01*
G02X143948Y1146016I199J-22D01*
G02X143957Y1146026I153J-129D01*
G01X145311Y1147380D01*
G02X145321Y1147389I139J-144D01*
G02X145430Y1147437I131J-151D01*
G02X145466Y1147438I24J-199D01*
G01X145554Y1147432D01*
X145767Y1147418D01*
G02X145912Y1147340I-14J-200D01*
G03X146948Y1146827I1036J790D01*
G03X148250Y1148129I0J1302D01*
G03X147737Y1149165I-1303J0D01*
G02X147659Y1149310I122J159D01*
G01X147645Y1149523D01*
X147639Y1149611D01*
G02X147640Y1149647I200J12D01*
G02X147688Y1149756I199J-22D01*
G02X147697Y1149766I153J-129D01*
G01X149052Y1151121D01*
G02X149062Y1151130I139J-144D01*
G02X149171Y1151178I131J-151D01*
G02X149207Y1151179I24J-199D01*
G01X149295Y1151173D01*
X149508Y1151159D01*
G02X149653Y1151081I-14J-200D01*
G03X150689Y1150568I1036J790D01*
G03X151991Y1151870I0J1302D01*
G03X151478Y1152906I-1303J0D01*
G02X151400Y1153051I122J159D01*
G01X151386Y1153264D01*
X151380Y1153352D01*
G02X151381Y1153388I200J12D01*
G02X151429Y1153497I199J-22D01*
G02X151438Y1153507I153J-129D01*
G01X152792Y1154861D01*
G02X152802Y1154870I139J-144D01*
G02X152911Y1154918I131J-151D01*
G02X152947Y1154919I24J-199D01*
G01X153035Y1154913D01*
X153248Y1154899D01*
G02X153393Y1154821I-14J-200D01*
G03X154429Y1154308I1036J790D01*
G03X155731Y1155610I0J1302D01*
G03X155218Y1156646I-1303J0D01*
G02X155140Y1156791I122J159D01*
G01X155126Y1157004D01*
X155120Y1157092D01*
G02X155121Y1157128I200J12D01*
G02X155169Y1157237I199J-22D01*
G02X155178Y1157247I153J-129D01*
G01X164012Y1166081D01*
G02X164022Y1166090I139J-144D01*
G02X164131Y1166138I131J-151D01*
G02X164167Y1166139I24J-199D01*
G01X164255Y1166133D01*
X164468Y1166119D01*
G02X164613Y1166041I-14J-200D01*
G03X165649Y1165528I1036J790D01*
G03X166951Y1166830I0J1302D01*
G03X166924Y1167091I-1302J-3D01*
G01Y1167093D01*
G02X166965Y1167258I196J39D01*
G01X167161Y1167500D01*
G02X167316Y1167574I155J-126D01*
G01X171462D01*
G02X171617Y1167500I0J-200D01*
G01X171813Y1167258D01*
G02X171854Y1167093I-155J-126D01*
G01Y1167091D01*
G03X171827Y1166830I1275J-264D01*
G03X174431I1302J0D01*
G03X174404Y1167091I-1302J-3D01*
G01Y1167093D01*
G02X174445Y1167258I196J39D01*
G01X174641Y1167500D01*
G02X174796Y1167574I155J-126D01*
G01X175203D01*
G02X175358Y1167500I0J-200D01*
G01X175554Y1167258D01*
G02X175595Y1167093I-155J-126D01*
G01Y1167091D01*
G03X175568Y1166830I1275J-264D01*
G03X178172I1302J0D01*
G03X178141Y1167115I-1302J3D01*
G01Y1167116D01*
G02X178180Y1167284I195J43D01*
G01X178375Y1167527D01*
G02X178531Y1167602I156J-125D01*
G01X178995D01*
X179076Y1167563D01*
X179105Y1167527D01*
X179300Y1167284D01*
G02X179339Y1167116I-156J-125D01*
G01Y1167115D01*
G03X179308Y1166830I1271J-282D01*
G03X181912I1302J0D01*
G03X181881Y1167115I-1302J3D01*
G01Y1167116D01*
G02X181920Y1167284I195J43D01*
G01X182115Y1167527D01*
G02X182271Y1167602I156J-125D01*
G01X182735D01*
X182816Y1167563D01*
X182845Y1167527D01*
X183040Y1167284D01*
G02X183079Y1167116I-156J-125D01*
G01Y1167115D01*
G03X183048Y1166830I1271J-282D01*
G03X185652I1302J0D01*
G03X185621Y1167115I-1302J3D01*
G01Y1167116D01*
G02X185660Y1167284I195J43D01*
G01X185855Y1167527D01*
G02X186011Y1167602I156J-125D01*
G01X188260D01*
G02X188402Y1167543I0J-200D01*
G01X188458Y1167487D01*
X188475Y1167467D01*
X188479Y1167462D01*
G03X188588Y1167338I965J739D01*
G01X189260Y1166666D01*
X189264Y1166661D01*
G03X189274Y1166651I146J136D01*
G02X189281Y1166644I-138J-145D01*
G03X189287Y1166637I926J788D01*
G01X189293Y1166631D01*
X189305Y1166615D01*
G02X189345Y1166495I-160J-120D01*
G01Y1165834D01*
X189343Y1165819D01*
Y1165818D01*
G03X189335Y1165754I1202J-183D01*
G03X189330Y1165661I1210J-112D01*
G01Y1161069D01*
G02X189271Y1160927I-200J0D01*
G01X188899Y1160555D01*
G02X188789Y1160499I-141J141D01*
G02X188673Y1160514I-33J197D01*
G01X188639Y1160530D01*
G03X188090Y1160652I-550J-1178D01*
G03X187291Y1160378I0J-1302D01*
G01X187266Y1160359D01*
X187171Y1160325D01*
G02X187105Y1160314I-65J189D01*
G01X185335D01*
G02X185269Y1160325I-1J200D01*
G01X185174Y1160359D01*
X185149Y1160378D01*
G03X183551I-799J-1028D01*
G01X183526Y1160359D01*
X183431Y1160325D01*
G02X183365Y1160314I-65J189D01*
G01X181595D01*
G02X181529Y1160325I-1J200D01*
G01X181434Y1160359D01*
X181409Y1160378D01*
G03X180610Y1160652I-799J-1028D01*
G03X179310Y1159419I0J-1302D01*
G02X179292Y1159346I-200J11D01*
G01X179277Y1159313D01*
X178275Y1158312D01*
X178263D01*
X177944Y1157980D01*
X177942Y1157978D01*
X173193Y1153229D01*
G02X173137Y1153189I-143J140D01*
G01X173099Y1153172D01*
X173060Y1153170D01*
G03X171829Y1151938I69J-1300D01*
G01X171827Y1151900D01*
X171811Y1151865D01*
G02X171770Y1151806I-182J83D01*
G01X169452Y1149488D01*
G02X169396Y1149448I-143J140D01*
G01X169358Y1149431D01*
X169319Y1149429D01*
G03X168089Y1148198I70J-1300D01*
G02X168071Y1148125I-200J11D01*
G01X168056Y1148092D01*
X165712Y1145748D01*
G02X165656Y1145708I-143J140D01*
G01X165618Y1145691D01*
X165579Y1145689D01*
G03X164349Y1144458I70J-1300D01*
G02X164331Y1144385I-200J11D01*
G01X164316Y1144352D01*
X161972Y1142008D01*
G02X161916Y1141968I-143J140D01*
G01X161878Y1141951D01*
X161839Y1141949D01*
G03X160609Y1140718I70J-1300D01*
G02X160591Y1140645I-200J11D01*
G01X160576Y1140612D01*
X158232Y1138268D01*
G02X158176Y1138228I-143J140D01*
G01X158138Y1138211D01*
X158099Y1138209D01*
G03X156869Y1136978I70J-1300D01*
G02X156851Y1136905I-200J11D01*
G01X156836Y1136872D01*
X154493Y1134529D01*
G02X154351Y1134470I-142J141D01*
G01X150689D01*
G03Y1131864I0J-1303D01*
G01X151345D01*
G02X151530Y1131741I0J-200D01*
G01X151554Y1131684D01*
X151530Y1131566D01*
X150752Y1130788D01*
G02X150696Y1130748I-143J140D01*
G01X150658Y1130731D01*
X150619Y1130729D01*
G03X149387Y1129429I70J-1300D01*
G03X150314Y1128182I1302J0D01*
G01X150377Y1128163D01*
X150456Y1128057D01*
Y1127127D01*
G02X150314Y1126935I-200J-1D01*
G01X150313D01*
G03X150314Y1124441I376J-1247D01*
G01X150377Y1124422D01*
X150456Y1124316D01*
Y1123387D01*
G02X150314Y1123195I-200J-1D01*
G01X150313D01*
G03X150314Y1120701I376J-1247D01*
G01X150377Y1120682D01*
X150456Y1120576D01*
Y1119647D01*
G02X150314Y1119455I-200J-1D01*
G01X150313D01*
G03X150314Y1116961I376J-1247D01*
G01X150377Y1116942D01*
X150456Y1116836D01*
Y1115907D01*
G02X150314Y1115715I-200J-1D01*
G01X150313D01*
G03X150314Y1113221I376J-1247D01*
G01X150377Y1113202D01*
X150456Y1113096D01*
Y1112167D01*
G02X150314Y1111975I-200J-1D01*
G01X150313D01*
G03X150314Y1109481I376J-1247D01*
G01X150377Y1109462D01*
X150456Y1109356D01*
Y1108427D01*
G02X150314Y1108235I-200J-1D01*
G01X150313D01*
G03X150314Y1105741I376J-1247D01*
G01X150377Y1105722D01*
X150456Y1105616D01*
Y1104686D01*
G02X150314Y1104494I-200J-1D01*
G01X150313D01*
G03X150314Y1102000I376J-1247D01*
G01X150377Y1101981D01*
X150456Y1101875D01*
Y1100946D01*
G02X150314Y1100754I-200J-1D01*
G01X150313D01*
G03X150314Y1098260I376J-1247D01*
G01X150377Y1098241D01*
X150456Y1098135D01*
Y1097206D01*
G02X150314Y1097014I-200J-1D01*
G01X150313D01*
G03X150314Y1094520I376J-1247D01*
G01X150377Y1094501D01*
X150456Y1094395D01*
Y1093466D01*
G02X150314Y1093274I-200J-1D01*
G01X150313D01*
G03X150314Y1090780I376J-1247D01*
G01X150377Y1090761D01*
X150456Y1090655D01*
Y1089726D01*
G02X150314Y1089534I-200J-1D01*
G01X150313D01*
G03X150314Y1087040I376J-1247D01*
G01X150377Y1087021D01*
X150456Y1086915D01*
Y1085986D01*
G02X150314Y1085794I-200J-1D01*
G01X150313D01*
G03X150314Y1083300I376J-1247D01*
G01X150377Y1083281D01*
X150456Y1083175D01*
Y1082246D01*
G02X150314Y1082054I-200J-1D01*
G01X150313D01*
G03X150314Y1079560I376J-1247D01*
G01X150377Y1079541D01*
X150456Y1079435D01*
Y1078505D01*
G02X150314Y1078313I-200J-1D01*
G01X150313D01*
G03Y1075819I374J-1247D01*
G01X150377Y1075800D01*
X150456Y1075694D01*
Y1074765D01*
G02X150314Y1074573I-200J-1D01*
G01X150313D01*
G03X150314Y1072079I376J-1247D01*
G01X150377Y1072060D01*
X150456Y1071954D01*
Y1041746D01*
X150385Y1041644D01*
X150326Y1041622D01*
G03X149852Y1039092I525J-1408D01*
G02X149854Y1039090I-141J-143D01*
G03X150442Y1038702I1098J1025D01*
G01X150456Y1038682D01*
Y1026549D01*
X150454Y1026548D01*
Y1026387D01*
X150424Y1026313D01*
X150395Y1026285D01*
X147176Y1023065D01*
X147148Y1023036D01*
X147074Y1023006D01*
X137724D01*
G02X137588Y1023059I0J200D01*
G03X135554I-1017J-1104D01*
G02X135418Y1023006I-136J147D01*
G01X134739D01*
G02X134597Y1023065I0J200D01*
G01X133825Y1023837D01*
X133796Y1023865D01*
X133766Y1023939D01*
Y1034159D01*
X133772Y1034183D01*
G03X133814Y1034536I-1460J353D01*
G01Y1034540D01*
G37*
G36*
G01X240020Y54588D02*
X268877D01*
X269414Y54051D01*
Y53128D01*
X268877Y52591D01*
X240020D01*
G03X234083Y46654I0J-5937D01*
G01Y7874D01*
G02X228209Y2000I-5874J0D01*
G01X180965D01*
G02X175091Y7874I0J5874D01*
G01Y46167D01*
X177088D01*
Y7874D01*
G03X180963Y3998I3876J0D01*
G01X228209D01*
G03X232086Y7874I0J3877D01*
G01Y46654D01*
G02X240020Y54588I7934J0D01*
G37*
G36*
G01X328177Y1253176D02*
X332543D01*
G02X332576Y1253173I-2J-200D01*
G02X332683Y1253119I-32J-197D01*
G01X342009Y1243793D01*
G03X342151Y1243734I142J141D01*
G01X367255D01*
G03X367397Y1243793I0J200D01*
G01X374258Y1250654D01*
G02X374283Y1250675I141J-142D01*
G01Y1250676D01*
G02X374400Y1250713I116J-163D01*
G01X461532D01*
G02X461730Y1250542I0J-200D01*
G03X463216Y1249258I1486J218D01*
G03X463775Y1249366I0J1501D01*
G01X463821Y1249385D01*
X463920Y1249374D01*
X464236Y1249160D01*
G02X464324Y1248994I-112J-166D01*
G01Y1245821D01*
G02X464236Y1245655I-200J0D01*
G01X463920Y1245441D01*
X463821Y1245430D01*
X463775Y1245449D01*
G03X463216Y1245557I-559J-1393D01*
G03Y1242553I0J-1502D01*
G03X463775Y1242661I0J1501D01*
G01X463821Y1242680D01*
X463920Y1242669D01*
X464236Y1242455D01*
G02X464324Y1242289I-112J-166D01*
G01Y1204570D01*
G02X464265Y1204428I-200J0D01*
G01X459480Y1199643D01*
G03X459421Y1199501I141J-142D01*
G01Y1190630D01*
G03X459480Y1190488I200J0D01*
G01X464265Y1185703D01*
G02X464267Y1185701I-140J-142D01*
G02X464324Y1185561I-143J-140D01*
G01Y1159195D01*
G02X464265Y1159053I-200J0D01*
G01X462619Y1157407D01*
X462591Y1157378D01*
X462517Y1157348D01*
X460443D01*
G03X460367Y1157333I0J-200D01*
G01X460265Y1157290D01*
X397623D01*
G02X397492Y1157339I0J200D01*
G01X397454Y1157372D01*
G03X396256Y1157797I-1198J-1477D01*
G01X389623D01*
Y1157796D01*
X384831D01*
G03X384179Y1157680I2J-1901D01*
G03X383490Y1157240I655J-1785D01*
G01X373870Y1147620D01*
G03X373430Y1146931I1345J-1344D01*
G03X373314Y1146275I1785J-654D01*
G01Y1130205D01*
G03X373430Y1129549I1901J-2D01*
G03X373870Y1128860I1785J655D01*
G01X381916Y1120814D01*
X383092Y1119639D01*
G02X383146Y1119503I-146J-137D01*
G01Y1086930D01*
G02X382946Y1086730I-200J0D01*
G01X343607D01*
G03X343465Y1086671I0J-200D01*
G01X323935Y1067141D01*
X323907Y1067112D01*
X323833Y1067082D01*
X235754D01*
G02X235612Y1067141I0J200D01*
G01X233710Y1069043D01*
G02X233674Y1069092I141J142D01*
G01X233660Y1069119D01*
X233654Y1069150D01*
Y1069152D01*
G03X233446Y1069898I-3868J-676D01*
G01X233432Y1069933D01*
Y1070209D01*
Y1070216D01*
G02X233537Y1070385I200J-7D01*
G02X233546Y1070390I101J-172D01*
G01X233925Y1070570D01*
X234039Y1070556D01*
X234084Y1070520D01*
G03X234841Y1070252I757J935D01*
G03Y1072656I0J1202D01*
G03X234084Y1072388I0J-1203D01*
G01X234039Y1072352D01*
X233925Y1072338D01*
X233546Y1072518D01*
G02X233537Y1072523I92J177D01*
G02X233432Y1072692I95J176D01*
G01Y1073842D01*
G02X233506Y1073997I200J0D01*
G01X233523Y1074011D01*
X233863Y1074181D01*
G02X234070Y1074165I90J-178D01*
G01X234072Y1074163D01*
X234073Y1074162D01*
G03X234841Y1073908I768J1034D01*
G03Y1076482I0J1287D01*
G03X234073Y1076228I0J-1288D01*
G01X234072Y1076227D01*
X234070Y1076225D01*
G02X233863Y1076209I-117J162D01*
G01X233543Y1076369D01*
G02X233506Y1076393I90J179D01*
G02X233432Y1076548I126J155D01*
G01Y1077582D01*
G02X233506Y1077737I200J0D01*
G01X233523Y1077751D01*
X233863Y1077921D01*
G02X234070Y1077905I90J-178D01*
G01X234072Y1077903D01*
X234073Y1077902D01*
G03X234841Y1077648I768J1034D01*
G03Y1080222I0J1287D01*
G01X234806D01*
X234752Y1080221D01*
X234705Y1080246D01*
G02X234630Y1080318I96J175D01*
G01X234422Y1080661D01*
X234419Y1080768D01*
X234446Y1080816D01*
G03X234689Y1081344I-3345J1859D01*
G02X234871Y1081475I188J-69D01*
G03X236044Y1082677I-29J1202D01*
G03X235076Y1083856I-1202J0D01*
G02X234916Y1084035I39J196D01*
G03X234847Y1084506I-3813J-318D01*
G02Y1084588I196J41D01*
G03X234916Y1085059I-3744J789D01*
G02X235076Y1085238I199J-17D01*
G03X236044Y1086417I-234J1179D01*
G03X234871Y1087619I-1202J0D01*
G02X234689Y1087749I5J200D01*
G03X234402Y1088354I-3587J-1331D01*
G01X234401Y1088355D01*
X234400Y1088357D01*
G02X234403Y1088560I174J99D01*
G01X234617Y1088909D01*
X234714Y1088960D01*
X234770Y1088957D01*
G03X234842Y1088955I69J1200D01*
G03X233640Y1090157I0J1202D01*
G03X233734Y1089692I1202J1D01*
G02X233428Y1089456I-185J-77D01*
G03X233239Y1089592I-2329J-3037D01*
G02X233150Y1089758I111J166D01*
G01Y1092807D01*
G03X233091Y1092949I-200J0D01*
G01X232360Y1093680D01*
G02X232315Y1093750I142J141D01*
G01X232300Y1093789D01*
X232302Y1093832D01*
Y1093833D01*
G03X232304Y1093897I-1200J70D01*
G03X231102Y1095099I-1202J0D01*
G03X230881Y1095078I3J-1202D01*
G01X230832Y1095069D01*
X230738Y1095098D01*
X230433Y1095403D01*
X230404Y1095497D01*
X230413Y1095546D01*
G03X230434Y1095767I-1182J224D01*
G01Y1095778D01*
G03X230413Y1095988I-1202J-14D01*
G01X230404Y1096037D01*
X230433Y1096131D01*
X230738Y1096436D01*
X230832Y1096465D01*
X230881Y1096456D01*
G03X231102Y1096435I224J1181D01*
G03X229900Y1097637I0J1202D01*
G03X229921Y1097416I1202J3D01*
G01X229930Y1097367D01*
X229901Y1097273D01*
X229596Y1096968D01*
X229502Y1096939D01*
X229453Y1096948D01*
G03X229232Y1096969I-224J-1181D01*
G01X229231D01*
G03X228725Y1096857I1J-1202D01*
G01X228723D01*
G03X228714Y1096853I484J-1102D01*
G03X228712Y1096852I89J-180D01*
G02X228640Y1096833I-86J180D01*
G02X228456Y1096927I-14J200D01*
G01X228429Y1096971D01*
X228424Y1097073D01*
X228446Y1097119D01*
G03X228564Y1097637I-1084J519D01*
G03X226160I-1202J0D01*
G03X226169Y1097496I1202J6D01*
G01Y1097491D01*
G02X226108Y1097326I-199J-20D01*
G01X225841Y1097071D01*
X225752Y1097044D01*
X225705Y1097052D01*
G03X225489Y1097070I-216J-1284D01*
G01X225488D01*
G03X225278Y1097053I0J-1303D01*
G01X225277D01*
G02X225106Y1097106I-33J197D01*
G01X224841Y1097360D01*
X224810Y1097447D01*
X224816Y1097495D01*
G03X224824Y1097637I-1194J139D01*
G03X222420I-1202J0D01*
G03X222438Y1097428I1202J-2D01*
G01X222447Y1097380D01*
X222417Y1097285D01*
X222149Y1097020D01*
G02X221972Y1096965I-141J142D01*
G03X221752Y1096985I-220J-1198D01*
G01X221751D01*
G03X221531Y1096965I0J-1218D01*
G01X221482Y1096956D01*
X221389Y1096985D01*
X221086Y1097286D01*
X221056Y1097379D01*
X221065Y1097428D01*
G03X221083Y1097637I-1184J207D01*
G03X218679I-1202J0D01*
G03X218688Y1097496I1202J6D01*
G01Y1097491D01*
G02X218628Y1097326I-199J-21D01*
G01X218396Y1097105D01*
G02X218225Y1097052I-138J144D01*
G01X218224D01*
G03X218009Y1097070I-216J-1285D01*
G03X217797Y1097053I-2J-1302D01*
G01X217750Y1097045D01*
X217661Y1097072D01*
X217395Y1097325D01*
G02X217335Y1097495I139J144D01*
G03X217343Y1097637I-1194J139D01*
G03X214939I-1202J0D01*
G03X214957Y1097428I1202J-2D01*
G01X214966Y1097379D01*
X214936Y1097286D01*
X214633Y1096985D01*
X214540Y1096956D01*
X214491Y1096965D01*
G03X214271Y1096985I-220J-1198D01*
G03X214051Y1096965I0J-1218D01*
G01X214002Y1096956D01*
X213909Y1096985D01*
X213606Y1097286D01*
X213576Y1097379D01*
X213585Y1097428D01*
G03X213603Y1097637I-1184J207D01*
G03X211199I-1202J0D01*
G03X211208Y1097496I1202J6D01*
G01Y1097494D01*
X211213Y1097446D01*
X211198Y1097403D01*
G02X211147Y1097325I-188J67D01*
G01X210880Y1097071D01*
X210791Y1097044D01*
X210744Y1097052D01*
G03X210528Y1097070I-216J-1284D01*
G01X210526D01*
G03X210316Y1097053I0J-1303D01*
G01X210269Y1097045D01*
X210180Y1097073D01*
X209881Y1097359D01*
X209849Y1097448D01*
X209855Y1097495D01*
G03X209863Y1097637I-1194J139D01*
G03X207459I-1202J0D01*
G03X207477Y1097428I1202J-2D01*
G01X207486Y1097379D01*
X207456Y1097286D01*
X207153Y1096985D01*
X207060Y1096956D01*
X207011Y1096965D01*
G03X206791Y1096985I-220J-1198D01*
G03X206571Y1096965I0J-1218D01*
G01X206522Y1096956D01*
X206429Y1096985D01*
X206126Y1097286D01*
X206096Y1097379D01*
X206105Y1097428D01*
G03X206123Y1097637I-1184J207D01*
G03X203719I-1202J0D01*
G03X203728Y1097496I1202J6D01*
G01Y1097494D01*
X203733Y1097446D01*
X203718Y1097403D01*
G02X203667Y1097325I-188J67D01*
G01X203400Y1097071D01*
X203311Y1097044D01*
X203264Y1097052D01*
G03X203048Y1097070I-216J-1284D01*
G01X203046D01*
G03X202836Y1097053I0J-1303D01*
G01X202789Y1097045D01*
X202700Y1097073D01*
X202401Y1097359D01*
X202369Y1097448D01*
X202375Y1097495D01*
G03X202383Y1097637I-1194J139D01*
G03X199979I-1202J0D01*
G03X199997Y1097428I1202J-2D01*
G01X200006Y1097379D01*
X199976Y1097286D01*
X199673Y1096985D01*
X199580Y1096956D01*
X199531Y1096965D01*
G03X199311Y1096985I-220J-1198D01*
G01X199310D01*
G03X199090Y1096965I0J-1218D01*
G02X198913Y1097020I-36J197D01*
G01X198645Y1097285D01*
X198615Y1097380D01*
X198624Y1097428D01*
G03X198642Y1097637I-1184J207D01*
G03X196238I-1202J0D01*
G03X196247Y1097496I1202J6D01*
G01Y1097491D01*
G02X196186Y1097326I-199J-20D01*
G01X195919Y1097071D01*
X195830Y1097044D01*
X195783Y1097052D01*
G03X195567Y1097070I-216J-1284D01*
G01X195566D01*
G03X195356Y1097053I0J-1303D01*
G01X195355D01*
G02X195184Y1097106I-33J197D01*
G01X194919Y1097360D01*
X194888Y1097447D01*
X194894Y1097495D01*
G03X194902Y1097637I-1194J139D01*
G03X192498I-1202J0D01*
G03X192518Y1097421I1202J2D01*
G01X192527Y1097372D01*
X192498Y1097279D01*
X192194Y1096976D01*
X192101Y1096947D01*
X192052Y1096956D01*
G03X191830Y1096976I-219J-1189D01*
G03X191608Y1096956I-3J-1209D01*
G01X191559Y1096947D01*
X191466Y1096976D01*
X191162Y1097279D01*
X191133Y1097372D01*
X191142Y1097421D01*
G03X191162Y1097637I-1182J218D01*
G03X189960Y1098839I-1202J0D01*
G01X189959D01*
G03X189518Y1098755I0J-1202D01*
G01X189483Y1098741D01*
X189445D01*
G02X189245Y1098941I0J200D01*
G01Y1099147D01*
X189252Y1099199D01*
X189255Y1099211D01*
G03X189292Y1099506I-1165J296D01*
G01Y1099508D01*
G03X189291Y1099544I-1202J-15D01*
G01Y1099573D01*
Y1099587D01*
X189290Y1099594D01*
Y1099598D01*
G03X189252Y1099819I-1199J-92D01*
G01X189245Y1099845D01*
Y1100073D01*
G02X189445Y1100273I200J0D01*
G01X189483D01*
X189518Y1100259D01*
G03X189959Y1100175I441J1118D01*
G01X189960D01*
G03Y1102579I0J1202D01*
G01X189959D01*
G03X189518Y1102495I0J-1202D01*
G01X189483Y1102481D01*
X189445D01*
G02X189245Y1102681I0J200D01*
G01Y1102887D01*
X189252Y1102939D01*
X189255Y1102951D01*
G03X189292Y1103246I-1165J296D01*
G01Y1103248D01*
G03X189291Y1103284I-1202J-15D01*
G01Y1103313D01*
Y1103327D01*
X189290Y1103334D01*
Y1103338D01*
G03X189252Y1103559I-1199J-92D01*
G01X189245Y1103585D01*
Y1103813D01*
G02X189445Y1104013I200J0D01*
G01X189483D01*
X189518Y1103999D01*
G03X189959Y1103915I441J1118D01*
G01X189960D01*
G03Y1106319I0J1202D01*
G01X189959D01*
G03X189518Y1106235I0J-1202D01*
G01X189483Y1106221D01*
X189445D01*
G02X189245Y1106421I0J200D01*
G01Y1106628D01*
X189252Y1106680D01*
X189255Y1106692D01*
G03X189292Y1106987I-1165J296D01*
G01Y1106989D01*
G03X189291Y1107025I-1202J-15D01*
G01Y1107054D01*
Y1107068D01*
X189290Y1107075D01*
Y1107079D01*
G03X189252Y1107300I-1199J-92D01*
G01X189245Y1107326D01*
Y1107554D01*
G02X189445Y1107754I200J0D01*
G01X189483D01*
X189518Y1107740D01*
G03X189959Y1107656I441J1118D01*
G01X189960D01*
G03Y1110060I0J1202D01*
G01X189959D01*
G03X189518Y1109976I0J-1202D01*
G01X189483Y1109962D01*
X189445D01*
G02X189245Y1110162I0J200D01*
G01Y1110368D01*
X189252Y1110420D01*
X189255Y1110432D01*
G03X189292Y1110727I-1165J296D01*
G01Y1110729D01*
G03X189291Y1110765I-1202J-15D01*
G01Y1110794D01*
Y1110808D01*
X189290Y1110815D01*
Y1110819D01*
G03X189252Y1111040I-1199J-92D01*
G01X189245Y1111066D01*
Y1114108D01*
X189252Y1114160D01*
X189255Y1114172D01*
G03X189292Y1114468I-1165J296D01*
G03X189291Y1114509I-1202J-9D01*
G01Y1114534D01*
G03X189290Y1114552I-200J-2D01*
G01Y1114555D01*
G03X189252Y1114779I-1200J-88D01*
G01X189245Y1114805D01*
Y1117848D01*
X189252Y1117900D01*
X189255Y1117912D01*
G03X189292Y1118208I-1165J296D01*
G03X189291Y1118249I-1202J-9D01*
G01Y1118274D01*
G03X189290Y1118292I-200J-2D01*
G01Y1118295D01*
G03X189252Y1118519I-1200J-88D01*
G01X189245Y1118545D01*
Y1121588D01*
X189252Y1121640D01*
X189255Y1121652D01*
G03X189292Y1121948I-1165J296D01*
G03X189291Y1121989I-1202J-9D01*
G01Y1122014D01*
G03X189290Y1122032I-200J-2D01*
G01Y1122035D01*
G03X189252Y1122259I-1200J-88D01*
G01X189245Y1122285D01*
Y1125328D01*
X189252Y1125380D01*
X189255Y1125392D01*
G03X189292Y1125688I-1165J296D01*
G03X189291Y1125729I-1202J-9D01*
G01Y1125754D01*
G03X189290Y1125772I-200J-2D01*
G01Y1125775D01*
G03X189252Y1125999I-1200J-88D01*
G01X189245Y1126025D01*
Y1129069D01*
X189252Y1129121D01*
X189255Y1129133D01*
G03X189292Y1129429I-1165J296D01*
G03X189291Y1129470I-1202J-9D01*
G01Y1129495D01*
G03X189290Y1129513I-200J-2D01*
G01Y1129516D01*
G03X189252Y1129740I-1200J-88D01*
G01X189245Y1129766D01*
Y1132809D01*
X189252Y1132861D01*
X189255Y1132873D01*
G03X189292Y1133169I-1165J296D01*
G03X189291Y1133210I-1202J-9D01*
G01Y1133235D01*
G03X189290Y1133253I-200J-2D01*
G01Y1133256D01*
G03X189252Y1133480I-1200J-88D01*
G01X189245Y1133506D01*
Y1136549D01*
X189252Y1136601D01*
X189255Y1136613D01*
G03X189292Y1136909I-1165J296D01*
G03X189291Y1136950I-1202J-9D01*
G01Y1136975D01*
G03X189290Y1136993I-200J-2D01*
G01Y1136996D01*
G03X189252Y1137220I-1200J-88D01*
G01X189245Y1137246D01*
Y1140289D01*
X189252Y1140340D01*
X189255Y1140351D01*
G03X189280Y1140478I-1165J295D01*
G01X189285Y1140512D01*
G03X189292Y1140641I-1195J130D01*
G01Y1140650D01*
G03X189254Y1140949I-1202J-1D01*
G01X189251Y1140961D01*
X189245Y1141006D01*
Y1141024D01*
G02X189300Y1141162I200J0D01*
G01X189302Y1141164D01*
X189714Y1141575D01*
G03X189886Y1141793I-851J848D01*
G01X189900Y1141816D01*
X189903Y1141821D01*
G03X189951Y1141911I-1036J610D01*
G01X189971Y1141955D01*
X189976Y1141969D01*
X189978Y1141973D01*
G03X190066Y1142393I-1113J452D01*
G01Y1142822D01*
G02X190099Y1142933I200J1D01*
G01X190195Y1143078D01*
G03X190141Y1143354I-166J111D01*
G01X189714Y1143642D01*
G02X189688Y1143663I112J166D01*
G01X189639Y1143710D01*
G03X189611Y1143732I-137J-145D01*
G01X189571Y1143758D01*
X189563Y1143767D01*
X189392Y1143886D01*
G02X189389Y1143888I109J167D01*
G01X189341Y1143923D01*
G02X189263Y1144127I117J162D01*
G01Y1144129D01*
G03X189292Y1144389I-1173J262D01*
G03X189263Y1144651I-1202J0D01*
G01X189250Y1144710D01*
X189293Y1144822D01*
X189388Y1144890D01*
X189419Y1144912D01*
X189467Y1144945D01*
X189472Y1144949D01*
X189480Y1144954D01*
X189502Y1144970D01*
X189542Y1144998D01*
X189564Y1145013D01*
G03X189648Y1145079I-700J977D01*
G01X189655Y1145086D01*
X189666Y1145094D01*
X189684Y1145110D01*
G03X189738Y1145165I-830J869D01*
G01X189742Y1145170D01*
X189749Y1145177D01*
G03X189801Y1145235I-868J831D01*
G01X189840Y1145288D01*
G03X190066Y1145989I-976J701D01*
G01Y1146562D01*
G02X190099Y1146673I200J1D01*
G01X190195Y1146818D01*
G03X190141Y1147094I-166J111D01*
G01X189714Y1147382D01*
G02X189688Y1147403I112J166D01*
G01X189639Y1147450D01*
G03X189611Y1147472I-137J-145D01*
G01X189571Y1147498D01*
X189563Y1147507D01*
X189392Y1147626D01*
G02X189389Y1147628I109J167D01*
G01X189341Y1147663D01*
G02X189263Y1147867I117J162D01*
G01Y1147869D01*
G03X189292Y1148129I-1173J262D01*
G03X189263Y1148391I-1202J0D01*
G01X189250Y1148450D01*
X189293Y1148562D01*
X189388Y1148630D01*
X189419Y1148652D01*
X189467Y1148685D01*
X189472Y1148689D01*
X189480Y1148694D01*
X189502Y1148710D01*
X189542Y1148738D01*
X189564Y1148753D01*
G03X189648Y1148819I-700J977D01*
G01X189655Y1148826D01*
X189666Y1148834D01*
X189684Y1148850D01*
G03X189738Y1148905I-830J869D01*
G01X189742Y1148910D01*
X189749Y1148917D01*
G03X189801Y1148975I-868J831D01*
G01X189840Y1149028D01*
G03X190066Y1149729I-976J701D01*
G01Y1150303D01*
G02X190099Y1150414I200J1D01*
G01X190195Y1150559D01*
G03X190141Y1150835I-166J111D01*
G01X189714Y1151123D01*
G02X189688Y1151144I112J166D01*
G01X189639Y1151191D01*
G03X189611Y1151213I-137J-145D01*
G01X189571Y1151239D01*
X189563Y1151248D01*
X189392Y1151367D01*
G02X189389Y1151369I109J167D01*
G01X189341Y1151404D01*
G02X189263Y1151608I117J162D01*
G01Y1151610D01*
G03X189292Y1151870I-1173J262D01*
G03X189263Y1152132I-1202J0D01*
G01X189250Y1152191D01*
X189293Y1152303D01*
X189388Y1152371D01*
X189419Y1152393D01*
X189467Y1152426D01*
X189472Y1152430D01*
X189480Y1152435D01*
X189502Y1152451D01*
X189542Y1152479D01*
X189564Y1152494D01*
G03X189648Y1152560I-700J977D01*
G01X189655Y1152567D01*
X189666Y1152575D01*
X189684Y1152591D01*
G03X189738Y1152646I-830J869D01*
G01X189742Y1152651D01*
X189749Y1152658D01*
G03X189801Y1152716I-868J831D01*
G01X189840Y1152769D01*
G03X190066Y1153470I-976J701D01*
G01Y1156114D01*
G02X190095Y1156217I200J-1D01*
G01X190152Y1156313D01*
G03X190122Y1156558I-172J103D01*
G01X189297Y1157382D01*
G02X189246Y1157493I148J135D01*
G02X189245Y1157517I199J20D01*
G01Y1158990D01*
X189252Y1159042D01*
X189255Y1159054D01*
G03X189292Y1159350I-1165J296D01*
G01Y1159430D01*
G02X189349Y1159570I200J0D01*
G01X189350Y1159571D01*
X189601Y1159822D01*
X189606Y1159826D01*
G03X189619Y1159839I-844J857D01*
G01X189996Y1160216D01*
G03X190095Y1160329I-853J847D01*
G03X190215Y1160519I-952J734D01*
G03X190346Y1161061I-1071J546D01*
G01Y1165649D01*
Y1165651D01*
G02X190438Y1165817I200J-2D01*
G02X190466Y1165832I108J-168D01*
G01X190693Y1165932D01*
X190695D01*
X190779Y1165970D01*
G02X190935Y1165975I84J-181D01*
G01X190983Y1165956D01*
G02X191041Y1165922I-71J-187D01*
G01X191061Y1165905D01*
X191094Y1165879D01*
G03X191829Y1165628I735J951D01*
G01X191862D01*
G03X192226Y1165695I-33J1202D01*
G03X193032Y1166830I-396J1135D01*
G03X191830Y1168032I-1202J0D01*
G01X191829D01*
G03X190747Y1167354I0J-1202D01*
G01X190725Y1167308D01*
X190642Y1167249D01*
X190292Y1167207D01*
X190288D01*
G02X190182Y1167225I-21J199D01*
G01X190116Y1167257D01*
G02X190060Y1167296I84J181D01*
G01X190041Y1167315D01*
X190034Y1167324D01*
G03X190013Y1167348I-915J-779D01*
G01X190006Y1167355D01*
X190005Y1167356D01*
G03X189991Y1167370I-857J-843D01*
G01X189990Y1167371D01*
X189469Y1167893D01*
X189294Y1168068D01*
G02X189245Y1168198I151J131D01*
G01Y1170210D01*
X189252Y1170262D01*
X189255Y1170274D01*
G03X189292Y1170570I-1165J296D01*
G03X189291Y1170611I-1202J-9D01*
G01Y1170636D01*
G03X189290Y1170654I-200J-2D01*
G01Y1170657D01*
G03X189252Y1170881I-1200J-88D01*
G01X189245Y1170907D01*
Y1170972D01*
G02X189321Y1171129I200J0D01*
G01X189333Y1171138D01*
X189390Y1171181D01*
X189480Y1171249D01*
G03X189957Y1172207I-725J959D01*
G01Y1176414D01*
G03X189480Y1177372I-1202J-1D01*
G01X189420Y1177417D01*
X189418Y1177420D01*
X189341Y1177476D01*
G02X189317Y1177496I116J163D01*
G01X189304Y1177509D01*
G02X189245Y1177651I141J142D01*
G01Y1177691D01*
X189252Y1177743D01*
X189255Y1177755D01*
G03X189292Y1178051I-1165J296D01*
G03X189291Y1178092I-1202J-9D01*
G01Y1178117D01*
G03X189290Y1178135I-200J-2D01*
G01Y1178138D01*
G03X189252Y1178362I-1200J-88D01*
G01X189245Y1178388D01*
Y1181431D01*
X189252Y1181483D01*
X189255Y1181495D01*
G03X189292Y1181791I-1165J296D01*
G03X189291Y1181832I-1202J-9D01*
G01Y1181857D01*
G03X189290Y1181875I-200J-2D01*
G01Y1181878D01*
G03X189252Y1182102I-1200J-88D01*
G01X189245Y1182128D01*
Y1185171D01*
X189252Y1185223D01*
X189255Y1185235D01*
G03X189292Y1185531I-1165J296D01*
G03X189291Y1185572I-1202J-9D01*
G01Y1185597D01*
G03X189290Y1185615I-200J-2D01*
G01Y1185618D01*
G03X189252Y1185842I-1200J-88D01*
G01X189245Y1185868D01*
Y1192651D01*
X189252Y1192703D01*
X189255Y1192715D01*
G03X189292Y1193011I-1165J296D01*
G03X189291Y1193052I-1202J-9D01*
G01Y1193077D01*
G03X189290Y1193095I-200J-2D01*
G01Y1193098D01*
G03X189252Y1193322I-1200J-88D01*
G01X189245Y1193348D01*
Y1196391D01*
X189252Y1196443D01*
X189255Y1196455D01*
G03X189292Y1196751I-1165J296D01*
G03X189291Y1196792I-1202J-9D01*
G01Y1196817D01*
G03X189290Y1196835I-200J-2D01*
G01Y1196838D01*
G03X189252Y1197062I-1200J-88D01*
G01X189245Y1197088D01*
Y1200131D01*
X189252Y1200183D01*
X189255Y1200195D01*
G03X189292Y1200491I-1165J296D01*
G03X189291Y1200532I-1202J-9D01*
G01Y1200557D01*
G03X189290Y1200575I-200J-2D01*
G01Y1200578D01*
G03X189252Y1200802I-1200J-88D01*
G01X189245Y1200828D01*
Y1203872D01*
X189252Y1203924D01*
X189255Y1203936D01*
G03X189292Y1204232I-1165J296D01*
G03X189291Y1204273I-1202J-9D01*
G01Y1204298D01*
G03X189290Y1204316I-200J-2D01*
G01Y1204319D01*
G03X189252Y1204543I-1200J-88D01*
G01X189245Y1204569D01*
Y1207612D01*
X189252Y1207664D01*
X189255Y1207676D01*
G03X189292Y1207971I-1165J296D01*
G01Y1207973D01*
G03X189291Y1208009I-1202J-15D01*
G01Y1208038D01*
Y1208052D01*
X189290Y1208059D01*
Y1208063D01*
G03X189252Y1208284I-1199J-92D01*
G01X189245Y1208310D01*
Y1208538D01*
G02X189445Y1208738I200J0D01*
G01X189483D01*
X189518Y1208724D01*
G03X189959Y1208640I441J1118D01*
G01X189960D01*
G03X190181Y1208661I-3J1202D01*
G01X190230Y1208670D01*
X190324Y1208641D01*
X190629Y1208336D01*
X190658Y1208242D01*
X190649Y1208193D01*
G03X190628Y1207972I1181J-224D01*
G03X193032I1202J0D01*
G03X193011Y1208193I-1202J-3D01*
G01X193002Y1208242D01*
X193031Y1208336D01*
X193336Y1208641D01*
X193430Y1208670D01*
X193479Y1208661D01*
G03X193700Y1208640I224J1181D01*
G03X193921Y1208661I-3J1202D01*
G01X193970Y1208670D01*
X194064Y1208641D01*
X194369Y1208336D01*
X194398Y1208242D01*
X194389Y1208193D01*
G03X194368Y1207972I1181J-224D01*
G03X196772I1202J0D01*
G03X196751Y1208193I-1202J-3D01*
G01X196742Y1208242D01*
X196771Y1208336D01*
X197076Y1208641D01*
X197170Y1208670D01*
X197219Y1208661D01*
G03X197440Y1208640I224J1181D01*
G03X197662Y1208661I-2J1202D01*
G02X197758Y1208656I38J-197D01*
G02X197841Y1208606I-59J-191D01*
G01X198075Y1208372D01*
G02X198130Y1208194I-142J-141D01*
G03X198109Y1207972I1181J-224D01*
G03X199311Y1209174I1202J0D01*
G03X199089Y1209153I2J-1202D01*
G02X198993Y1209158I-38J197D01*
G02X198910Y1209208I59J191D01*
G01X198676Y1209442D01*
G02X198621Y1209620I142J141D01*
G03X198642Y1209842I-1181J224D01*
G03X196238I-1202J0D01*
G03X196259Y1209621I1202J3D01*
G01X196268Y1209572D01*
X196239Y1209478D01*
X195934Y1209173D01*
X195840Y1209144D01*
X195791Y1209153D01*
G03X195570Y1209174I-224J-1181D01*
G03X195349Y1209153I3J-1202D01*
G01X195300Y1209144D01*
X195206Y1209173D01*
X194901Y1209478D01*
X194872Y1209572D01*
X194881Y1209621D01*
G03X194902Y1209842I-1181J224D01*
G03X192498I-1202J0D01*
G03X192519Y1209621I1202J3D01*
G01X192528Y1209572D01*
X192499Y1209478D01*
X192194Y1209173D01*
X192100Y1209144D01*
X192051Y1209153D01*
G03X191830Y1209174I-224J-1181D01*
G03X191609Y1209153I3J-1202D01*
G01X191560Y1209144D01*
X191466Y1209173D01*
X191161Y1209478D01*
X191132Y1209572D01*
X191141Y1209621D01*
G03X191162Y1209842I-1181J224D01*
G03X189960Y1211044I-1202J0D01*
G01X189959D01*
G03X189518Y1210960I0J-1202D01*
G01X189483Y1210946D01*
X189445D01*
G02X189245Y1211146I0J200D01*
G01Y1211352D01*
X189252Y1211404D01*
X189255Y1211416D01*
G03X189292Y1211711I-1165J296D01*
G01Y1211713D01*
G03X189291Y1211749I-1202J-15D01*
G01Y1211778D01*
Y1211792D01*
X189290Y1211799D01*
Y1211803D01*
G03X189252Y1212024I-1199J-92D01*
G01X189245Y1212050D01*
Y1212278D01*
G02X189445Y1212478I200J0D01*
G01X189483D01*
X189518Y1212464D01*
G03X189959Y1212380I441J1118D01*
G01X189960D01*
G03Y1214784I0J1202D01*
G01X189959D01*
G03X189518Y1214700I0J-1202D01*
G01X189483Y1214686D01*
X189445D01*
G02X189245Y1214886I0J200D01*
G01Y1215092D01*
X189252Y1215144D01*
X189255Y1215156D01*
G03X189292Y1215451I-1165J296D01*
G01Y1215453D01*
G03X189291Y1215489I-1202J-15D01*
G01Y1215518D01*
Y1215532D01*
X189290Y1215539D01*
Y1215543D01*
G03X189252Y1215764I-1199J-92D01*
G01X189245Y1215790D01*
Y1216018D01*
G02X189445Y1216218I200J0D01*
G01X189483D01*
X189518Y1216204D01*
G03X189959Y1216120I441J1118D01*
G01X189960D01*
G03X191162Y1217322I0J1202D01*
G03X191141Y1217543I-1202J-3D01*
G01X191132Y1217592D01*
X191160Y1217685D01*
X191464Y1217990D01*
X191557Y1218019D01*
X191607Y1218010D01*
G03X191829Y1217990I218J1182D01*
G01X191830D01*
G03X193032Y1219192I0J1202D01*
G01Y1219220D01*
X193031Y1219260D01*
X193060Y1219334D01*
X193216Y1219495D01*
X193287Y1219568D01*
G02X193431Y1219629I144J-139D01*
G01X193967D01*
G02X194110Y1219569I0J-200D01*
G01X194339Y1219334D01*
X194368Y1219260D01*
X194367Y1219220D01*
Y1219192D01*
G03X195569Y1217990I1202J0D01*
G01X195570D01*
G03X195791Y1218011I-3J1202D01*
G01X195840Y1218020D01*
X195934Y1217991D01*
X196239Y1217686D01*
X196268Y1217592D01*
X196259Y1217543D01*
G03X196238Y1217322I1181J-224D01*
G03X196259Y1217101I1202J3D01*
G01X196268Y1217052D01*
X196239Y1216958D01*
X195934Y1216653D01*
X195840Y1216624D01*
X195791Y1216633D01*
G03X195570Y1216654I-224J-1181D01*
G03X194368Y1215452I0J-1202D01*
G03X194389Y1215231I1202J3D01*
G01X194398Y1215182D01*
X194369Y1215088D01*
X194064Y1214783D01*
X193970Y1214754D01*
X193921Y1214763D01*
G03X193700Y1214784I-224J-1181D01*
G03X194902Y1213582I0J-1202D01*
G03X194881Y1213803I-1202J-3D01*
G01X194872Y1213852D01*
X194901Y1213946D01*
X195206Y1214251D01*
X195300Y1214280D01*
X195349Y1214271D01*
G03X195570Y1214250I224J1181D01*
G03X196772Y1215452I0J1202D01*
G03X196751Y1215673I-1202J-3D01*
G01X196742Y1215722D01*
X196771Y1215816D01*
X197076Y1216121D01*
X197170Y1216150D01*
X197219Y1216141D01*
G03X197440Y1216120I224J1181D01*
G03X198642Y1217322I0J1202D01*
G03X198621Y1217543I-1202J-3D01*
G01X198612Y1217592D01*
X198641Y1217686D01*
X198946Y1217991D01*
X199040Y1218020D01*
X199089Y1218011D01*
G03X199310Y1217990I224J1181D01*
G01X199311D01*
G03X199532Y1218011I-3J1202D01*
G01X199581Y1218020D01*
X199675Y1217991D01*
X199980Y1217686D01*
X200009Y1217592D01*
X200000Y1217543D01*
G03X199979Y1217322I1181J-224D01*
G03X201181Y1216120I1202J0D01*
G03X201402Y1216141I-3J1202D01*
G01X201451Y1216150D01*
X201545Y1216121D01*
X201850Y1215816D01*
X201879Y1215722D01*
X201870Y1215673D01*
G03X201849Y1215452I1181J-224D01*
G03X201870Y1215231I1202J3D01*
G01X201879Y1215182D01*
X201850Y1215088D01*
X201545Y1214783D01*
X201451Y1214754D01*
X201402Y1214763D01*
G03X201181Y1214784I-224J-1181D01*
G03X202383Y1213582I0J-1202D01*
G03X202362Y1213803I-1202J-3D01*
G01X202353Y1213852D01*
X202382Y1213946D01*
X202687Y1214251D01*
X202781Y1214280D01*
X202830Y1214271D01*
G03X203051Y1214250I224J1181D01*
G03X203272Y1214271I-3J1202D01*
G01X203321Y1214280D01*
X203415Y1214251D01*
X203720Y1213946D01*
X203749Y1213852D01*
X203740Y1213803D01*
G03X203719Y1213582I1181J-224D01*
G03X204921Y1214784I1202J0D01*
G03X204700Y1214763I3J-1202D01*
G01X204651Y1214754D01*
X204557Y1214783D01*
X204252Y1215088D01*
X204223Y1215182D01*
X204232Y1215231D01*
G03X204253Y1215452I-1181J224D01*
G03X203051Y1216654I-1202J0D01*
G03X202830Y1216633I3J-1202D01*
G01X202781Y1216624D01*
X202687Y1216653D01*
X202382Y1216958D01*
X202353Y1217052D01*
X202362Y1217101D01*
G03X202383Y1217322I-1181J224D01*
G03X202362Y1217543I-1202J-3D01*
G01X202353Y1217592D01*
X202381Y1217685D01*
X202685Y1217990D01*
X202778Y1218019D01*
X202828Y1218010D01*
G03X203050Y1217990I218J1182D01*
G01X203051D01*
G03X204253Y1219192I0J1202D01*
G01Y1219220D01*
X204252Y1219260D01*
X204281Y1219334D01*
X204437Y1219495D01*
X204508Y1219568D01*
G02X204652Y1219629I144J-139D01*
G01X205188D01*
G02X205331Y1219569I0J-200D01*
G01X205560Y1219334D01*
X205589Y1219260D01*
X205588Y1219220D01*
Y1219192D01*
G03X206790Y1217990I1202J0D01*
G01X206791D01*
G03X207012Y1218011I-3J1202D01*
G01X207061Y1218020D01*
X207155Y1217991D01*
X207460Y1217686D01*
X207489Y1217592D01*
X207480Y1217543D01*
G03X207459Y1217322I1181J-224D01*
G03X208661Y1216120I1202J0D01*
G03X208882Y1216141I-3J1202D01*
G01X208931Y1216150D01*
X209025Y1216121D01*
X209330Y1215816D01*
X209359Y1215722D01*
X209350Y1215673D01*
G03X209329Y1215452I1181J-224D01*
G03X209350Y1215231I1202J3D01*
G01X209359Y1215182D01*
X209330Y1215088D01*
X209025Y1214783D01*
X208931Y1214754D01*
X208882Y1214763D01*
G03X208661Y1214784I-224J-1181D01*
G03Y1212380I0J-1202D01*
G03X208882Y1212401I-3J1202D01*
G01X208931Y1212410D01*
X209025Y1212381D01*
X209330Y1212076D01*
X209359Y1211982D01*
X209350Y1211933D01*
G03X209329Y1211712I1181J-224D01*
G03X210531Y1212914I1202J0D01*
G03X210310Y1212893I3J-1202D01*
G01X210261Y1212884D01*
X210167Y1212913D01*
X209862Y1213218D01*
X209833Y1213312D01*
X209842Y1213361D01*
G03X209863Y1213582I-1181J224D01*
G03X209842Y1213803I-1202J-3D01*
G01X209833Y1213852D01*
X209862Y1213946D01*
X210167Y1214251D01*
X210261Y1214280D01*
X210310Y1214271D01*
G03X210531Y1214250I224J1181D01*
G03Y1216654I0J1202D01*
G03X210310Y1216633I3J-1202D01*
G01X210261Y1216624D01*
X210167Y1216653D01*
X209862Y1216958D01*
X209833Y1217052D01*
X209842Y1217101D01*
G03X209863Y1217322I-1181J224D01*
G03X209842Y1217543I-1202J-3D01*
G01X209833Y1217592D01*
X209861Y1217685D01*
X210165Y1217990D01*
X210258Y1218019D01*
X210308Y1218010D01*
G03X210530Y1217990I218J1182D01*
G01X210531D01*
G03X211733Y1219192I0J1202D01*
G01Y1219220D01*
X211732Y1219260D01*
X211761Y1219334D01*
X211917Y1219495D01*
X211988Y1219568D01*
G02X212132Y1219629I144J-139D01*
G01X212668D01*
G02X212811Y1219569I0J-200D01*
G01X213040Y1219334D01*
X213069Y1219260D01*
X213068Y1219220D01*
Y1219192D01*
G03X214270Y1217990I1202J0D01*
G01X214271D01*
G03X215473Y1219192I0J1202D01*
G01Y1219220D01*
X215472Y1219260D01*
X215501Y1219334D01*
X215657Y1219495D01*
X215728Y1219568D01*
G02X215872Y1219629I144J-139D01*
G01X216408D01*
G02X216551Y1219569I0J-200D01*
G01X216780Y1219334D01*
X216809Y1219260D01*
X216808Y1219220D01*
Y1219192D01*
G03X218010Y1217990I1202J0D01*
G01X218011D01*
G03X218232Y1218011I-3J1202D01*
G01X218281Y1218020D01*
X218375Y1217991D01*
X218680Y1217686D01*
X218709Y1217592D01*
X218700Y1217543D01*
G03X218679Y1217322I1181J-224D01*
G03X218700Y1217101I1202J3D01*
G01X218709Y1217052D01*
X218680Y1216958D01*
X218375Y1216653D01*
X218281Y1216624D01*
X218232Y1216633D01*
G03X218011Y1216654I-224J-1181D01*
G03X219213Y1215452I0J-1202D01*
G03X219192Y1215673I-1202J-3D01*
G01X219183Y1215722D01*
X219212Y1215816D01*
X219517Y1216121D01*
X219611Y1216150D01*
X219660Y1216141D01*
G03X219881Y1216120I224J1181D01*
G03X220103Y1216141I-2J1202D01*
G02X220199Y1216136I38J-197D01*
G02X220282Y1216086I-59J-191D01*
G01X220516Y1215852D01*
G02X220571Y1215674I-142J-141D01*
G03X220550Y1215452I1181J-224D01*
G03X221752Y1216654I1202J0D01*
G03X221530Y1216633I2J-1202D01*
G02X221434Y1216638I-38J197D01*
G02X221351Y1216688I59J191D01*
G01X221117Y1216922D01*
G02X221062Y1217100I142J141D01*
G03X221083Y1217322I-1181J224D01*
G03X221062Y1217543I-1202J-3D01*
G01X221053Y1217592D01*
X221081Y1217685D01*
X221385Y1217990D01*
X221478Y1218019D01*
X221528Y1218010D01*
G03X221750Y1217990I218J1182D01*
G01X221751D01*
G03X222953Y1219192I0J1202D01*
G01Y1219220D01*
X222952Y1219260D01*
X222981Y1219334D01*
X223137Y1219495D01*
X223208Y1219568D01*
G02X223352Y1219629I144J-139D01*
G01X223889D01*
G02X224032Y1219569I0J-200D01*
G01X224261Y1219334D01*
X224290Y1219260D01*
X224289Y1219220D01*
Y1219192D01*
G03X225491Y1217990I1202J0D01*
G01X225492D01*
G03X226694Y1219192I0J1202D01*
G01Y1219220D01*
X226693Y1219260D01*
X226722Y1219334D01*
X226878Y1219495D01*
X226949Y1219568D01*
G02X227093Y1219629I144J-139D01*
G01X227306D01*
G02X227401Y1219605I0J-200D01*
G01X227471Y1219567D01*
X227477Y1219564D01*
X227528Y1219538D01*
G03X227677Y1219468I1689J3401D01*
G01X227683Y1219466D01*
X227694Y1219461D01*
G03X227731Y1219443I1679J3405D01*
G01X227768Y1219427D01*
G03X227846Y1219395I1480J3497D01*
G01X227874Y1219384D01*
X227921Y1219347D01*
X227986Y1219252D01*
X228003Y1219197D01*
X228004Y1219167D01*
G03X230458I1227J25D01*
G01Y1219203D01*
X230475Y1219253D01*
G02X230543Y1219349I190J-62D01*
G01X230594Y1219388D01*
X230620Y1219399D01*
G03X231020Y1219583I-1384J3536D01*
G01X231022Y1219584D01*
X231044Y1219595D01*
X231085Y1219611D01*
X231122Y1219622D01*
G02X231177Y1219629I53J-193D01*
G01X235109D01*
G02X235252Y1219569I0J-200D01*
G01X235481Y1219334D01*
X235510Y1219260D01*
X235509Y1219220D01*
Y1219192D01*
G03X236711Y1217990I1202J0D01*
G01X236712D01*
G03X236933Y1218011I-3J1202D01*
G01X236982Y1218020D01*
X237076Y1217991D01*
X237381Y1217686D01*
X237410Y1217592D01*
X237401Y1217543D01*
G03X237380Y1217322I1181J-224D01*
G03X237401Y1217101I1202J3D01*
G01X237410Y1217052D01*
X237381Y1216958D01*
X237076Y1216653D01*
X236982Y1216624D01*
X236933Y1216633D01*
G03X236712Y1216654I-224J-1181D01*
G03X237914Y1215452I0J-1202D01*
G03X237893Y1215673I-1202J-3D01*
G01X237884Y1215722D01*
X237913Y1215816D01*
X238218Y1216121D01*
X238312Y1216150D01*
X238361Y1216141D01*
G03X238582Y1216120I224J1181D01*
G03X238803Y1216141I-3J1202D01*
G01X238852Y1216150D01*
X238946Y1216121D01*
X239251Y1215816D01*
X239280Y1215722D01*
X239271Y1215673D01*
G03X239250Y1215452I1181J-224D01*
G03X241654I1202J0D01*
G03X241633Y1215673I-1202J-3D01*
G01X241624Y1215722D01*
X241653Y1215816D01*
X241958Y1216121D01*
X242052Y1216150D01*
X242101Y1216141D01*
G03X242322Y1216120I224J1181D01*
G03X242543Y1216141I-3J1202D01*
G01X242592Y1216150D01*
X242686Y1216121D01*
X242991Y1215816D01*
X243020Y1215722D01*
X243011Y1215673D01*
G03X242990Y1215452I1181J-224D01*
G03X244192Y1216654I1202J0D01*
G03X243971Y1216633I3J-1202D01*
G01X243922Y1216624D01*
X243828Y1216653D01*
X243523Y1216958D01*
X243494Y1217052D01*
X243503Y1217101D01*
G03X243524Y1217322I-1181J224D01*
G03X243503Y1217543I-1202J-3D01*
G01X243494Y1217592D01*
X243522Y1217685D01*
X243826Y1217990D01*
X243919Y1218019D01*
X243969Y1218010D01*
G03X244191Y1217990I218J1182D01*
G01X244192D01*
G03X245394Y1219192I0J1202D01*
G01Y1219220D01*
X245393Y1219260D01*
X245422Y1219334D01*
X245578Y1219495D01*
X245649Y1219568D01*
G02X245793Y1219629I144J-139D01*
G01X246005D01*
G02X246054Y1219623I0J-200D01*
G01X246082Y1219616D01*
X246106Y1219603D01*
X246150Y1219580D01*
X246151D01*
G03X246543Y1219398I1792J3347D01*
G01X246544Y1219397D01*
G02X246635Y1219325I-73J-186D01*
G01X246694Y1219240D01*
G02X246719Y1219192I-163J-115D01*
G01X246729Y1219164D01*
X246730Y1219135D01*
G03X247931Y1217990I1201J57D01*
G01X247932D01*
G03X249133Y1219139I0J1202D01*
G01X249134Y1219168D01*
X249153Y1219223D01*
X249210Y1219302D01*
X249213Y1219307D01*
X249238Y1219344D01*
X249264Y1219365D01*
X249291Y1219386D01*
X249319Y1219397D01*
G03X249638Y1219540I-1392J3533D01*
G03X249760Y1219604I-1702J3393D01*
G02X249856Y1219629I97J-175D01*
G01X250070D01*
G02X250213Y1219569I0J-200D01*
G01X250442Y1219334D01*
X250471Y1219260D01*
X250470Y1219220D01*
Y1219192D01*
G03X251672Y1217990I1202J0D01*
G01X251673D01*
G03X252875Y1219192I0J1202D01*
G01Y1219220D01*
X252874Y1219260D01*
X252903Y1219334D01*
X253059Y1219495D01*
X253130Y1219568D01*
G02X253274Y1219629I144J-139D01*
G01X253578D01*
G02X253749Y1219533I0J-200D01*
G01X253750Y1219531D01*
X253761Y1219513D01*
G03X253919Y1219441I1653J3418D01*
G01X253947Y1219430D01*
X253950Y1219428D01*
G03X253964Y1219422I1502J3485D01*
G03X253970Y1219420I66J189D01*
G03X253977Y1219417I1499J3488D01*
G01X253982D01*
X254048Y1219387D01*
X254073Y1219372D01*
X254089Y1219358D01*
G02X254128Y1219314I-128J-153D01*
G01X254169Y1219250D01*
G03X254210Y1219218I143J140D01*
G03X255384Y1217990I1202J-26D01*
G01X255414D01*
G03X256614Y1219138I-1J1202D01*
G01X256615Y1219167D01*
X256633Y1219219D01*
X256654Y1219249D01*
X256695Y1219312D01*
G02X256721Y1219344I167J-109D01*
G01X256758Y1219381D01*
X256797Y1219396D01*
G03X256947Y1219459I-1395J3531D01*
G03X257242Y1219604I-1526J3477D01*
G01X257243Y1219605D01*
G02X257339Y1219629I95J-176D01*
G01X257550D01*
G02X257693Y1219569I0J-200D01*
G01X257922Y1219334D01*
X257951Y1219260D01*
X257950Y1219220D01*
Y1219192D01*
G03X259152Y1217990I1202J0D01*
G01X259153D01*
G03X260355Y1219192I0J1202D01*
G01Y1219220D01*
X260354Y1219260D01*
X260383Y1219334D01*
X260539Y1219495D01*
X260610Y1219568D01*
G02X260754Y1219629I144J-139D01*
G01X261058D01*
G02X261229Y1219533I0J-200D01*
G01X261230Y1219531D01*
X261241Y1219513D01*
G03X261399Y1219441I1653J3418D01*
G01X261427Y1219430D01*
X261430Y1219428D01*
G03X261444Y1219422I1502J3485D01*
G03X261450Y1219420I66J189D01*
G03X261457Y1219417I1499J3488D01*
G01X261462D01*
X261528Y1219387D01*
X261553Y1219372D01*
X261569Y1219358D01*
G02X261608Y1219314I-128J-153D01*
G01X261649Y1219250D01*
G03X261690Y1219218I143J140D01*
G03X262864Y1217990I1202J-26D01*
G01X262894D01*
G03X264094Y1219138I-1J1202D01*
G01X264095Y1219167D01*
X264113Y1219219D01*
X264134Y1219249D01*
X264175Y1219312D01*
G02X264201Y1219344I167J-109D01*
G01X264238Y1219381D01*
X264277Y1219396D01*
G03X264427Y1219459I-1395J3531D01*
G03X264722Y1219604I-1526J3477D01*
G01X264723Y1219605D01*
G02X264819Y1219629I95J-176D01*
G01X265030D01*
G02X265173Y1219569I0J-200D01*
G01X265402Y1219334D01*
X265431Y1219260D01*
X265430Y1219220D01*
Y1219192D01*
G03X266632Y1217990I1202J0D01*
G01X266633D01*
G03X267835Y1219192I0J1202D01*
G01Y1219220D01*
X267834Y1219260D01*
X267863Y1219334D01*
X268019Y1219495D01*
X268090Y1219568D01*
G02X268234Y1219629I144J-139D01*
G01X268636D01*
X268733Y1219566D01*
X268758Y1219512D01*
X268768Y1219491D01*
G03X268817Y1219468I1638J3425D01*
G01X268819D01*
X268860Y1219449D01*
G03X268873Y1219443I1598J3445D01*
G01X268910Y1219427D01*
G03X268988Y1219395I1480J3497D01*
G01X269016Y1219384D01*
X269063Y1219347D01*
X269128Y1219252D01*
X269145Y1219197D01*
X269146Y1219168D01*
G03X270373Y1217965I1227J24D01*
G03X271600Y1219167I0J1227D01*
G01X271601Y1219197D01*
X271618Y1219252D01*
X271635Y1219276D01*
X271639Y1219282D01*
X271672Y1219328D01*
G02X271737Y1219387I164J-115D01*
G01X271750Y1219394D01*
G03X271889Y1219451I-1371J3541D01*
G03X272202Y1219604I-1509J3484D01*
G01X272204Y1219605D01*
X272227Y1219617D01*
X272274Y1219629D01*
X272511D01*
G02X272654Y1219569I0J-200D01*
G01X272883Y1219334D01*
X272912Y1219260D01*
X272911Y1219220D01*
Y1219192D01*
G03X274113Y1217990I1202J0D01*
G01X274114D01*
G03X275316Y1219192I0J1202D01*
G01Y1219220D01*
X275315Y1219260D01*
X275344Y1219334D01*
X275500Y1219495D01*
X275571Y1219568D01*
G02X275715Y1219629I144J-139D01*
G01X276019D01*
G02X276190Y1219533I0J-200D01*
G01X276191Y1219531D01*
X276202Y1219513D01*
G03X276360Y1219441I1653J3418D01*
G01X276388Y1219430D01*
X276391Y1219428D01*
G03X276405Y1219422I1502J3485D01*
G03X276411Y1219420I66J189D01*
G03X276418Y1219417I1499J3488D01*
G01X276423D01*
X276489Y1219387D01*
X276514Y1219372D01*
X276530Y1219358D01*
G02X276569Y1219314I-128J-153D01*
G01X276610Y1219250D01*
G03X276651Y1219218I143J140D01*
G03X277825Y1217990I1202J-26D01*
G01X277855D01*
G03X279055Y1219138I-1J1202D01*
G01X279056Y1219167D01*
X279074Y1219219D01*
X279095Y1219249D01*
X279136Y1219312D01*
G02X279162Y1219344I167J-109D01*
G01X279199Y1219381D01*
X279238Y1219396D01*
G03X279388Y1219459I-1395J3531D01*
G03X279683Y1219604I-1526J3477D01*
G01X279684Y1219605D01*
G02X279780Y1219629I95J-176D01*
G01X279991D01*
G02X280134Y1219569I0J-200D01*
G01X280363Y1219334D01*
X280392Y1219260D01*
X280391Y1219220D01*
Y1219192D01*
G03X281593Y1217990I1202J0D01*
G01X281594D01*
G03X282796Y1219192I0J1202D01*
G01Y1219220D01*
X282795Y1219260D01*
X282824Y1219334D01*
X282980Y1219495D01*
X283051Y1219568D01*
G02X283195Y1219629I144J-139D01*
G01X283499D01*
G02X283670Y1219533I0J-200D01*
G01X283671Y1219531D01*
X283682Y1219513D01*
G03X283840Y1219441I1653J3418D01*
G01X283868Y1219430D01*
X283871Y1219428D01*
G03X283885Y1219422I1502J3485D01*
G03X283891Y1219420I66J189D01*
G03X283898Y1219417I1499J3488D01*
G01X283903D01*
X283969Y1219387D01*
X283994Y1219372D01*
X284010Y1219358D01*
G02X284049Y1219314I-128J-153D01*
G01X284090Y1219250D01*
G03X284131Y1219218I143J140D01*
G03X285305Y1217990I1202J-26D01*
G01X285335D01*
G03X286535Y1219138I-1J1202D01*
G01X286536Y1219167D01*
X286554Y1219219D01*
X286575Y1219249D01*
X286616Y1219312D01*
G02X286642Y1219344I167J-109D01*
G01X286679Y1219381D01*
X286718Y1219396D01*
G03X286747Y1219408I-1437J3514D01*
G01X286784Y1219423D01*
G03X286981Y1219511I-1449J3509D01*
G01X286982Y1219512D01*
X287012Y1219526D01*
G03X287162Y1219604I-1676J3407D01*
G01X287207Y1219629D01*
X287261D01*
X287297Y1219644D01*
G03X287362Y1219687I-76J185D01*
G01X287453Y1219778D01*
X287481Y1219801D01*
X287493Y1219809D01*
G03X287565Y1219860I-2158J3123D01*
G01X287567Y1219862D01*
X287580Y1219871D01*
G03X287631Y1219909I-2243J3063D01*
G01X287635Y1219913D01*
X287647Y1219922D01*
G03X287657Y1219929I-2172J3113D01*
G01X287682Y1219949D01*
X287732Y1219967D01*
G02X287930Y1219927I65J-189D01*
G01X287971Y1219891D01*
X288005Y1219789D01*
X287987Y1219706D01*
X287978Y1219686D01*
G03X287872Y1219209I1096J-494D01*
G01Y1219207D01*
X287871Y1219173D01*
G03X289073Y1217990I1202J19D01*
G01X289074D01*
G03X289295Y1218011I-3J1202D01*
G01X289344Y1218020D01*
X289438Y1217991D01*
X289743Y1217686D01*
X289772Y1217592D01*
X289763Y1217543D01*
G03X289742Y1217322I1181J-224D01*
G03X290944Y1218524I1202J0D01*
G03X290723Y1218503I3J-1202D01*
G01X290674Y1218494D01*
X290580Y1218523D01*
X290275Y1218828D01*
X290246Y1218922D01*
X290255Y1218971D01*
G03X290276Y1219191I-1181J224D01*
G01Y1219193D01*
G03X290255Y1219412I-1202J-5D01*
G01X290246Y1219461D01*
X290274Y1219554D01*
X290545Y1219826D01*
G02X290722Y1219881I141J-142D01*
G01X290723D01*
G03X290944Y1219860I224J1181D01*
G03X292146Y1221062I0J1202D01*
G01Y1221064D01*
G03X292076Y1221466I-1202J-2D01*
G02X292337Y1221720I188J68D01*
G03X292432Y1221687I475J1213D01*
G03X293028Y1221647I383J1245D01*
G01X293075Y1221655D01*
X293164Y1221628D01*
X293465Y1221341D01*
X293497Y1221253D01*
X293491Y1221206D01*
G03X293483Y1221062I1194J-139D01*
G03X294685Y1222264I1202J0D01*
G03X294541Y1222256I-5J-1202D01*
G01X294494Y1222250D01*
X294406Y1222282D01*
X294120Y1222583D01*
X294092Y1222671D01*
X294100Y1222719D01*
G03X294118Y1222931I-1285J216D01*
G01Y1223210D01*
G02X294184Y1223358I200J0D01*
G01X294405Y1223558D01*
G02X294477Y1223599I133J-150D01*
G01X294517Y1223612D01*
X294560Y1223608D01*
G03X294685Y1223601I130J1195D01*
G03Y1226005I0J1202D01*
G03X294560Y1225998I5J-1202D01*
G01X294517Y1225994D01*
X294477Y1226007D01*
G02X294405Y1226048I61J191D01*
G01X294184Y1226248D01*
G02X294118Y1226396I134J148D01*
G01Y1226672D01*
G03X294100Y1226886I-1302J-2D01*
G02X294152Y1227057I197J33D01*
G01X294374Y1227289D01*
G02X294518Y1227351I145J-138D01*
G01X294532D01*
G03X294685Y1227341I155J1192D01*
G03Y1229745I0J1202D01*
G03X294463Y1229724I2J-1202D01*
G02X294367Y1229729I-38J197D01*
G02X294284Y1229779I59J191D01*
G01X294050Y1230013D01*
G02X293995Y1230191I142J141D01*
G03X294016Y1230413I-1181J224D01*
G03X293995Y1230635I-1202J-2D01*
G02X294050Y1230813I197J37D01*
G01X294284Y1231047D01*
G02X294367Y1231097I142J-141D01*
G02X294463Y1231102I58J-192D01*
G03X294685Y1231081I224J1181D01*
G03Y1233485I0J1202D01*
G03X294463Y1233464I2J-1202D01*
G01X294414Y1233455D01*
X294367Y1233469D01*
G02X294284Y1233519I59J191D01*
G01X294016Y1233788D01*
X293987Y1233881D01*
X293996Y1233930D01*
G03X294004Y1233981I-1184J212D01*
G01Y1233982D01*
X294011Y1234030D01*
G03X294017Y1234153I-1197J120D01*
G03X293996Y1234374I-1203J-3D01*
G01X293987Y1234423D01*
X294016Y1234517D01*
X294321Y1234822D01*
X294415Y1234851D01*
X294464Y1234842D01*
G03X294685Y1234821I224J1181D01*
G03Y1237225I0J1202D01*
G03X294463Y1237204I2J-1202D01*
G02X294367Y1237209I-38J197D01*
G02X294284Y1237259I59J191D01*
G01X294050Y1237493D01*
G02X293995Y1237671I142J141D01*
G03X294016Y1237897I-1181J224D01*
G01Y1237900D01*
G03X294002Y1238077I-1202J-6D01*
G03X294000Y1238087I-197J-34D01*
G01Y1238089D01*
X293999Y1238093D01*
X293996Y1238106D01*
G02X294001Y1238210I195J43D01*
G01Y1238212D01*
G02X294050Y1238292I190J-62D01*
G01X294284Y1238527D01*
G02X294367Y1238577I142J-141D01*
G01X294414Y1238591D01*
X294463Y1238582D01*
G03X294685Y1238561I224J1181D01*
G03Y1240965I0J1202D01*
G03X294470Y1240945I3J-1202D01*
G01X294421Y1240936D01*
X294328Y1240965D01*
X294024Y1241270D01*
X293995Y1241363D01*
X294004Y1241412D01*
G03X294022Y1241559I-1182J219D01*
G03X294003Y1241852I-1200J69D01*
G01Y1241855D01*
G02X294058Y1242031I197J35D01*
G01X294291Y1242265D01*
G02X294468Y1242321I142J-141D01*
G01X294469D01*
G03X294685Y1242301I218J1182D01*
G03Y1244705I0J1202D01*
G01X294683D01*
G03X294281Y1244635I2J-1202D01*
G02X294027Y1244896I-68J188D01*
G03X294036Y1244920I-1215J469D01*
G01X294041Y1244934D01*
G03X294118Y1245373I-1226J441D01*
G01Y1245650D01*
G02X294184Y1245798I200J0D01*
G01X294405Y1245998D01*
G02X294477Y1246039I133J-150D01*
G01X294517Y1246052D01*
X294560Y1246048D01*
G03X294685Y1246041I130J1195D01*
G03Y1248445I0J1202D01*
G03X294560Y1248438I5J-1202D01*
G01X294517Y1248434D01*
X294477Y1248447D01*
G02X294405Y1248488I61J191D01*
G01X294184Y1248688D01*
G02X294118Y1248836I134J148D01*
G01Y1249113D01*
G03X294100Y1249327I-1302J-2D01*
G01X294092Y1249375D01*
X294120Y1249463D01*
X294374Y1249730D01*
G02X294518Y1249792I145J-138D01*
G01X294532D01*
G03X294685Y1249782I155J1192D01*
G03X295887Y1250984I0J1202D01*
G03X295817Y1251388I-1201J0D01*
G01X295794Y1251451D01*
X295832Y1251576D01*
X295885Y1251616D01*
G02X296079Y1251642I120J-160D01*
G03X296172Y1251609I482J1210D01*
G03X296768Y1251569I383J1245D01*
G01X296815Y1251577D01*
X296904Y1251550D01*
X297205Y1251263D01*
X297237Y1251175D01*
X297231Y1251128D01*
G03X297223Y1250984I1194J-139D01*
G03X299627I1202J0D01*
G03X299606Y1251205I-1202J-3D01*
G01X299597Y1251254D01*
X299625Y1251347D01*
X299929Y1251652D01*
X300022Y1251681D01*
X300072Y1251672D01*
G03X300294Y1251652I218J1183D01*
G01X300295D01*
G03X300516Y1251673I-3J1202D01*
G01X300565Y1251682D01*
X300659Y1251653D01*
X300964Y1251348D01*
X300993Y1251254D01*
X300984Y1251205D01*
G03X300963Y1250984I1181J-224D01*
G03X303367I1202J0D01*
G03X303297Y1251388I-1201J0D01*
G01X303274Y1251451D01*
X303312Y1251576D01*
X303365Y1251616D01*
G02X303559Y1251642I120J-160D01*
G03X303652Y1251609I482J1210D01*
G03X304248Y1251569I383J1245D01*
G01X304295Y1251577D01*
X304384Y1251550D01*
X304685Y1251263D01*
X304717Y1251175D01*
X304711Y1251128D01*
G03X304703Y1250984I1194J-139D01*
G03X307107I1202J0D01*
G03X307086Y1251205I-1202J-3D01*
G01X307077Y1251254D01*
X307105Y1251347D01*
X307409Y1251652D01*
X307502Y1251681D01*
X307552Y1251672D01*
G03X307774Y1251652I218J1183D01*
G01X307775D01*
G03X307996Y1251673I-3J1202D01*
G01X308045Y1251682D01*
X308139Y1251653D01*
X308444Y1251348D01*
X308473Y1251254D01*
X308464Y1251205D01*
G03X308443Y1250984I1181J-224D01*
G03X310847I1202J0D01*
G03X310777Y1251388I-1201J0D01*
G01X310754Y1251451D01*
X310792Y1251576D01*
X310845Y1251616D01*
G02X311039Y1251642I120J-160D01*
G03X311132Y1251609I482J1210D01*
G03X311728Y1251569I383J1245D01*
G01X311775Y1251577D01*
X311864Y1251550D01*
X312165Y1251263D01*
X312197Y1251175D01*
X312191Y1251128D01*
G03X312183Y1250984I1194J-139D01*
G03X314587I1202J0D01*
G03X314566Y1251205I-1202J-3D01*
G01X314557Y1251254D01*
X314585Y1251347D01*
X314889Y1251652D01*
X314982Y1251681D01*
X315032Y1251672D01*
G03X315254Y1251652I218J1183D01*
G01X315255D01*
G03X315476Y1251673I-3J1202D01*
G01X315525Y1251682D01*
X315619Y1251653D01*
X315924Y1251348D01*
X315953Y1251254D01*
X315944Y1251205D01*
G03X315923Y1250984I1181J-224D01*
G03X318327I1202J0D01*
G03X318257Y1251388I-1201J0D01*
G01X318234Y1251451D01*
X318272Y1251576D01*
X318325Y1251616D01*
G02X318519Y1251642I120J-160D01*
G03X318612Y1251609I482J1210D01*
G03X318825Y1251563I380J1246D01*
G01X319001Y1251551D01*
G03X319209Y1251569I-8J1303D01*
G01X319257Y1251577D01*
X319345Y1251549D01*
X319612Y1251295D01*
G02X319674Y1251151I-138J-145D01*
G01Y1251138D01*
X319673Y1251126D01*
G03X319664Y1250984I1193J-147D01*
G03X322068I1202J0D01*
G03X322047Y1251205I-1202J-3D01*
G01X322038Y1251254D01*
X322066Y1251347D01*
X322370Y1251652D01*
X322463Y1251681D01*
X322513Y1251672D01*
G03X322735Y1251652I218J1183D01*
G01X322736D01*
G03X322957Y1251673I-3J1202D01*
G01X323006Y1251682D01*
X323100Y1251653D01*
X323405Y1251348D01*
X323434Y1251254D01*
X323425Y1251205D01*
G03X323404Y1250984I1181J-224D01*
G03X325808I1202J0D01*
G03X325799Y1251125I-1202J-6D01*
G01Y1251130D01*
G02X325859Y1251295I199J21D01*
G01X326125Y1251549D01*
X326214Y1251577D01*
X326262Y1251569D01*
G03X326537Y1251553I213J1285D01*
G03X327778Y1252795I-60J1301D01*
G01X327780Y1252834D01*
X327811Y1252903D01*
X328008Y1253093D01*
X328012Y1253096D01*
X328043Y1253124D01*
G02X328177Y1253176I135J-148D01*
G37*
G36*
G01X342382Y54588D02*
X371080D01*
X371204Y54464D01*
Y52932D01*
X370863Y52591D01*
X342382D01*
G03X336445Y46654I0J-5937D01*
G01Y7874D01*
G02X330571Y2000I-5874J0D01*
G01X283327D01*
G02X277453Y7874I0J5874D01*
G01Y46126D01*
X279450D01*
Y7874D01*
G03X283325Y3998I3876J0D01*
G01X330571D01*
G03X334448Y7874I0J3877D01*
G01Y46654D01*
G02X342382Y54588I7934J0D01*
G37*
G36*
G01X492382D02*
X520615D01*
X520833Y54370D01*
Y52809D01*
X520615Y52591D01*
X492382D01*
G03X486445Y46654I0J-5937D01*
G01Y7874D01*
G02X480571Y2000I-5874J0D01*
G01X385689D01*
G02X379815Y7874I0J5874D01*
G01Y46160D01*
X381812D01*
Y7874D01*
G03X385687Y3998I3876J0D01*
G01X480571D01*
G03X484448Y7874I0J3877D01*
G01Y46654D01*
G02X492382Y54588I7934J0D01*
G37*
G36*
G01X581703Y939404D02*
G03X582490Y939627I-1J1503D01*
G02X583100Y939287I210J-341D01*
G01Y930475D01*
G03X583101Y930458I200J3D01*
G01X583102Y930448D01*
Y930392D01*
X583143Y930351D01*
X583148Y930345D01*
G03X583159Y930333I153J129D01*
G01X584629Y928863D01*
G03X584641Y928852I141J142D01*
G01X584647Y928847D01*
X584688Y928806D01*
X584744D01*
X584754Y928805D01*
G03X584771Y928804I20J199D01*
G01X587615D01*
G02X587899Y928123I-1J-400D01*
G03X587464Y927066I1067J-1057D01*
G03X588966Y925564I1502J0D01*
G03X589207Y925584I-3J1502D01*
G01X589209D01*
G02X589370Y925539I32J-197D01*
G01X589603Y925341D01*
G02X589673Y925189I-130J-152D01*
G01Y800617D01*
X589197Y798106D01*
X588542Y794648D01*
X587988Y791725D01*
X587939Y791655D01*
X587901Y791633D01*
G03X587156Y790336I758J-1298D01*
G01Y790329D01*
X587157Y790299D01*
Y790298D01*
G03X587478Y789407I1502J38D01*
G01X587508Y789369D01*
X587527Y789277D01*
X587511Y789221D01*
G02X587460Y789132I-193J52D01*
G01X583606Y785278D01*
G02X583464Y785219I-142J141D01*
G01X573421D01*
G02X573252Y785312I0J200D01*
G03X570716I-1268J-805D01*
G02X570547Y785219I-169J107D01*
G01X563790D01*
X563685Y785296D01*
X563665Y785359D01*
G03X560797I-1434J-447D01*
G02X560606Y785219I-191J60D01*
G01X559853D01*
X559748Y785296D01*
X559728Y785359D01*
G03X556860I-1434J-447D01*
G02X556669Y785219I-191J60D01*
G01X555978D01*
G02X555803Y785322I0J200D01*
G01X555787Y785351D01*
X555781Y785368D01*
G03X553263Y785918I-1424J-480D01*
G01X553235Y785889D01*
X553119Y785837D01*
X553078Y785825D01*
X552803D01*
X552762Y785837D01*
X552644Y785890D01*
X552616Y785920D01*
G03X551524Y786391I-1092J-1030D01*
G01X551429D01*
G03X551400Y786389I-1J-200D01*
G01X551303Y786375D01*
G03X550097Y785358I221J-1486D01*
G01Y785357D01*
X550096Y785355D01*
G02X550024Y785258I-189J65D01*
G01X550023Y785257D01*
G02X549906Y785219I-117J162D01*
G01X544105D01*
X544000Y785296D01*
X543980Y785359D01*
G03X541112I-1434J-447D01*
G02X540921Y785219I-191J60D01*
G01X536331D01*
G02X536164Y785309I0J200D01*
G01X536144Y785339D01*
X536136Y785374D01*
G03X533208I-1464J-337D01*
G01X533200Y785339D01*
X533180Y785309D01*
G02X533013Y785219I-167J110D01*
G01X510356D01*
G02X510214Y785278I0J200D01*
G01X509278Y786214D01*
G02X509233Y786428I142J141D01*
G01X509247Y786463D01*
X509281Y786522D01*
X509292Y786535D01*
G03X509633Y787488I-1161J953D01*
G03X509631Y787561I-1503J-5D01*
G01X509626Y787621D01*
G03X508306Y788980I-1496J-133D01*
G01X508252Y788986D01*
G03X507139Y788618I-122J-1498D01*
G01X507079Y788565D01*
X506922Y788570D01*
X506173Y789319D01*
G02X506142Y789359I141J142D01*
G01X506123Y789392D01*
X506116Y789426D01*
G03X504927Y790614I-1475J-287D01*
G01X504898Y790619D01*
X504871Y790634D01*
G02X504823Y790669I92J177D01*
G01X501869Y793623D01*
G02X501810Y793765I141J142D01*
G01Y861527D01*
G02X501922Y861707I200J0D01*
G01X502230Y861858D01*
G02X502360Y861874I88J-180D01*
G01X502376Y861871D01*
X502457Y861842D01*
X502481Y861824D01*
G03X503383Y861523I902J1201D01*
G03X503484Y861526I6J1502D01*
G01X503512Y861529D01*
X503514D01*
G03X504885Y863025I-131J1496D01*
G03X503383Y864527I-1502J0D01*
G01X503381D01*
G03X502480Y864227I0J-1503D01*
G01X502455Y864208D01*
X502389Y864184D01*
G02X502234Y864193I-67J189D01*
G01X501923Y864343D01*
G02X501810Y864523I87J180D01*
G01Y936700D01*
G03X501751Y936842I-200J0D01*
G01X484295Y954298D01*
G03X484153Y954357I-142J-141D01*
G01X409927D01*
G02X409785Y954416I0J200D01*
G01X406361Y957840D01*
G02X406303Y957971I142J141D01*
G02X406347Y958106I200J10D01*
G01Y958107D01*
G03X406681Y959051I-1167J944D01*
G03X405179Y960553I-1502J0D01*
G03X404235Y960219I0J-1501D01*
G01X404175Y960171D01*
X404022Y960179D01*
X402475Y961726D01*
G02X402416Y961868I141J142D01*
G01Y983470D01*
G02X402475Y983612I200J0D01*
G01X403344Y984481D01*
G02X403486Y984540I142J-141D01*
G01X502493D01*
G03X502510Y984541I-3J200D01*
G01X502520Y984542D01*
X502548D01*
G02X502651Y984514I1J-200D01*
G01X502731Y984466D01*
X502753Y984453D01*
X502788Y984418D01*
X502801Y984397D01*
X502802Y984396D01*
G03X504082Y983669I1287J775D01*
G01X504089D01*
G03X505159Y984118I-1J1502D01*
G01X505160Y984119D01*
X505192Y984151D01*
X505225Y984166D01*
X505300Y984201D01*
G02X505384Y984219I83J-182D01*
G01X505592D01*
X505653Y984206D01*
G02X505695Y984192I-42J-196D01*
G01X505786Y984150D01*
X505812Y984123D01*
G03X506888Y983669I1076J1048D01*
G03X508174Y984396I0J1501D01*
G01X508175Y984397D01*
X508188Y984418D01*
X508205Y984435D01*
G02X508245Y984466I142J-141D01*
G01X508323Y984512D01*
G02X508425Y984540I102J-172D01*
G01X510748D01*
G02X510771Y984539I3J-200D01*
G02X510914Y984451I-24J-199D01*
G02X510922Y984438I-166J-111D01*
G03X513542I1310J733D01*
G02X513550Y984451I174J-98D01*
G02X513693Y984539I167J-111D01*
G02X513716Y984540I20J-199D01*
G01X519039D01*
G03X519181Y984599I0J200D01*
G01X537068Y1002486D01*
G03X537127Y1002628I-141J142D01*
G01Y1018832D01*
G02X537327Y1019032I200J0D01*
G01X539881D01*
G02X540023Y1018973I0J-200D01*
G01X540033Y1018963D01*
X540230Y1018738D01*
G02X540278Y1018578I-150J-132D01*
G03X540264Y1018368I1488J-205D01*
G03X543268I1502J0D01*
G03X543254Y1018578I-1502J5D01*
G01X543248Y1018622D01*
X543273Y1018704D01*
X543496Y1018961D01*
G02X543506Y1018971I146J-136D01*
G01X543508Y1018973D01*
G02X543650Y1019032I142J-141D01*
G01X546978D01*
G02X547131Y1018961I0J-200D01*
G01X547357Y1018692D01*
X547380Y1018608D01*
X547372Y1018564D01*
G03X547350Y1018313I1480J-256D01*
G01Y1018299D01*
G03X550354I1502J8D01*
G01Y1018308D01*
G03X550332Y1018564I-1502J0D01*
G01X550324Y1018608D01*
X550347Y1018692D01*
X550573Y1018961D01*
G02X550726Y1019032I153J-129D01*
G01X552801D01*
G02X552948Y1018967I-1J-200D01*
G01X553148Y1018750D01*
G02X553190Y1018679I-148J-135D01*
G01X553204Y1018638D01*
X553200Y1018596D01*
G03X553194Y1018469I1496J-134D01*
G03X556198I1502J0D01*
G03X556192Y1018596I-1502J-7D01*
G01Y1018598D01*
X556189Y1018640D01*
X556202Y1018680D01*
G02X556245Y1018751I189J-66D01*
G01X556445Y1018968D01*
G02X556592Y1019032I147J-136D01*
G01X611849D01*
G02X611991Y1018973I0J-200D01*
G01X619488Y1011476D01*
G02X619547Y1011334I-141J-142D01*
G01Y982018D01*
G02X619488Y981876I-200J0D01*
G01X604266Y966654D01*
G02X603668Y966690I-283J283D01*
G03X602484Y967267I-1184J-926D01*
G03X600981Y965764I0J-1503D01*
G03X601558Y964580I1503J0D01*
G02X601594Y963982I-247J-315D01*
G01X591395Y953783D01*
G02X590795Y953822I-283J283D01*
G03X589603Y954410I-1192J-914D01*
G03X588100Y952907I0J-1503D01*
G03X589418Y951415I1503J0D01*
G01X589453Y951411D01*
X589515Y951379D01*
X589619Y951268D01*
G02X589673Y951131I-146J-137D01*
G01Y945010D01*
G02X589473Y944810I-200J0D01*
G01X584271D01*
G03X584254Y944809I3J-200D01*
G01X584244Y944808D01*
X584188D01*
X584147Y944767D01*
X584141Y944762D01*
G03X584129Y944751I129J-153D01*
G01X583159Y943781D01*
G03X583148Y943769I142J-141D01*
G01X583143Y943763D01*
X583102Y943722D01*
Y943666D01*
X583101Y943656D01*
G03X583100Y943639I199J-20D01*
G01Y942527D01*
G02X582490Y942187I-400J1D01*
G03X581703Y942410I-788J-1280D01*
G03Y939404I0J-1503D01*
G37*
G36*
G01X426007Y1020047D02*
X426379Y1020419D01*
G02X426401Y1020438I141J-141D01*
G02X426521Y1020478I120J-160D01*
G01X433239D01*
G02X433359Y1020438I0J-200D01*
G02X433381Y1020419I-119J-160D01*
G01X433875Y1019925D01*
G02X433894Y1019903I-141J-141D01*
G02X433934Y1019783I-160J-120D01*
G01Y1015482D01*
G02X433894Y1015362I-200J0D01*
G02X433875Y1015340I-160J119D01*
G01X433626Y1015091D01*
G02X433604Y1015072I-141J141D01*
G02X433484Y1015032I-120J160D01*
G01X426766D01*
G02X426646Y1015072I0J200D01*
G02X426624Y1015091I119J160D01*
G01X426007Y1015708D01*
G02X425988Y1015730I141J141D01*
G02X425948Y1015850I160J120D01*
G01Y1019905D01*
G02X425988Y1020025I200J0D01*
G02X426007Y1020047I160J-119D01*
G37*
G36*
G01X435590Y1148300D02*
X462961D01*
G02X462980Y1148299I-1J-200D01*
G02X463103Y1148241I-19J-199D01*
G01X463533Y1147811D01*
G02X463591Y1147688I-141J-142D01*
G01X463592Y1147678D01*
Y1120907D01*
X463566Y1120839D01*
X463540Y1120811D01*
G03X463536Y1120806I154J-127D01*
G01X463530Y1120799D01*
X463509Y1120778D01*
X462366Y1119634D01*
G03X461852Y1118396I1237J-1239D01*
G03X462361Y1117161I1753J0D01*
G01X462362Y1117160D01*
G02X462420Y1117036I-141J-142D01*
G01Y1117034D01*
X462428Y1116915D01*
Y1116913D01*
X462431Y1116882D01*
X462413Y1116815D01*
X462390Y1116781D01*
X462379Y1116766D01*
X462371Y1116755D01*
X462345Y1116717D01*
G03X462101Y1115896I1259J-821D01*
G01Y1115872D01*
X462104Y1115818D01*
G03X462464Y1114918I1500J78D01*
G02X462307Y1114588I-152J-130D01*
G01X458868D01*
G03X457523Y1114032I-1J-1902D01*
G01X455548Y1112056D01*
G02X455407Y1111998I-141J142D01*
G01X448961D01*
G03X447616Y1111441I0J-1902D01*
G01X443069Y1106893D01*
G02X442928Y1106834I-142J141D01*
G01X440765D01*
G02X440598Y1106925I1J200D01*
G01X440387Y1107248D01*
X440378Y1107348D01*
X440399Y1107395D01*
G03X440525Y1107997I-1375J602D01*
G03X440157Y1108982I-1502J0D01*
G01X440132Y1109011D01*
X440107Y1109081D01*
X440121Y1109433D01*
X440151Y1109501D01*
X440178Y1109528D01*
G03X440625Y1110597I-1055J1069D01*
G03X440248Y1111592I-1502J0D01*
G01X440215Y1111630D01*
X440192Y1111726D01*
X440299Y1112144D01*
X440366Y1112217D01*
X440413Y1112234D01*
G03X441410Y1113648I-504J1414D01*
G03X441337Y1114110I-1502J-1D01*
G01X441324Y1114151D01*
X441333Y1114236D01*
X441530Y1114569D01*
X441600Y1114618D01*
X441642Y1114626D01*
G03X442861Y1116101I-283J1475D01*
G03X442417Y1117167I-1502J0D01*
G01X442388Y1117195D01*
X442358Y1117269D01*
Y1117633D01*
X442388Y1117707D01*
X442417Y1117735D01*
G03X442861Y1118801I-1058J1066D01*
G03X439857I-1502J0D01*
G03X440301Y1117735I1502J0D01*
G01X440330Y1117707D01*
X440360Y1117633D01*
Y1117269D01*
X440330Y1117195D01*
X440301Y1117167D01*
G03X439857Y1116101I1058J-1066D01*
G03X439930Y1115639I1502J1D01*
G01X439943Y1115598D01*
X439934Y1115513D01*
X439737Y1115180D01*
X439667Y1115131D01*
X439625Y1115123D01*
G03X438433Y1113929I283J-1475D01*
G01X438423Y1113881D01*
X438361Y1113803D01*
X437967Y1113632D01*
X437868Y1113640D01*
X437826Y1113666D01*
G03X437023Y1113899I-803J-1269D01*
G03X436741Y1113872I2J-1502D01*
G01X436704Y1113865D01*
X436629Y1113880D01*
X436333Y1114068D01*
X436288Y1114130D01*
X436279Y1114167D01*
G03X434823Y1115299I-1456J-370D01*
G03X433321Y1113797I0J-1502D01*
G03X433327Y1113660I1502J-3D01*
G01X433333Y1113597D01*
X433270Y1113488D01*
X432872Y1113301D01*
G02X432646Y1113341I-84J181D01*
G01X432065Y1113923D01*
G02X432008Y1114095I141J142D01*
G01X432066Y1114462D01*
X432121Y1114539D01*
X432164Y1114561D01*
G03X432978Y1115883I-688J1335D01*
G01Y1115897D01*
G03X432702Y1116766I-1502J1D01*
G01X432700Y1116768D01*
X432698Y1116771D01*
X432690Y1116782D01*
X432673Y1116816D01*
G02X432652Y1116905I179J89D01*
G01Y1116922D01*
X432662Y1117037D01*
G02X432719Y1117162I199J-15D01*
G01X432745Y1117188D01*
X434454Y1118898D01*
G03X434968Y1120136I-1237J1239D01*
G01Y1147669D01*
G02X434969Y1147688I200J-1D01*
G02X435027Y1147811I199J-19D01*
G01X435457Y1148241D01*
G02X435580Y1148299I142J-141D01*
G01X435590Y1148300D01*
G37*
G36*
G01X467726D02*
X496502D01*
G02X496504Y1148299I-84J-171D01*
G01X496993Y1147810D01*
G02X497052Y1147669I-141J-142D01*
G01Y1133083D01*
G02X496993Y1132942I-200J1D01*
G01X494875Y1130824D01*
X494829Y1130798D01*
X494802Y1130791D01*
G03X493484Y1129094I433J-1697D01*
G03X495236Y1127342I1752J0D01*
G01X495622D01*
G03X496276Y1127469I-1J1752D01*
G01X496323Y1127488D01*
X496421Y1127478D01*
X496737Y1127264D01*
G02X496826Y1127098I-111J-166D01*
G01Y1126831D01*
G02X496767Y1126690I-200J1D01*
G01X490679Y1120603D01*
G03X490122Y1119258I1345J-1345D01*
G01Y1113647D01*
G02X490064Y1113506I-200J0D01*
G01X489449Y1112891D01*
G02X489308Y1112832I-142J141D01*
G01X482023D01*
G02X481867Y1112907I0J200D01*
G01X481643Y1113187D01*
X481623Y1113275D01*
X481633Y1113320D01*
G03X481669Y1113648I-1466J327D01*
G03X480167Y1115150I-1502J0D01*
G03X479180Y1114780I0J-1501D01*
G01X479152Y1114756D01*
X479085Y1114731D01*
X478749D01*
X478682Y1114756D01*
X478654Y1114780D01*
G03X477667Y1115150I-987J-1131D01*
G03Y1112146I0J-1502D01*
G03X478654Y1112516I0J1501D01*
G01X478682Y1112540D01*
X478749Y1112565D01*
X479085D01*
X479152Y1112540D01*
X479180Y1112516D01*
G03X479569Y1112270I988J1131D01*
G01X479615Y1112250D01*
X479676Y1112173D01*
X479747Y1111799D01*
G02X479692Y1111621I-196J-37D01*
G01X475153Y1107081D01*
G02X475012Y1107022I-142J141D01*
G01X474295D01*
G02X474134Y1107104I1J200D01*
G01X473915Y1107404D01*
X473899Y1107497D01*
X473914Y1107543D01*
G03X473984Y1107997I-1432J453D01*
G03X473616Y1108982I-1502J0D01*
G01X473591Y1109011D01*
X473566Y1109081D01*
X473580Y1109433D01*
X473610Y1109501D01*
X473637Y1109528D01*
G03X474084Y1110597I-1055J1069D01*
G03X473707Y1111592I-1502J0D01*
G01X473674Y1111630D01*
X473651Y1111726D01*
X473758Y1112144D01*
X473825Y1112217D01*
X473872Y1112234D01*
G03X474869Y1113648I-504J1414D01*
G03X474796Y1114110I-1502J-1D01*
G01X474783Y1114151D01*
X474792Y1114236D01*
X474989Y1114569D01*
X475059Y1114618D01*
X475101Y1114626D01*
G03X476320Y1116101I-283J1475D01*
G03X475876Y1117167I-1502J0D01*
G01X475847Y1117195D01*
X475817Y1117269D01*
Y1117633D01*
X475847Y1117707D01*
X475876Y1117735D01*
G03X476320Y1118801I-1058J1066D01*
G03X473316I-1502J0D01*
G03X473760Y1117735I1502J0D01*
G01X473789Y1117707D01*
X473819Y1117633D01*
Y1117269D01*
X473789Y1117195D01*
X473760Y1117167D01*
G03X473316Y1116101I1058J-1066D01*
G03X473389Y1115639I1502J1D01*
G01X473402Y1115598D01*
X473393Y1115513D01*
X473196Y1115180D01*
X473126Y1115131D01*
X473084Y1115123D01*
G03X471892Y1113929I283J-1475D01*
G01X471882Y1113881D01*
X471820Y1113803D01*
X471426Y1113632D01*
X471327Y1113640D01*
X471285Y1113666D01*
G03X470482Y1113899I-803J-1269D01*
G03X470200Y1113872I2J-1502D01*
G01X470163Y1113865D01*
X470088Y1113880D01*
X469792Y1114068D01*
X469747Y1114130D01*
X469738Y1114167D01*
G03X468282Y1115299I-1456J-370D01*
G03X466780Y1113797I0J-1502D01*
G03X467310Y1112652I1502J0D01*
G02X467381Y1112499I-129J-153D01*
G01Y1112195D01*
G02X467310Y1112042I-200J0D01*
G03X466905Y1111497I972J-1145D01*
G01X466885Y1111452D01*
X466808Y1111390D01*
X466434Y1111319D01*
G02X466256Y1111374I-37J197D01*
G01X463599Y1114032D01*
G03X463576Y1114054I-1326J-1363D01*
G02X463702Y1114397I139J144D01*
G03X465106Y1115883I-98J1499D01*
G01Y1115897D01*
G03X464830Y1116766I-1502J1D01*
G01X464828Y1116768D01*
X464826Y1116771D01*
X464818Y1116782D01*
X464801Y1116816D01*
G02X464780Y1116905I179J89D01*
G01Y1116922D01*
X464790Y1117037D01*
G02X464847Y1117162I199J-15D01*
G01X464873Y1117188D01*
X466582Y1118898D01*
G03X467096Y1120136I-1237J1239D01*
G01Y1147669D01*
G02X467097Y1147688I200J-1D01*
G02X467155Y1147811I199J-19D01*
G01X467160Y1147816D01*
X467585Y1148242D01*
G02X467726Y1148300I141J-142D01*
G37*
G36*
G01X652824Y1216897D02*
X652788Y1216861D01*
G02X652786Y1216859I-142J140D01*
G01X652730Y1216804D01*
G02X652675Y1216769I-133J149D01*
G01X652642Y1216755D01*
X652604Y1216753D01*
X652603D01*
G03X652568Y1214153I53J-1301D01*
G01X652572D01*
X652605Y1214150D01*
X652660Y1214127D01*
G02X652664Y1214125I-87J-180D01*
G01X652716Y1214102D01*
G02X652750Y1214078I-98J-174D01*
G01X652822Y1214009D01*
G02X652882Y1213866I-140J-143D01*
G01Y1213298D01*
G02X652846Y1213184I-200J0D01*
G02X652824Y1213157I-165J112D01*
G01X652788Y1213121D01*
G02X652786Y1213119I-142J140D01*
G01X652730Y1213064D01*
G02X652675Y1213029I-133J149D01*
G01X652642Y1213015D01*
X652604Y1213013D01*
X652603D01*
G03X652568Y1210413I53J-1301D01*
G01X652572D01*
X652605Y1210410D01*
X652660Y1210387D01*
G02X652664Y1210385I-87J-180D01*
G01X652716Y1210362D01*
G02X652750Y1210338I-98J-174D01*
G01X652822Y1210269D01*
G02X652882Y1210126I-140J-143D01*
G01Y1209558D01*
G02X652846Y1209444I-200J0D01*
G02X652824Y1209417I-165J112D01*
G01X652788Y1209381D01*
G02X652786Y1209379I-142J140D01*
G01X652730Y1209324D01*
G02X652675Y1209289I-133J149D01*
G01X652642Y1209275D01*
X652604Y1209273D01*
X652603D01*
G03X652568Y1206673I53J-1301D01*
G01X652572D01*
X652605Y1206670D01*
X652660Y1206647D01*
G02X652664Y1206645I-87J-180D01*
G01X652716Y1206622D01*
G02X652750Y1206598I-98J-174D01*
G01X652822Y1206529D01*
G02X652882Y1206386I-140J-143D01*
G01Y1205818D01*
G02X652846Y1205704I-200J0D01*
G02X652824Y1205677I-165J112D01*
G01X652788Y1205641D01*
G02X652786Y1205639I-142J140D01*
G01X652730Y1205584D01*
G02X652675Y1205549I-133J149D01*
G01X652642Y1205535D01*
X652604Y1205533D01*
X652603D01*
G03X652568Y1202933I53J-1301D01*
G01X652572D01*
X652605Y1202930D01*
X652660Y1202907D01*
G02X652664Y1202905I-87J-180D01*
G01X652716Y1202882D01*
G02X652750Y1202858I-98J-174D01*
G01X652822Y1202789D01*
G02X652882Y1202646I-140J-143D01*
G01Y1202077D01*
G02X652846Y1201963I-200J0D01*
G02X652824Y1201936I-165J112D01*
G01X652788Y1201900D01*
G02X652786Y1201898I-142J140D01*
G01X652730Y1201843D01*
G02X652675Y1201808I-133J149D01*
G01X652642Y1201794D01*
X652604Y1201792D01*
X652603D01*
G03X651354Y1200491I53J-1301D01*
G03X652656Y1199189I1302J0D01*
G01X652657D01*
G03X653466Y1199471I0J1303D01*
G01X653491Y1199491D01*
X653581Y1199524D01*
G02X653585Y1199526I91J-176D01*
G03X653589Y1199527I-46J194D01*
G02X653612Y1199533I62J-191D01*
G02X653659Y1199536I36J-197D01*
G01X653908Y1199524D01*
G02X654029Y1199467I-20J-199D01*
G01X655325Y1198171D01*
G03X655410Y1198120I142J141D01*
G01X655425Y1198116D01*
G02X655482Y1198082I-73J-187D01*
G01X655557Y1198004D01*
G02X655549Y1197740I-154J-127D01*
G01X655531Y1197722D01*
G03X655095Y1196751I863J-971D01*
G03X657699I1302J0D01*
G01Y1196752D01*
G03X657472Y1197487I-1302J0D01*
G01X657462Y1197501D01*
G02X657456Y1197512I173J101D01*
G01Y1197514D01*
G02Y1197686I180J86D01*
G01X657579Y1197916D01*
Y1197918D01*
X657618Y1197991D01*
X657634Y1198021D01*
G02X657688Y1198077I168J-108D01*
G01X657696Y1198082D01*
X657926D01*
G02X657977Y1198076I2J-200D01*
G01X658002Y1198069D01*
Y1198046D01*
X658881D01*
G02X658908Y1198008I-148J-134D01*
G01X658976Y1197878D01*
X659082Y1197678D01*
G02X659069Y1197497I-184J-78D01*
G01X659061Y1197485D01*
G03X659049Y1197467I1077J-731D01*
G03X659047Y1197465I140J-142D01*
G03X658835Y1196755I1090J-712D01*
G03Y1196753I1302J-1D01*
G01Y1196751D01*
G03X661439I1302J0D01*
G01Y1196752D01*
G03X661212Y1197487I-1302J0D01*
G01X661202Y1197501D01*
G02X661196Y1197512I173J101D01*
G01Y1197514D01*
G02Y1197686I180J86D01*
G01X661319Y1197916D01*
Y1197918D01*
X661358Y1197991D01*
X661374Y1198021D01*
G02X661428Y1198077I168J-108D01*
G01X661436Y1198082D01*
X661666D01*
G02X661717Y1198076I2J-200D01*
G01X661742Y1198069D01*
Y1198046D01*
X662621D01*
G02X662648Y1198008I-148J-134D01*
G01X662716Y1197878D01*
X662822Y1197678D01*
G02X662809Y1197497I-184J-78D01*
G01X662801Y1197485D01*
G03X662789Y1197467I1077J-731D01*
G03X662787Y1197465I140J-142D01*
G03X662575Y1196755I1090J-712D01*
G03Y1196753I1302J-1D01*
G01Y1196751D01*
G03X665179I1302J0D01*
G01Y1196752D01*
G03X664952Y1197487I-1302J0D01*
G01X664942Y1197501D01*
G02X664936Y1197512I173J101D01*
G01Y1197514D01*
G02Y1197686I180J86D01*
G01X665059Y1197916D01*
Y1197918D01*
X665098Y1197991D01*
X665114Y1198021D01*
G02X665168Y1198077I168J-108D01*
G01X665176Y1198082D01*
X665406D01*
G02X665457Y1198076I2J-200D01*
G01X665482Y1198069D01*
Y1198046D01*
X666361D01*
G02X666388Y1198008I-148J-134D01*
G01X666456Y1197878D01*
X666562Y1197678D01*
G02X666549Y1197497I-184J-78D01*
G01X666541Y1197485D01*
G03X666529Y1197467I1077J-731D01*
G03X666527Y1197465I140J-142D01*
G03X666315Y1196755I1090J-712D01*
G03Y1196753I1302J-1D01*
G01Y1196751D01*
G03X668919I1302J0D01*
G01Y1196752D01*
G03X668692Y1197487I-1302J0D01*
G01X668682Y1197501D01*
G02X668676Y1197512I173J101D01*
G01Y1197514D01*
G02Y1197686I180J86D01*
G01X668799Y1197916D01*
Y1197918D01*
X668838Y1197991D01*
X668854Y1198021D01*
G02X668908Y1198077I168J-108D01*
G01X668916Y1198082D01*
X669146D01*
G02X669197Y1198076I2J-200D01*
G01X669222Y1198069D01*
Y1198046D01*
X670101D01*
G02X670128Y1198008I-148J-134D01*
G01X670196Y1197878D01*
X670302Y1197678D01*
G02X670289Y1197497I-184J-78D01*
G01X670281Y1197485D01*
G03X670269Y1197467I1077J-731D01*
G03X670267Y1197465I140J-142D01*
G03X670055Y1196755I1090J-712D01*
G03Y1196753I1302J-1D01*
G01Y1196751D01*
G03X672659I1302J0D01*
G01Y1196752D01*
G03X672432Y1197487I-1302J0D01*
G01X672422Y1197501D01*
G02X672416Y1197512I173J101D01*
G01Y1197514D01*
G02Y1197686I180J86D01*
G01X672539Y1197916D01*
Y1197918D01*
X672578Y1197991D01*
X672594Y1198021D01*
G02X672648Y1198077I168J-108D01*
G01X672656Y1198082D01*
X672886D01*
G02X672937Y1198076I2J-200D01*
G01X672962Y1198069D01*
Y1198046D01*
X673841D01*
G02X673868Y1198008I-148J-134D01*
G01X673936Y1197878D01*
X674042Y1197678D01*
G02X674029Y1197497I-184J-78D01*
G01X674021Y1197485D01*
G03X674009Y1197467I1077J-731D01*
G03X674007Y1197465I140J-142D01*
G03X673795Y1196755I1090J-712D01*
G03Y1196753I1302J-1D01*
G01Y1196751D01*
G03X676399I1302J0D01*
G01Y1196752D01*
G03X676172Y1197487I-1302J0D01*
G01X676162Y1197501D01*
G02X676156Y1197512I173J101D01*
G01Y1197514D01*
G02Y1197686I180J86D01*
G01X676279Y1197916D01*
Y1197918D01*
X676318Y1197991D01*
X676334Y1198021D01*
G02X676388Y1198077I168J-108D01*
G01X676396Y1198082D01*
X676626D01*
G02X676677Y1198076I2J-200D01*
G01X676702Y1198069D01*
Y1198046D01*
X677581D01*
G02X677608Y1198008I-148J-134D01*
G01X677676Y1197878D01*
X677782Y1197678D01*
G02X677769Y1197497I-184J-78D01*
G01X677761Y1197485D01*
G03X677749Y1197467I1077J-731D01*
G03X677747Y1197465I140J-142D01*
G03X677535Y1196755I1090J-712D01*
G03Y1196753I1302J-1D01*
G01Y1196751D01*
G03X680139I1302J0D01*
G01Y1196752D01*
G03X679912Y1197487I-1302J0D01*
G01X679902Y1197501D01*
G02X679896Y1197512I173J101D01*
G01Y1197514D01*
G02Y1197686I180J86D01*
G01X680019Y1197916D01*
Y1197918D01*
X680058Y1197991D01*
X680074Y1198021D01*
G02X680128Y1198077I168J-108D01*
G01X680136Y1198082D01*
X680366D01*
G02X680417Y1198076I2J-200D01*
G01X680442Y1198069D01*
Y1198046D01*
X681322D01*
G02X681349Y1198008I-148J-134D01*
G01X681417Y1197878D01*
X681523Y1197678D01*
G02X681510Y1197497I-184J-78D01*
G01X681502Y1197485D01*
G03X681490Y1197467I1077J-731D01*
G03X681488Y1197465I140J-142D01*
G03X681276Y1196755I1090J-712D01*
G03Y1196753I1302J-1D01*
G01Y1196751D01*
G03X683880I1302J0D01*
G01Y1196752D01*
G03X683653Y1197487I-1302J0D01*
G01X683643Y1197501D01*
G02X683637Y1197512I173J101D01*
G01Y1197514D01*
G02Y1197686I180J86D01*
G01X683760Y1197916D01*
Y1197918D01*
X683799Y1197991D01*
X683815Y1198021D01*
G02X683869Y1198077I168J-108D01*
G01X683877Y1198082D01*
X684107D01*
G02X684158Y1198076I2J-200D01*
G01X684183Y1198069D01*
Y1198046D01*
X685062D01*
G02X685089Y1198008I-148J-134D01*
G01X685157Y1197878D01*
X685263Y1197678D01*
G02X685250Y1197497I-184J-78D01*
G01X685242Y1197485D01*
G03X685230Y1197467I1077J-731D01*
G03X685228Y1197465I140J-142D01*
G03X685016Y1196755I1090J-712D01*
G03Y1196753I1302J-1D01*
G01Y1196751D01*
G03X687620I1302J0D01*
G01Y1196752D01*
G03X687393Y1197487I-1302J0D01*
G01X687383Y1197501D01*
G02X687377Y1197512I173J101D01*
G01Y1197514D01*
G02Y1197686I180J86D01*
G01X687500Y1197916D01*
Y1197918D01*
X687539Y1197991D01*
X687555Y1198021D01*
G02X687609Y1198077I168J-108D01*
G01X687617Y1198082D01*
X687847D01*
G02X687898Y1198076I2J-200D01*
G01X687923Y1198069D01*
Y1198046D01*
X692542D01*
G02X692569Y1198008I-148J-134D01*
G01X692637Y1197878D01*
X692743Y1197678D01*
G02X692730Y1197497I-184J-78D01*
G01X692722Y1197485D01*
G03X692710Y1197467I1077J-731D01*
G03X692708Y1197465I140J-142D01*
G03X692496Y1196755I1090J-712D01*
G03Y1196753I1302J-1D01*
G01Y1196751D01*
G03X695100I1302J0D01*
G01Y1196752D01*
G03X694873Y1197487I-1302J0D01*
G01X694863Y1197501D01*
G02X694857Y1197512I173J101D01*
G01Y1197514D01*
G02Y1197686I180J86D01*
G01X694980Y1197916D01*
Y1197918D01*
X695019Y1197991D01*
X695035Y1198021D01*
G02X695089Y1198077I168J-108D01*
G01X695097Y1198082D01*
X695327D01*
G02X695378Y1198076I2J-200D01*
G01X695403Y1198069D01*
Y1198046D01*
X696282D01*
G02X696309Y1198008I-148J-134D01*
G01X696377Y1197878D01*
X696483Y1197678D01*
G02X696470Y1197497I-184J-78D01*
G01X696462Y1197485D01*
G03X696450Y1197467I1077J-731D01*
G03X696448Y1197465I140J-142D01*
G03X696236Y1196755I1090J-712D01*
G03Y1196753I1302J-1D01*
G01Y1196751D01*
G03X698840I1302J0D01*
G01Y1196752D01*
G03X698613Y1197487I-1302J0D01*
G01X698603Y1197501D01*
G02X698597Y1197512I173J101D01*
G01Y1197514D01*
G02Y1197686I180J86D01*
G01X698720Y1197916D01*
Y1197918D01*
X698759Y1197991D01*
X698775Y1198021D01*
G02X698829Y1198077I168J-108D01*
G01X698837Y1198082D01*
X699067D01*
G02X699118Y1198076I2J-200D01*
G01X699143Y1198069D01*
Y1198046D01*
X700022D01*
G02X700049Y1198008I-148J-134D01*
G01X700117Y1197878D01*
X700223Y1197678D01*
G02X700210Y1197497I-184J-78D01*
G01X700202Y1197485D01*
G03X700190Y1197467I1077J-731D01*
G03X700188Y1197465I140J-142D01*
G03X699976Y1196755I1090J-712D01*
G03Y1196753I1302J-1D01*
G01Y1196751D01*
G03X702580I1302J0D01*
G01Y1196752D01*
G03X702353Y1197487I-1302J0D01*
G01X702343Y1197501D01*
G02X702337Y1197512I173J101D01*
G01Y1197514D01*
G02Y1197686I180J86D01*
G01X702460Y1197916D01*
Y1197918D01*
X702499Y1197991D01*
X702515Y1198021D01*
G02X702569Y1198077I168J-108D01*
G01X702577Y1198082D01*
X702807D01*
G02X702858Y1198076I2J-200D01*
G01X702883Y1198069D01*
Y1198046D01*
X703763D01*
G02X703790Y1198008I-148J-134D01*
G01X703858Y1197878D01*
X703964Y1197678D01*
G02X703951Y1197497I-184J-78D01*
G01X703943Y1197485D01*
G03X703931Y1197467I1077J-731D01*
G03X703929Y1197465I140J-142D01*
G03X703717Y1196755I1090J-712D01*
G03Y1196753I1302J-1D01*
G01Y1196751D01*
G03X706321I1302J0D01*
G01Y1196752D01*
G03X706094Y1197487I-1302J0D01*
G01X706084Y1197501D01*
G02X706078Y1197512I173J101D01*
G01Y1197514D01*
G02Y1197686I180J86D01*
G01X706201Y1197916D01*
Y1197918D01*
X706240Y1197991D01*
X706256Y1198021D01*
G02X706310Y1198077I168J-108D01*
G01X706318Y1198082D01*
X706548D01*
G02X706599Y1198076I2J-200D01*
G01X706624Y1198069D01*
Y1198046D01*
X707503D01*
G02X707530Y1198008I-148J-134D01*
G01X707598Y1197878D01*
X707704Y1197678D01*
G02X707691Y1197497I-184J-78D01*
G01X707683Y1197485D01*
G03X707671Y1197467I1077J-731D01*
G03X707669Y1197465I140J-142D01*
G03X707457Y1196755I1090J-712D01*
G03Y1196753I1302J-1D01*
G01Y1196751D01*
G03X710061I1302J0D01*
G01Y1196752D01*
G03X709834Y1197487I-1302J0D01*
G01X709824Y1197501D01*
G02X709818Y1197512I173J101D01*
G01Y1197514D01*
G02Y1197686I180J86D01*
G01X709941Y1197916D01*
Y1197918D01*
X709980Y1197991D01*
X709996Y1198021D01*
G02X710050Y1198077I168J-108D01*
G01X710058Y1198082D01*
X710288D01*
G02X710339Y1198076I2J-200D01*
G01X710364Y1198069D01*
Y1198046D01*
X711243D01*
G02X711270Y1198008I-148J-134D01*
G01X711338Y1197878D01*
X711444Y1197678D01*
G02X711431Y1197497I-184J-78D01*
G01X711423Y1197485D01*
G03X711411Y1197467I1077J-731D01*
G03X711409Y1197465I140J-142D01*
G03X711197Y1196755I1090J-712D01*
G03Y1196753I1302J-1D01*
G01Y1196751D01*
G03X713801I1302J0D01*
G01Y1196752D01*
G03X713574Y1197487I-1302J0D01*
G01X713564Y1197501D01*
G02X713558Y1197512I173J101D01*
G01Y1197514D01*
G02Y1197686I180J86D01*
G01X713681Y1197916D01*
Y1197918D01*
X713720Y1197991D01*
X713736Y1198021D01*
G02X713790Y1198077I168J-108D01*
G01X713798Y1198082D01*
X714028D01*
G02X714079Y1198076I2J-200D01*
G01X714104Y1198069D01*
Y1198046D01*
X714983D01*
G02X715010Y1198008I-148J-134D01*
G01X715078Y1197878D01*
X715184Y1197678D01*
G02X715171Y1197497I-184J-78D01*
G01X715163Y1197485D01*
G03X715151Y1197467I1077J-731D01*
G03X715149Y1197465I140J-142D01*
G03X714937Y1196755I1090J-712D01*
G03Y1196753I1302J-1D01*
G01Y1196751D01*
G03X717541I1302J0D01*
G01Y1196752D01*
G03X717314Y1197487I-1302J0D01*
G01X717304Y1197501D01*
G02X717298Y1197512I173J101D01*
G01Y1197514D01*
G02Y1197686I180J86D01*
G01X717421Y1197916D01*
Y1197918D01*
X717460Y1197991D01*
X717476Y1198021D01*
G02X717530Y1198077I168J-108D01*
G01X717538Y1198082D01*
X717768D01*
G02X717819Y1198076I2J-200D01*
G01X717844Y1198069D01*
Y1198046D01*
X718723D01*
G02X718750Y1198008I-148J-134D01*
G01X718818Y1197878D01*
X718924Y1197678D01*
G02X718911Y1197497I-184J-78D01*
G01X718903Y1197485D01*
G03X718891Y1197467I1077J-731D01*
G03X718889Y1197465I140J-142D01*
G03X718677Y1196755I1090J-712D01*
G03Y1196753I1302J-1D01*
G01Y1196751D01*
G03X721281I1302J0D01*
G01Y1196752D01*
G03X721054Y1197487I-1302J0D01*
G01X721044Y1197501D01*
G02X721038Y1197512I173J101D01*
G01Y1197514D01*
G02Y1197686I180J86D01*
G01X721161Y1197916D01*
Y1197918D01*
X721200Y1197991D01*
X721216Y1198021D01*
G02X721270Y1198077I168J-108D01*
G01X721278Y1198082D01*
X721508D01*
G02X721559Y1198076I2J-200D01*
G01X721584Y1198069D01*
Y1198046D01*
X722463D01*
G02X722490Y1198008I-148J-134D01*
G01X722558Y1197878D01*
X722664Y1197678D01*
G02X722651Y1197497I-184J-78D01*
G01X722643Y1197485D01*
G03X722631Y1197467I1077J-731D01*
G03X722629Y1197465I140J-142D01*
G03X722417Y1196755I1090J-712D01*
G03Y1196753I1302J-1D01*
G01Y1196751D01*
G03X725021I1302J0D01*
G01Y1196752D01*
G03X724794Y1197487I-1302J0D01*
G01X724784Y1197501D01*
G02X724778Y1197512I173J101D01*
G01Y1197514D01*
G02Y1197686I180J86D01*
G01X724901Y1197916D01*
Y1197918D01*
X724940Y1197991D01*
X724956Y1198021D01*
G02X725010Y1198077I168J-108D01*
G01X725018Y1198082D01*
X725248D01*
G02X725299Y1198076I2J-200D01*
G01X725324Y1198069D01*
Y1198046D01*
X725826D01*
G02X725933Y1198015I0J-200D01*
G03X726008Y1197971I679J1071D01*
G01X726034Y1197957D01*
X726338Y1197653D01*
G02X726362Y1197624I-141J-141D01*
G02X726396Y1197530I-165J-113D01*
G01X726399Y1197493D01*
X726381Y1197430D01*
X726367Y1197407D01*
G03X726177Y1196732I1111J-677D01*
G03X727478Y1195430I1302J0D01*
G01X727480D01*
G03X727581Y1195433I12J1302D01*
G01X727596Y1195434D01*
G02X727725Y1195386I-1J-200D01*
G01X727862Y1195260D01*
X727946Y1195182D01*
G02X728010Y1195036I-136J-147D01*
G01Y1194706D01*
G02X727953Y1194567I-200J1D01*
G01X727727Y1194359D01*
G02X727657Y1194317I-136J147D01*
G01X727618Y1194304D01*
X727575Y1194308D01*
G03X727459Y1194313I-114J-1297D01*
G03Y1191709I0J-1302D01*
G03X727575Y1191714I2J1302D01*
G01X727618Y1191718D01*
X727657Y1191705D01*
G02X727727Y1191663I-66J-189D01*
G01X727945Y1191463D01*
G02X728010Y1191316I-135J-148D01*
G01Y1190966D01*
G02X727953Y1190827I-200J1D01*
G01X727727Y1190619D01*
G02X727657Y1190577I-136J147D01*
G01X727618Y1190564D01*
X727575Y1190568D01*
G03X727459Y1190573I-114J-1297D01*
G03Y1187969I0J-1302D01*
G03X727575Y1187974I2J1302D01*
G01X727618Y1187978D01*
X727657Y1187965D01*
G02X727727Y1187923I-66J-189D01*
G01X727945Y1187723D01*
G02X728010Y1187576I-135J-148D01*
G01Y1187226D01*
G02X727953Y1187087I-200J1D01*
G01X727727Y1186879D01*
G02X727657Y1186837I-136J147D01*
G01X727618Y1186824D01*
X727575Y1186828D01*
G03X727459Y1186833I-114J-1297D01*
G03Y1184229I0J-1302D01*
G03X727575Y1184234I2J1302D01*
G01X727618Y1184238D01*
X727657Y1184225D01*
G02X727727Y1184183I-66J-189D01*
G01X727945Y1183983D01*
G02X728010Y1183836I-135J-148D01*
G01Y1183486D01*
G02X727953Y1183347I-200J1D01*
G01X727727Y1183139D01*
G02X727657Y1183097I-136J147D01*
G01X727618Y1183084D01*
X727575Y1183088D01*
G03X727459Y1183093I-114J-1297D01*
G03Y1180489I0J-1302D01*
G03X727575Y1180494I2J1302D01*
G01X727618Y1180498D01*
X727657Y1180485D01*
G02X727727Y1180443I-66J-189D01*
G01X727945Y1180243D01*
G02X728010Y1180096I-135J-148D01*
G01Y1179746D01*
G02X727953Y1179607I-200J1D01*
G01X727727Y1179399D01*
G02X727657Y1179357I-136J147D01*
G01X727618Y1179344D01*
X727575Y1179348D01*
G03X727459Y1179353I-114J-1297D01*
G03Y1176749I0J-1302D01*
G03X727575Y1176754I2J1302D01*
G01X727618Y1176758D01*
X727657Y1176745D01*
G02X727727Y1176703I-66J-189D01*
G01X727945Y1176503D01*
G02X728010Y1176356I-135J-148D01*
G01Y1176005D01*
G02X727953Y1175866I-200J1D01*
G01X727727Y1175658D01*
G02X727657Y1175616I-136J147D01*
G01X727618Y1175603D01*
X727575Y1175607D01*
G03X727459Y1175612I-114J-1297D01*
G03Y1173008I0J-1302D01*
G03X727575Y1173013I2J1302D01*
G01X727618Y1173017D01*
X727657Y1173004D01*
G02X727727Y1172962I-66J-189D01*
G01X727945Y1172762D01*
G02X728010Y1172615I-135J-148D01*
G01Y1172265D01*
G02X727953Y1172126I-200J1D01*
G01X727727Y1171918D01*
G02X727657Y1171876I-136J147D01*
G01X727618Y1171863D01*
X727575Y1171867D01*
G03X727459Y1171872I-114J-1297D01*
G03Y1169268I0J-1302D01*
G03X727575Y1169273I2J1302D01*
G01X727618Y1169277D01*
X727657Y1169264D01*
G02X727727Y1169222I-66J-189D01*
G01X727945Y1169022D01*
G02X728010Y1168875I-135J-148D01*
G01Y1168525D01*
G02X727953Y1168386I-200J1D01*
G01X727727Y1168178D01*
G02X727657Y1168136I-136J147D01*
G01X727618Y1168123D01*
X727575Y1168127D01*
G03X727459Y1168132I-114J-1297D01*
G03Y1165528I0J-1302D01*
G03X727575Y1165533I2J1302D01*
G01X727618Y1165537D01*
X727657Y1165524D01*
G02X727727Y1165482I-66J-189D01*
G01X727945Y1165282D01*
G02X728010Y1165135I-135J-148D01*
G01Y1161045D01*
G02X727953Y1160906I-200J1D01*
G01X727727Y1160698D01*
G02X727657Y1160656I-136J147D01*
G01X727618Y1160643D01*
X727575Y1160647D01*
G03X727459Y1160652I-114J-1297D01*
G03Y1158048I0J-1302D01*
G03X727575Y1158053I2J1302D01*
G01X727618Y1158057D01*
X727657Y1158044D01*
G02X727727Y1158002I-66J-189D01*
G01X727945Y1157802D01*
G02X728010Y1157655I-135J-148D01*
G01Y1157305D01*
G02X727953Y1157166I-200J1D01*
G01X727727Y1156958D01*
G02X727657Y1156916I-136J147D01*
G01X727618Y1156903D01*
X727575Y1156907D01*
G03X727459Y1156912I-114J-1297D01*
G03Y1154308I0J-1302D01*
G03X727575Y1154313I2J1302D01*
G01X727618Y1154317D01*
X727657Y1154304D01*
G02X727727Y1154262I-66J-189D01*
G01X727945Y1154062D01*
G02X728010Y1153915I-135J-148D01*
G01Y1153564D01*
G02X727953Y1153425I-200J1D01*
G01X727727Y1153217D01*
G02X727657Y1153175I-136J147D01*
G01X727618Y1153162D01*
X727575Y1153166D01*
G03X727459Y1153171I-114J-1297D01*
G03Y1150567I0J-1302D01*
G03X727575Y1150572I2J1302D01*
G01X727618Y1150576D01*
X727657Y1150563D01*
G02X727727Y1150521I-66J-189D01*
G01X727945Y1150321D01*
G02X728010Y1150174I-135J-148D01*
G01Y1149824D01*
G02X727953Y1149685I-200J1D01*
G01X727727Y1149477D01*
G02X727657Y1149435I-136J147D01*
G01X727618Y1149422D01*
X727575Y1149426D01*
G03X727459Y1149431I-114J-1297D01*
G03Y1146827I0J-1302D01*
G03X727575Y1146832I2J1302D01*
G01X727618Y1146836D01*
X727657Y1146823D01*
G02X727727Y1146781I-66J-189D01*
G01X727945Y1146581D01*
G02X728010Y1146434I-135J-148D01*
G01Y1146084D01*
G02X727953Y1145945I-200J1D01*
G01X727727Y1145737D01*
G02X727657Y1145695I-136J147D01*
G01X727618Y1145682D01*
X727575Y1145686D01*
G03X727459Y1145691I-114J-1297D01*
G03Y1143087I0J-1302D01*
G03X727575Y1143092I2J1302D01*
G01X727618Y1143096D01*
X727657Y1143083D01*
G02X727727Y1143041I-66J-189D01*
G01X727945Y1142841D01*
G02X728010Y1142694I-135J-148D01*
G01Y1142344D01*
G02X727953Y1142205I-200J1D01*
G01X727727Y1141997D01*
G02X727657Y1141955I-136J147D01*
G01X727618Y1141942D01*
X727575Y1141946D01*
G03X727459Y1141951I-114J-1297D01*
G03Y1139347I0J-1302D01*
G03X727575Y1139352I2J1302D01*
G01X727618Y1139356D01*
X727657Y1139343D01*
G02X727727Y1139301I-66J-189D01*
G01X727945Y1139101D01*
G02X728010Y1138954I-135J-148D01*
G01Y1138604D01*
G02X727953Y1138465I-200J1D01*
G01X727727Y1138257D01*
G02X727657Y1138215I-136J147D01*
G01X727618Y1138202D01*
X727575Y1138206D01*
G03X727459Y1138211I-114J-1297D01*
G03Y1135607I0J-1302D01*
G03X727575Y1135612I2J1302D01*
G01X727618Y1135616D01*
X727657Y1135603D01*
G02X727727Y1135561I-66J-189D01*
G01X727945Y1135361D01*
G02X728010Y1135214I-135J-148D01*
G01Y1134864D01*
G02X727953Y1134725I-200J1D01*
G01X727727Y1134517D01*
G02X727657Y1134475I-136J147D01*
G01X727618Y1134462D01*
X727575Y1134466D01*
G03X727459Y1134471I-114J-1297D01*
G03X726157Y1133169I0J-1302D01*
G03X726861Y1132012I1303J0D01*
G01X726889Y1131998D01*
X726918Y1131969D01*
G02X726911Y1131693I-148J-134D01*
G01X726847Y1131629D01*
G02X726780Y1131585I-141J142D01*
G01X726746Y1131571D01*
X726447D01*
X726433Y1131582D01*
X726100Y1131627D01*
G03X725927Y1131638I-167J-1257D01*
G01X724779D01*
G02X724749Y1131682I149J134D01*
G01X724605Y1132027D01*
X724596Y1132049D01*
G02X724593Y1132164I190J62D01*
G01X724600Y1132184D01*
X724610Y1132207D01*
X724615Y1132219D01*
X724618Y1132226D01*
X724644Y1132253D01*
X724645Y1132254D01*
G03X725021Y1133169I-925J915D01*
G03X722417I-1302J0D01*
G03X722793Y1132254I1301J0D01*
G01X722794Y1132253D01*
X722820Y1132226D01*
X722823Y1132219D01*
X722828Y1132207D01*
X722838Y1132184D01*
X722845Y1132164D01*
G02X722842Y1132049I-193J-53D01*
G01X722833Y1132027D01*
X722689Y1131682D01*
G02X722659Y1131638I-179J90D01*
G01X721039D01*
G02X721009Y1131682I149J134D01*
G01X720865Y1132027D01*
X720856Y1132049D01*
G02X720853Y1132164I190J62D01*
G01X720860Y1132184D01*
X720870Y1132207D01*
X720875Y1132219D01*
X720878Y1132226D01*
X720904Y1132253D01*
X720905Y1132254D01*
G03X721281Y1133169I-925J915D01*
G03X718677I-1302J0D01*
G03X719053Y1132254I1301J0D01*
G01X719054Y1132253D01*
X719080Y1132226D01*
X719083Y1132219D01*
X719088Y1132207D01*
X719098Y1132184D01*
X719105Y1132164D01*
G02X719102Y1132049I-193J-53D01*
G01X719093Y1132027D01*
X718949Y1131682D01*
G02X718919Y1131638I-179J90D01*
G01X717299D01*
G02X717269Y1131682I149J134D01*
G01X717125Y1132027D01*
X717116Y1132049D01*
G02X717113Y1132164I190J62D01*
G01X717120Y1132184D01*
X717130Y1132207D01*
X717135Y1132219D01*
X717138Y1132226D01*
X717164Y1132253D01*
X717165Y1132254D01*
G03X717541Y1133169I-925J915D01*
G03X714937I-1302J0D01*
G03X715313Y1132254I1301J0D01*
G01X715314Y1132253D01*
X715340Y1132226D01*
X715343Y1132219D01*
X715348Y1132207D01*
X715358Y1132184D01*
X715365Y1132164D01*
G02X715362Y1132049I-193J-53D01*
G01X715353Y1132027D01*
X715209Y1131682D01*
G02X715179Y1131638I-179J90D01*
G01X713559D01*
G02X713529Y1131682I149J134D01*
G01X713385Y1132027D01*
X713376Y1132049D01*
G02X713373Y1132164I190J62D01*
G01X713380Y1132184D01*
X713390Y1132207D01*
X713395Y1132219D01*
X713398Y1132226D01*
X713424Y1132253D01*
X713425Y1132254D01*
G03X713801Y1133169I-925J915D01*
G03X711197I-1302J0D01*
G03X711573Y1132254I1301J0D01*
G01X711574Y1132253D01*
X711600Y1132226D01*
X711603Y1132219D01*
X711608Y1132207D01*
X711618Y1132184D01*
X711625Y1132164D01*
G02X711622Y1132049I-193J-53D01*
G01X711613Y1132027D01*
X711469Y1131682D01*
G02X711439Y1131638I-179J90D01*
G01X709819D01*
G02X709789Y1131682I149J134D01*
G01X709645Y1132027D01*
X709636Y1132049D01*
G02X709633Y1132164I190J62D01*
G01X709640Y1132184D01*
X709650Y1132207D01*
X709655Y1132219D01*
X709658Y1132226D01*
X709684Y1132253D01*
X709685Y1132254D01*
G03X710061Y1133169I-925J915D01*
G03X707457I-1302J0D01*
G03X707833Y1132254I1301J0D01*
G01X707834Y1132253D01*
X707860Y1132226D01*
X707863Y1132219D01*
X707868Y1132207D01*
X707878Y1132184D01*
X707885Y1132164D01*
G02X707882Y1132049I-193J-53D01*
G01X707873Y1132027D01*
X707729Y1131682D01*
G02X707699Y1131638I-179J90D01*
G01X706079D01*
G02X706049Y1131682I149J134D01*
G01X705905Y1132027D01*
X705896Y1132049D01*
G02X705893Y1132164I190J62D01*
G01X705900Y1132184D01*
X705910Y1132207D01*
X705915Y1132219D01*
X705918Y1132226D01*
X705944Y1132253D01*
X705945Y1132254D01*
G03X706321Y1133169I-925J915D01*
G03X703717I-1302J0D01*
G03X704093Y1132254I1301J0D01*
G01X704094Y1132253D01*
X704120Y1132226D01*
X704123Y1132219D01*
X704128Y1132207D01*
X704138Y1132184D01*
X704145Y1132164D01*
G02X704142Y1132049I-193J-53D01*
G01X704133Y1132027D01*
X703989Y1131682D01*
G02X703959Y1131638I-179J90D01*
G01X702338D01*
G02X702308Y1131682I149J134D01*
G01X702164Y1132027D01*
X702155Y1132049D01*
G02X702152Y1132164I190J62D01*
G01X702159Y1132184D01*
X702169Y1132207D01*
X702174Y1132219D01*
X702177Y1132226D01*
X702203Y1132253D01*
X702204Y1132254D01*
G03X702580Y1133169I-925J915D01*
G03X699976I-1302J0D01*
G03X700352Y1132254I1301J0D01*
G01X700353Y1132253D01*
X700379Y1132226D01*
X700382Y1132219D01*
X700387Y1132207D01*
X700397Y1132184D01*
X700404Y1132164D01*
G02X700401Y1132049I-193J-53D01*
G01X700392Y1132027D01*
X700248Y1131682D01*
G02X700218Y1131638I-179J90D01*
G01X698598D01*
G02X698568Y1131682I149J134D01*
G01X698424Y1132027D01*
X698415Y1132049D01*
G02X698412Y1132164I190J62D01*
G01X698419Y1132184D01*
X698429Y1132207D01*
X698434Y1132219D01*
X698437Y1132226D01*
X698463Y1132253D01*
X698464Y1132254D01*
G03X698840Y1133169I-925J915D01*
G03X696236I-1302J0D01*
G03X696612Y1132254I1301J0D01*
G01X696613Y1132253D01*
X696639Y1132226D01*
X696642Y1132219D01*
X696647Y1132207D01*
X696657Y1132184D01*
X696664Y1132164D01*
G02X696661Y1132049I-193J-53D01*
G01X696652Y1132027D01*
X696508Y1131682D01*
G02X696478Y1131638I-179J90D01*
G01X687816D01*
G02X687803Y1131654I148J134D01*
G01X687707Y1131803D01*
X687612Y1131951D01*
G02X687601Y1131973I173J100D01*
G01Y1132136D01*
X687617Y1132174D01*
G03X687718Y1132676I-1201J503D01*
G01Y1132677D01*
G03X685114I-1302J0D01*
G01Y1132676D01*
G03X685231Y1132138I1302J1D01*
G01Y1132136D01*
G02X685222Y1131955I-182J-82D01*
G01X685215Y1131943D01*
X685197Y1131915D01*
X685196Y1131914D01*
X685029Y1131654D01*
G02X685016Y1131638I-161J118D01*
G01X683638D01*
G02X683608Y1131682I149J134D01*
G01X683464Y1132027D01*
X683455Y1132049D01*
G02X683452Y1132164I190J62D01*
G01X683459Y1132184D01*
X683469Y1132207D01*
X683474Y1132219D01*
X683477Y1132226D01*
X683503Y1132253D01*
X683504Y1132254D01*
G03X683880Y1133169I-925J915D01*
G03X681276I-1302J0D01*
G03X681652Y1132254I1301J0D01*
G01X681653Y1132253D01*
X681679Y1132226D01*
X681682Y1132219D01*
X681687Y1132207D01*
X681697Y1132184D01*
X681704Y1132164D01*
G02X681701Y1132049I-193J-53D01*
G01X681692Y1132027D01*
X681548Y1131682D01*
G02X681518Y1131638I-179J90D01*
G01X679897D01*
G02X679867Y1131682I149J134D01*
G01X679723Y1132027D01*
X679714Y1132049D01*
G02X679711Y1132164I190J62D01*
G01X679718Y1132184D01*
X679728Y1132207D01*
X679733Y1132219D01*
X679736Y1132226D01*
X679762Y1132253D01*
X679763Y1132254D01*
G03X680139Y1133169I-925J915D01*
G03X677535I-1302J0D01*
G03X677911Y1132254I1301J0D01*
G01X677912Y1132253D01*
X677938Y1132226D01*
X677941Y1132219D01*
X677946Y1132207D01*
X677956Y1132184D01*
X677963Y1132164D01*
G02X677960Y1132049I-193J-53D01*
G01X677951Y1132027D01*
X677807Y1131682D01*
G02X677777Y1131638I-179J90D01*
G01X676157D01*
G02X676127Y1131682I149J134D01*
G01X675983Y1132027D01*
X675974Y1132049D01*
G02X675971Y1132164I190J62D01*
G01X675978Y1132184D01*
X675988Y1132207D01*
X675993Y1132219D01*
X675996Y1132226D01*
X676022Y1132253D01*
X676023Y1132254D01*
G03X676399Y1133169I-925J915D01*
G03X673795I-1302J0D01*
G03X674171Y1132254I1301J0D01*
G01X674172Y1132253D01*
X674198Y1132226D01*
X674201Y1132219D01*
X674206Y1132207D01*
X674216Y1132184D01*
X674223Y1132164D01*
G02X674220Y1132049I-193J-53D01*
G01X674211Y1132027D01*
X674067Y1131682D01*
G02X674037Y1131638I-179J90D01*
G01X672417D01*
G02X672387Y1131682I149J134D01*
G01X672243Y1132027D01*
X672234Y1132049D01*
G02X672231Y1132164I190J62D01*
G01X672238Y1132184D01*
X672248Y1132207D01*
X672253Y1132219D01*
X672256Y1132226D01*
X672282Y1132253D01*
X672283Y1132254D01*
G03X672659Y1133169I-925J915D01*
G03X670055I-1302J0D01*
G03X670431Y1132254I1301J0D01*
G01X670432Y1132253D01*
X670458Y1132226D01*
X670461Y1132219D01*
X670466Y1132207D01*
X670476Y1132184D01*
X670483Y1132164D01*
G02X670480Y1132049I-193J-53D01*
G01X670471Y1132027D01*
X670327Y1131682D01*
G02X670297Y1131638I-179J90D01*
G01X668677D01*
G02X668647Y1131682I149J134D01*
G01X668503Y1132027D01*
X668494Y1132049D01*
G02X668491Y1132164I190J62D01*
G01X668498Y1132184D01*
X668508Y1132207D01*
X668513Y1132219D01*
X668516Y1132226D01*
X668542Y1132253D01*
X668543Y1132254D01*
G03X668919Y1133169I-925J915D01*
G03X666315I-1302J0D01*
G03X666691Y1132254I1301J0D01*
G01X666692Y1132253D01*
X666718Y1132226D01*
X666721Y1132219D01*
X666726Y1132207D01*
X666736Y1132184D01*
X666743Y1132164D01*
G02X666740Y1132049I-193J-53D01*
G01X666731Y1132027D01*
X666587Y1131682D01*
G02X666557Y1131638I-179J90D01*
G01X664937D01*
G02X664907Y1131682I149J134D01*
G01X664763Y1132027D01*
X664754Y1132049D01*
G02X664751Y1132164I190J62D01*
G01X664758Y1132184D01*
X664768Y1132207D01*
X664773Y1132219D01*
X664776Y1132226D01*
X664802Y1132253D01*
X664803Y1132254D01*
G03X665179Y1133169I-925J915D01*
G03X662575I-1302J0D01*
G03X662951Y1132254I1301J0D01*
G01X662952Y1132253D01*
X662978Y1132226D01*
X662981Y1132219D01*
X662986Y1132207D01*
X662996Y1132184D01*
X663003Y1132164D01*
G02X663000Y1132049I-193J-53D01*
G01X662991Y1132027D01*
X662847Y1131682D01*
G02X662817Y1131638I-179J90D01*
G01X661197D01*
G02X661167Y1131682I149J134D01*
G01X661023Y1132027D01*
X661014Y1132049D01*
G02X661011Y1132164I190J62D01*
G01X661018Y1132184D01*
X661028Y1132207D01*
X661033Y1132219D01*
X661036Y1132226D01*
X661062Y1132253D01*
X661063Y1132254D01*
G03X661439Y1133169I-925J915D01*
G03X658835I-1302J0D01*
G03X659211Y1132254I1301J0D01*
G01X659212Y1132253D01*
X659238Y1132226D01*
X659241Y1132219D01*
X659246Y1132207D01*
X659256Y1132184D01*
X659263Y1132164D01*
G02X659260Y1132049I-193J-53D01*
G01X659251Y1132027D01*
X659107Y1131682D01*
G02X659077Y1131638I-179J90D01*
G01X657457D01*
G02X657427Y1131682I149J134D01*
G01X657283Y1132027D01*
X657274Y1132049D01*
G02X657271Y1132164I190J62D01*
G01X657278Y1132184D01*
X657288Y1132207D01*
X657293Y1132219D01*
X657296Y1132226D01*
X657322Y1132253D01*
X657323Y1132254D01*
G03X657699Y1133169I-925J915D01*
G03X655095I-1302J0D01*
G03X655471Y1132254I1301J0D01*
G01X655472Y1132253D01*
X655498Y1132226D01*
X655501Y1132219D01*
X655506Y1132207D01*
X655516Y1132184D01*
X655523Y1132164D01*
G02X655520Y1132049I-193J-53D01*
G01X655511Y1132027D01*
X655367Y1131682D01*
G02X655337Y1131638I-179J90D01*
G01X654187D01*
G03X653899Y1131604I4J-1268D01*
G01X653802Y1131581D01*
G02X653742Y1131613I63J190D01*
G02X653680Y1131694I123J158D01*
G01X653637Y1131798D01*
X653609Y1131865D01*
X653535Y1132044D01*
G02X653537Y1132187I188J69D01*
G01X653539Y1132193D01*
G02X653571Y1132243I183J-82D01*
G01X653579Y1132251D01*
G03X653958Y1133169I-922J918D01*
G03X651723Y1134078I-1302J0D01*
G02X651721Y1134076I-142J140D01*
G01X651719Y1134074D01*
G02X651436I-141J141D01*
G01X651332Y1134178D01*
G02X651273Y1134320I141J142D01*
G01Y1135645D01*
G02X651275Y1135675I200J2D01*
G02X651374Y1135819I198J-30D01*
G02X651385Y1135825I101J-172D01*
G01X651761Y1136009D01*
X651874Y1135997D01*
X651919Y1135961D01*
G03X652657Y1135707I739J948D01*
G03Y1138111I0J1202D01*
G03X651969Y1137893I2J-1201D01*
G01X651968D01*
G02X651855Y1137857I-114J164D01*
G01X651710D01*
G02X651623Y1137877I0J200D01*
G01X651385Y1137993D01*
G02X651367Y1138003I88J180D01*
G02X651275Y1138143I106J170D01*
G02X651273Y1138173I198J28D01*
G01Y1139229D01*
G03X651214Y1139371I-200J0D01*
G01X650465Y1140120D01*
G03X650323Y1140179I-142J-141D01*
G01X650293D01*
G02X650093Y1140379I0J200D01*
G01Y1140399D01*
X650097Y1140418D01*
G03X650119Y1140647I-1180J229D01*
G01Y1140649D01*
G03X647715I-1202J0D01*
G03X647716Y1140596I1202J-4D01*
G01X647718Y1140554D01*
X647689Y1140478D01*
X647460Y1140240D01*
G02X647316Y1140179I-144J139D01*
G01X646777D01*
G02X646633Y1140241I1J200D01*
G01X646434Y1140448D01*
G02X646378Y1140596I144J139D01*
G03X646379Y1140649I-1201J49D01*
G03X643975I-1202J0D01*
G03X644208Y1139939I1200J1D01*
G02X644188Y1139679I-161J-118D01*
G01X643790Y1139281D01*
G02X643660Y1139222I-142J141D01*
G01X643116D01*
G03X642916Y1139022I0J-200D01*
G01Y1138560D01*
G02X642857Y1138418I-200J0D01*
G01X642315Y1137876D01*
X642172Y1137862D01*
X642121Y1137896D01*
G02X642119Y1137898I138J140D01*
G03X641437Y1138111I-683J-989D01*
G03X640235Y1136909I0J-1202D01*
G03X640443Y1136234I1202J1D01*
G02X640419Y1135980I-165J-113D01*
G01X638697Y1134259D01*
G02X638442Y1134237I-141J142D01*
G01X638441D01*
G03X636394Y1133169I-745J-1068D01*
G01Y1133168D01*
G03X636412Y1132953I1301J1D01*
G01X636413Y1132948D01*
Y1132945D01*
X636416Y1132926D01*
X636417Y1132923D01*
X636405Y1132882D01*
G02X636365Y1132808I-192J56D01*
G01X636162Y1132570D01*
G02X636030Y1132507I-146J136D01*
G02X636015Y1132506I-21J199D01*
G01X635637D01*
X635623D01*
G02X635491Y1132569I14J200D01*
G01X635452Y1132615D01*
X635300Y1132792D01*
X635287Y1132807D01*
G02X635247Y1132881I152J130D01*
G01X635235Y1132922D01*
X635238Y1132941D01*
X635239Y1132947D01*
G03X635258Y1133168I-1282J222D01*
G01Y1133169D01*
G03X632654I-1302J0D01*
G01Y1133168D01*
G03X632672Y1132953I1301J1D01*
G01X632673Y1132948D01*
Y1132945D01*
X632676Y1132926D01*
X632677Y1132923D01*
X632665Y1132882D01*
G02X632625Y1132808I-192J56D01*
G01X632422Y1132570D01*
G02X632290Y1132507I-146J136D01*
G02X632275Y1132506I-21J199D01*
G01X621620D01*
G03X620629Y1132095I1J-1402D01*
G01X620290Y1131757D01*
G02X620116Y1131702I-141J142D01*
G01X620110Y1131703D01*
G02X620023Y1131744I39J196D01*
G01X620004Y1131759D01*
X619975Y1131798D01*
X619882Y1132023D01*
X619873Y1132046D01*
G02X619876Y1132187I189J67D01*
G01X619878Y1132193D01*
G02X619911Y1132244I183J-82D01*
G03X620297Y1133169I-915J925D01*
G03X617693I-1302J0D01*
G03X618070Y1132253I1301J0D01*
G01X618071Y1132252D01*
G02X618124Y1132151I-143J-140D01*
G01Y1132149D01*
G02X618117Y1132045I-196J-39D01*
G01X618046Y1131874D01*
X617971Y1131694D01*
G02X617795Y1131571I-185J77D01*
G01X608983D01*
G02X608861Y1131613I1J200D01*
G02X608799Y1131694I123J158D01*
G01X608787Y1131722D01*
X608728Y1131865D01*
X608654Y1132044D01*
G02X608656Y1132187I188J69D01*
G01X608658Y1132193D01*
G02X608690Y1132243I183J-82D01*
G01X608698Y1132251D01*
G03X609077Y1133169I-922J918D01*
G03X606473I-1302J0D01*
G03X606850Y1132253I1301J0D01*
G01X606851Y1132252D01*
G02X606904Y1132151I-143J-140D01*
G01Y1132149D01*
G02X606897Y1132045I-196J-39D01*
G01X606826Y1131874D01*
X606751Y1131694D01*
G02X606575Y1131571I-185J77D01*
G01X605242D01*
G02X605120Y1131613I1J200D01*
G02X605058Y1131694I123J158D01*
G01X605046Y1131722D01*
X604987Y1131865D01*
X604913Y1132044D01*
G02X604915Y1132187I188J69D01*
G01X604917Y1132193D01*
G02X604949Y1132243I183J-82D01*
G01X604957Y1132251D01*
G03X605336Y1133169I-922J918D01*
G03X602732I-1302J0D01*
G03X603109Y1132253I1301J0D01*
G01X603110Y1132252D01*
G02X603163Y1132151I-143J-140D01*
G01Y1132149D01*
G02X603156Y1132045I-196J-39D01*
G01X603085Y1131874D01*
X603010Y1131694D01*
G02X602834Y1131571I-185J77D01*
G01X601502D01*
G02X601380Y1131613I1J200D01*
G02X601318Y1131694I123J158D01*
G01X601306Y1131722D01*
X601247Y1131865D01*
X601173Y1132044D01*
G02X601175Y1132187I188J69D01*
G01X601177Y1132193D01*
G02X601209Y1132243I183J-82D01*
G01X601217Y1132251D01*
G03X601596Y1133169I-922J918D01*
G03X598992I-1302J0D01*
G03X599369Y1132253I1301J0D01*
G01X599370Y1132252D01*
G02X599423Y1132151I-143J-140D01*
G01Y1132149D01*
G02X599416Y1132045I-196J-39D01*
G01X599345Y1131874D01*
X599270Y1131694D01*
G02X599094Y1131571I-185J77D01*
G01X591824D01*
G02X591783Y1131576I4J200D01*
G01X591700Y1131597D01*
X591678Y1131609D01*
G03X590958Y1131793I-720J-1318D01*
G01X590920D01*
G03X590465Y1131710I39J-1502D01*
G01X590463D01*
G03X590397Y1131684I517J-1410D01*
G01X590395D01*
G03X590239Y1131610I565J-1392D01*
G01X590228Y1131604D01*
X590216Y1131598D01*
X590138Y1131578D01*
G02X590088Y1131571I-52J193D01*
G01X588334D01*
G02X588293Y1131576I4J200D01*
G01X588210Y1131597D01*
X588188Y1131609D01*
G03X587468Y1131793I-720J-1318D01*
G01X587430D01*
G03X586975Y1131710I39J-1502D01*
G01X586973D01*
G03X586907Y1131684I517J-1410D01*
G01X586905D01*
G03X586749Y1131610I565J-1392D01*
G01X586738Y1131604D01*
X586726Y1131598D01*
X586648Y1131578D01*
G02X586598Y1131571I-52J193D01*
G01X582834D01*
G02X582793Y1131576I4J200D01*
G01X582710Y1131597D01*
X582688Y1131609D01*
G03X581968Y1131793I-720J-1318D01*
G01X581930D01*
G03X581475Y1131710I39J-1502D01*
G01X581473D01*
G03X581407Y1131684I517J-1410D01*
G01X581405D01*
G03X581249Y1131610I565J-1392D01*
G01X581238Y1131604D01*
X581226Y1131598D01*
X581148Y1131578D01*
G02X581098Y1131571I-52J193D01*
G01X539006D01*
G02X538915Y1131593I0J200D01*
G02X538865Y1131629I90J178D01*
G01X536869Y1133625D01*
G02X536825Y1133692I142J141D01*
G01X536811Y1133726D01*
Y1153322D01*
G03X536752Y1153464I-200J0D01*
G01X532249Y1157967D01*
G03X532107Y1158026I-142J-141D01*
G01X470431D01*
G02X470310Y1158067I0J200D01*
G01X470298Y1158078D01*
G03X470293Y1158082I-127J-153D01*
G01X470286Y1158088D01*
X468166Y1160208D01*
G03X468072Y1160261I-142J-141D01*
G01X468071D01*
X468044Y1160268D01*
X468022Y1160280D01*
G02X468017Y1160283I100J173D01*
G02X467977Y1160314I102J172D01*
G01X467904Y1160387D01*
G02X467860Y1160454I142J141D01*
G01X467846Y1160488D01*
Y1239546D01*
G02X467852Y1239594I200J-1D01*
G02X467861Y1239622I194J-47D01*
G01X467885Y1239680D01*
G03X467900Y1239756I-185J76D01*
G01Y1248457D01*
G02X467903Y1248489I200J-3D01*
G01Y1248491D01*
G02X467957Y1248597I197J-34D01*
G01X470767Y1251407D01*
G02X470873Y1251461I140J-143D01*
G01X470875D01*
G02X470907Y1251464I35J-197D01*
G01X557943D01*
G02X557975Y1251461I-3J-200D01*
G01X557977D01*
G02X558083Y1251407I-34J-197D01*
G01X565644Y1243846D01*
G03X565786Y1243787I142J141D01*
G01X581629D01*
G03X581771Y1243846I0J200D01*
G01X589332Y1251407D01*
G02X589438Y1251461I140J-143D01*
G01X589440D01*
G02X589472Y1251464I35J-197D01*
G01X600565D01*
G02X600710Y1251402I0J-200D01*
G01X600910Y1251192D01*
G02X600965Y1251045I-145J-138D01*
G01Y1251039D01*
G03X600963Y1250985I1199J-71D01*
G01Y1250983D01*
G03X603367I1202J1D01*
G01Y1250985D01*
G03X603365Y1251038I-1201J-19D01*
G01Y1251045D01*
X603363Y1251086D01*
X603391Y1251162D01*
X603620Y1251402D01*
G02X603765Y1251464I145J-138D01*
G01X604305D01*
G02X604450Y1251402I0J-200D01*
G01X604650Y1251192D01*
G02X604705Y1251045I-145J-138D01*
G01Y1251039D01*
G03X604703Y1250985I1199J-71D01*
G01Y1250983D01*
G03X607107I1202J1D01*
G01Y1250985D01*
G03X607105Y1251038I-1201J-19D01*
G01Y1251045D01*
X607103Y1251086D01*
X607131Y1251162D01*
X607360Y1251402D01*
G02X607505Y1251464I145J-138D01*
G01X608046D01*
G02X608191Y1251402I0J-200D01*
G01X608391Y1251192D01*
G02X608446Y1251045I-145J-138D01*
G01Y1251039D01*
G03X608444Y1250985I1199J-71D01*
G01Y1250983D01*
G03X610848I1202J1D01*
G01Y1250985D01*
G03X610846Y1251038I-1201J-19D01*
G01Y1251045D01*
X610844Y1251086D01*
X610872Y1251162D01*
X611101Y1251402D01*
G02X611246Y1251464I145J-138D01*
G01X611786D01*
G02X611931Y1251402I0J-200D01*
G01X612131Y1251192D01*
G02X612186Y1251045I-145J-138D01*
G01Y1251039D01*
G03X612184Y1250985I1199J-71D01*
G01Y1250983D01*
G03X614588I1202J1D01*
G01Y1250985D01*
G03X614586Y1251038I-1201J-19D01*
G01Y1251045D01*
X614584Y1251086D01*
X614612Y1251162D01*
X614841Y1251402D01*
G02X614986Y1251464I145J-138D01*
G01X615526D01*
G02X615671Y1251402I0J-200D01*
G01X615871Y1251192D01*
G02X615926Y1251045I-145J-138D01*
G01Y1251039D01*
G03X615924Y1250985I1199J-71D01*
G01Y1250983D01*
G03X618328I1202J1D01*
G01Y1250985D01*
G03X618326Y1251038I-1201J-19D01*
G01Y1251045D01*
X618324Y1251086D01*
X618352Y1251162D01*
X618581Y1251402D01*
G02X618726Y1251464I145J-138D01*
G01X619266D01*
G02X619411Y1251402I0J-200D01*
G01X619611Y1251192D01*
G02X619666Y1251045I-145J-138D01*
G01Y1251039D01*
G03X619664Y1250985I1199J-71D01*
G01Y1250983D01*
G03X622068I1202J1D01*
G01Y1250985D01*
G03X622066Y1251038I-1201J-19D01*
G01Y1251045D01*
X622064Y1251086D01*
X622092Y1251162D01*
X622321Y1251402D01*
G02X622466Y1251464I145J-138D01*
G01X623006D01*
G02X623151Y1251402I0J-200D01*
G01X623351Y1251192D01*
G02X623406Y1251045I-145J-138D01*
G01Y1251039D01*
G03X623404Y1250985I1199J-71D01*
G01Y1250983D01*
G03X625808I1202J1D01*
G01Y1250985D01*
G03X625806Y1251038I-1201J-19D01*
G01Y1251045D01*
X625804Y1251086D01*
X625832Y1251162D01*
X626061Y1251402D01*
G02X626206Y1251464I145J-138D01*
G01X626746D01*
G02X626891Y1251402I0J-200D01*
G01X627091Y1251192D01*
G02X627146Y1251045I-145J-138D01*
G01Y1251039D01*
G03X627144Y1250985I1199J-71D01*
G01Y1250983D01*
G03X629548I1202J1D01*
G01Y1250985D01*
G03X629546Y1251038I-1201J-19D01*
G01Y1251045D01*
X629544Y1251086D01*
X629572Y1251162D01*
X629801Y1251402D01*
G02X629946Y1251464I145J-138D01*
G01X630486D01*
G02X630631Y1251402I0J-200D01*
G01X630831Y1251192D01*
G02X630886Y1251045I-145J-138D01*
G01Y1251039D01*
G03X630884Y1250985I1199J-71D01*
G01Y1250983D01*
G03X633288I1202J1D01*
G01Y1250985D01*
G03X633286Y1251038I-1201J-19D01*
G01Y1251045D01*
X633284Y1251086D01*
X633312Y1251162D01*
X633541Y1251402D01*
G02X633686Y1251464I145J-138D01*
G01X634227D01*
G02X634372Y1251402I0J-200D01*
G01X634572Y1251192D01*
G02X634627Y1251045I-145J-138D01*
G01Y1251039D01*
G03X634625Y1250985I1199J-71D01*
G01Y1250983D01*
G03X637029I1202J1D01*
G01Y1250985D01*
G03X637027Y1251038I-1201J-19D01*
G01Y1251045D01*
X637025Y1251086D01*
X637053Y1251162D01*
X637282Y1251402D01*
G02X637427Y1251464I145J-138D01*
G01X637967D01*
G02X638112Y1251402I0J-200D01*
G01X638312Y1251192D01*
G02X638367Y1251045I-145J-138D01*
G01Y1251039D01*
G03X638365Y1250985I1199J-71D01*
G01Y1250983D01*
G03X640769I1202J1D01*
G01Y1250985D01*
G03X640767Y1251038I-1201J-19D01*
G01Y1251045D01*
X640765Y1251086D01*
X640793Y1251162D01*
X641022Y1251402D01*
G02X641167Y1251464I145J-138D01*
G01X641707D01*
G02X641852Y1251402I0J-200D01*
G01X642052Y1251192D01*
G02X642107Y1251045I-145J-138D01*
G01Y1251039D01*
G03X642105Y1250985I1199J-71D01*
G01Y1250983D01*
G03X643307Y1249782I1202J1D01*
G03X643511Y1249800I-3J1202D01*
G01X643528Y1249803D01*
X643529D01*
X643578Y1249812D01*
X643671Y1249783D01*
X643975Y1249478D01*
X644004Y1249385D01*
X643999Y1249357D01*
G03X643974Y1249113I1178J-244D01*
G01Y1249110D01*
G03X644000Y1248865I1202J4D01*
G01Y1248861D01*
X644004Y1248842D01*
X643975Y1248749D01*
X643707Y1248480D01*
G02X643624Y1248430I-142J141D01*
G01X643577Y1248416D01*
X643528Y1248425D01*
G03X643307Y1248445I-218J-1182D01*
G03X644509Y1247243I0J-1202D01*
G03X644488Y1247463I-1202J-4D01*
G01Y1247465D01*
G02X644543Y1247642I197J36D01*
G01X644776Y1247876D01*
G02X644859Y1247926I142J-141D01*
G01X644906Y1247940D01*
X644955Y1247931D01*
G03X645176Y1247911I218J1182D01*
G01X645178D01*
G03X645397Y1247932I-5J1202D01*
G01X645412Y1247934D01*
X645413D01*
X645445Y1247941D01*
X645541Y1247912D01*
X645846Y1247608D01*
X645875Y1247515D01*
X645866Y1247466D01*
X645863Y1247449D01*
G03X645845Y1247243I1184J-207D01*
G03X647047Y1246041I1202J0D01*
G03X647172Y1246047I5J1202D01*
G01X647173D01*
G02X647327Y1245997I20J-199D01*
G01X647546Y1245799D01*
G02X647550Y1245795I-139J-143D01*
G02X647611Y1245671I-138J-145D01*
G02X647612Y1245650I-199J-20D01*
G01Y1245373D01*
G03X647637Y1245119I1303J0D01*
G01Y1245115D01*
X647638Y1245113D01*
X647610Y1245023D01*
X647323Y1244723D01*
X647235Y1244691D01*
X647188Y1244697D01*
G03X647047Y1244705I-138J-1194D01*
G03Y1242301I0J-1202D01*
G03X647267Y1242322I-4J1202D01*
G01X647269D01*
G02X647446Y1242267I36J-197D01*
G01X647715Y1241998D01*
X647744Y1241903D01*
X647735Y1241855D01*
G03X647715Y1241635I1182J-218D01*
G01Y1241633D01*
G03X647741Y1241385I1202J1D01*
G01Y1241381D01*
X647745Y1241362D01*
X647716Y1241269D01*
X647446Y1240999D01*
G02X647269Y1240944I-141J142D01*
G01X647268D01*
G03X647047Y1240965I-224J-1181D01*
G03Y1238561I0J-1202D01*
G03X647190Y1238569I4J1202D01*
G01X647237Y1238575D01*
X647325Y1238543D01*
X647612Y1238243D01*
X647640Y1238154D01*
X647637Y1238135D01*
G03X647614Y1237893I1279J-244D01*
G01Y1237891D01*
G03X647639Y1237640I1302J3D01*
G01Y1237636D01*
X647640Y1237633D01*
X647612Y1237543D01*
X647325Y1237243D01*
X647237Y1237211D01*
X647190Y1237217D01*
G03X647047Y1237225I-139J-1194D01*
G03Y1234821I0J-1202D01*
G03X647190Y1234829I4J1202D01*
G01X647237Y1234835D01*
X647325Y1234803D01*
X647612Y1234503D01*
X647640Y1234414D01*
X647637Y1234395D01*
G03X647614Y1234153I1279J-244D01*
G01Y1234151D01*
G03X647639Y1233900I1302J3D01*
G01Y1233896D01*
X647640Y1233893D01*
X647612Y1233803D01*
X647325Y1233503D01*
X647237Y1233471D01*
X647190Y1233477D01*
G03X647047Y1233485I-139J-1194D01*
G03Y1231081I0J-1202D01*
G03X647190Y1231089I4J1202D01*
G01X647237Y1231095D01*
X647325Y1231063D01*
X647612Y1230763D01*
X647640Y1230674D01*
X647637Y1230655D01*
G03X647614Y1230413I1279J-244D01*
G01Y1230411D01*
G03X647639Y1230160I1302J3D01*
G01Y1230156D01*
X647640Y1230153D01*
X647612Y1230063D01*
X647325Y1229763D01*
X647237Y1229731D01*
X647190Y1229737D01*
G03X647047Y1229745I-139J-1194D01*
G03Y1227341I0J-1202D01*
G03X647189Y1227349I3J1202D01*
G01X647236Y1227355D01*
X647324Y1227323D01*
X647610Y1227023D01*
X647638Y1226933D01*
X647635Y1226915D01*
G03X647612Y1226672I1280J-244D01*
G01Y1226396D01*
G02X647611Y1226375I-200J-1D01*
G02X647550Y1226251I-199J21D01*
G02X647546Y1226247I-143J139D01*
G01X647327Y1226049D01*
G02X647173Y1225999I-134J149D01*
G01X647172D01*
G03X647047Y1226005I-120J-1196D01*
G03Y1223601I0J-1202D01*
G03X647172Y1223607I5J1202D01*
G01X647173D01*
G02X647327Y1223557I20J-199D01*
G01X647546Y1223359D01*
G02X647550Y1223355I-139J-143D01*
G02X647611Y1223231I-138J-145D01*
G02X647612Y1223210I-199J-20D01*
G01Y1222930D01*
G03X647637Y1222679I1302J3D01*
G01Y1222675D01*
X647638Y1222672D01*
X647610Y1222582D01*
X647323Y1222282D01*
X647235Y1222250D01*
X647188Y1222256D01*
G03X647047Y1222264I-138J-1194D01*
G03Y1219860I0J-1202D01*
G03X647267Y1219881I-4J1202D01*
G01X647269D01*
G02X647446Y1219826I36J-197D01*
G01X647681Y1219591D01*
G02X647736Y1219414I-142J-141D01*
G01Y1219413D01*
G03X647715Y1219192I1181J-224D01*
G03X650119I1202J0D01*
G03X650098Y1219412I-1202J-4D01*
G01Y1219414D01*
G02X650153Y1219591I197J36D01*
G01X650388Y1219826D01*
G02X650565Y1219881I141J-142D01*
G01X650566D01*
G03X650786Y1219860I224J1181D01*
G01X650788D01*
G03X650918Y1219868I-9J1202D01*
G01X650929Y1219869D01*
X650931D01*
X650977Y1219874D01*
X651021Y1219858D01*
G02X651097Y1219808I-69J-188D01*
G01X651351Y1219542D01*
X651379Y1219452D01*
X651371Y1219406D01*
G03X652403Y1217915I1285J-214D01*
G03X652568Y1217893I254J1277D01*
G01X652572D01*
X652605Y1217890D01*
X652660Y1217867D01*
G02X652664Y1217865I-87J-180D01*
G01X652716Y1217842D01*
G02X652750Y1217818I-98J-174D01*
G01X652822Y1217749D01*
G02X652882Y1217606I-140J-143D01*
G01Y1217038D01*
G02X652846Y1216924I-200J0D01*
G02X652824Y1216897I-165J112D01*
G37*
G36*
G01X594744Y54588D02*
X623251D01*
X623486Y54353D01*
Y52826D01*
X623251Y52591D01*
X594744D01*
G03X588807Y46654I0J-5937D01*
G01Y7874D01*
G02X582933Y2000I-5874J0D01*
G01X535689D01*
G02X529815Y7874I0J5874D01*
G01Y46526D01*
X531812D01*
Y7874D01*
G03X535687Y3998I3876J0D01*
G01X582933D01*
G03X586810Y7874I0J3877D01*
G01Y46654D01*
G02X594744Y54588I7934J0D01*
G37*
G36*
G01X631841Y1127485D02*
G02X631838Y1127450I-200J0D01*
G01X627371Y1122983D01*
G02X627336Y1122980I-34J197D01*
G01X627222Y1123016D01*
X627211Y1123023D01*
G03X626476Y1123250I-735J-1076D01*
G03X625174Y1121948I0J-1302D01*
G03X625189Y1121748I1302J-3D01*
G01X625188D01*
G03X625393Y1121223I1288J200D01*
G01X625409Y1121200D01*
X625444Y1121088D01*
G02X625441Y1121053I-200J-1D01*
G01X623557Y1119170D01*
G02X623411Y1119202I-33J197D01*
G03X622736Y1119410I-676J-994D01*
G03X621534Y1118208I0J-1202D01*
G03X621742Y1117533I1202J1D01*
G02X621774Y1117387I-165J-113D01*
G01X619891Y1115503D01*
G02X619856Y1115500I-34J197D01*
G01X619742Y1115536D01*
X619731Y1115543D01*
G03X618996Y1115770I-735J-1076D01*
G03X617694Y1114468I0J-1302D01*
G03X617709Y1114268I1302J-3D01*
G01X617708D01*
G03X617913Y1113743I1288J200D01*
G01X617929Y1113720D01*
X617964Y1113608D01*
G02X617961Y1113573I-200J-1D01*
G01X616151Y1111763D01*
G02X616116Y1111760I-34J197D01*
G01X616002Y1111796D01*
X615991Y1111803D01*
G03X615256Y1112030I-735J-1076D01*
G03X613954Y1110728I0J-1302D01*
G03X613969Y1110528I1302J-3D01*
G01X613968D01*
G03X614173Y1110003I1288J200D01*
G01X614189Y1109980D01*
X614224Y1109868D01*
G02X614221Y1109833I-200J-1D01*
G01X612411Y1108023D01*
G02X612376Y1108020I-34J197D01*
G01X612262Y1108056D01*
X612251Y1108063D01*
G03X611516Y1108290I-735J-1076D01*
G03X610214Y1106988I0J-1302D01*
G03X610229Y1106788I1302J-3D01*
G01X610228D01*
G03X610433Y1106263I1288J200D01*
G01X610449Y1106240D01*
X610484Y1106128D01*
G02X610481Y1106093I-200J-1D01*
G01X608670Y1104282D01*
G02X608521Y1104315I-34J197D01*
G03X607789Y1104549I-745J-1068D01*
G01X607766D01*
G03X606474Y1103257I10J-1302D01*
G01Y1103245D01*
G03X606708Y1102502I1302J2D01*
G02X606741Y1102353I-164J-115D01*
G01X605040Y1100652D01*
Y1100611D01*
X604862Y1100521D01*
G02X604822Y1100507I-86J181D01*
G02X604670Y1100528I-51J193D01*
G03X604036Y1100709I-634J-1021D01*
G01X604035D01*
G03X602833Y1099507I0J-1202D01*
G03X603862Y1098317I1203J0D01*
G01X603894Y1098312D01*
X603983Y1098268D01*
G02X604040Y1098226I-88J-180D01*
G01X604096Y1098166D01*
G02X604151Y1098029I-145J-138D01*
G01Y1089765D01*
G02X604096Y1089628I-200J1D01*
G01X604040Y1089568D01*
G02X603983Y1089526I-145J138D01*
G01X603894Y1089482D01*
X603862Y1089477D01*
G03Y1087097I173J-1190D01*
G01X603894Y1087092D01*
X603983Y1087048D01*
G02X604040Y1087006I-88J-180D01*
G01X604096Y1086946D01*
G02X604151Y1086809I-145J-138D01*
G01Y1055358D01*
Y1055345D01*
G02X604096Y1055220I-200J13D01*
G01X603882Y1055014D01*
G02X603815Y1054971I-139J144D01*
G01X603777Y1054957D01*
X603737Y1054958D01*
G03X603682Y1054959I-55J-1501D01*
G01X603681D01*
G03X602180Y1053457I1J-1502D01*
G03X603682Y1051955I1502J0D01*
G03X603737Y1051956I0J1502D01*
G01X603777Y1051957D01*
X603815Y1051943D01*
G02X603882Y1051900I-72J-187D01*
G01X604096Y1051694D01*
G02X604151Y1051569I-145J-138D01*
G01Y1050968D01*
G02X604129Y1050877I-200J0D01*
G02X604093Y1050827I-178J90D01*
G01X589250Y1035984D01*
G02X589112Y1035926I-141J142D01*
G01X588993Y1035924D01*
G02X588859Y1035973I-3J200D01*
G03X587880Y1036336I-979J-1139D01*
G03X586378Y1034834I0J-1502D01*
G01Y1034831D01*
G03X586419Y1034484I1502J2D01*
G01Y1034483D01*
G02X586420Y1034389I-194J-49D01*
G01X586411Y1034351D01*
X586182Y1034059D01*
G02X586031Y1033990I-151J131D01*
G01X546606D01*
G02X546515Y1034012I0J200D01*
G02X546465Y1034048I90J178D01*
G01X535468Y1045045D01*
G02X535432Y1045095I142J140D01*
G02X535410Y1045186I178J91D01*
G01Y1072838D01*
G02X535472Y1072982I200J-1D01*
G01X535742Y1073241D01*
X535785Y1073239D01*
G03X535806Y1073238I649J13414D01*
G01X535828Y1073237D01*
G03X536418Y1073224I591J13417D01*
G03Y1100084I0J13430D01*
G03X535828Y1100071I1J-13430D01*
G01X535806Y1100070D01*
G03X535785Y1100069I628J-13415D01*
G01X535742Y1100067D01*
X535472Y1100326D01*
G02X535410Y1100470I138J145D01*
G01Y1121468D01*
G02X535414Y1121506I200J-2D01*
G02X535467Y1121608I196J-37D01*
G01X543834Y1129975D01*
G02X543936Y1130028I139J-143D01*
G02X543974Y1130032I40J-196D01*
G01X580329D01*
G02X580521Y1129886I-1J-200D01*
G03X581062Y1129092I1447J404D01*
G01X581064Y1129090D01*
G02X581121Y1129023I-120J-160D01*
G01X581141Y1128984D01*
X581144Y1128774D01*
X581146Y1128620D01*
G02X581127Y1128533I-200J-2D01*
G01X581117Y1128512D01*
X581089Y1128477D01*
X581071Y1128462D01*
G03X580510Y1127291I942J-1171D01*
G03X583514I1502J0D01*
G03X582917Y1128490I-1503J0D01*
G01X582915Y1128492D01*
G02X582858Y1128559I120J160D01*
G01X582838Y1128598D01*
X582834Y1128962D01*
G02X582853Y1129050I200J3D01*
G01X582862Y1129070D01*
X582890Y1129105D01*
X582908Y1129120D01*
G03X583413Y1129886I-942J1170D01*
G01X583422Y1129918D01*
X583458Y1129972D01*
X583484Y1129991D01*
G02X583605Y1130032I121J-159D01*
G01X585829D01*
G02X586021Y1129886I-1J-200D01*
G03X588913I1446J405D01*
G01X588922Y1129918D01*
X588958Y1129972D01*
X588984Y1129991D01*
G02X589105Y1130032I121J-159D01*
G01X589319D01*
G02X589511Y1129886I-1J-200D01*
G03X592403I1446J405D01*
G01X592412Y1129918D01*
X592448Y1129972D01*
X592474Y1129991D01*
G02X592595Y1130032I121J-159D01*
G01X598707D01*
G02X598723Y1130031I-4J-200D01*
G02X598833Y1129987I-16J-199D01*
G01X598849Y1129971D01*
X599059Y1129733D01*
G02X599103Y1129582I-154J-127D01*
G01Y1129581D01*
G03X599093Y1129429I1192J-155D01*
G03X601497I1202J0D01*
G03X601178Y1130245I-1203J0D01*
G01X601166Y1130257D01*
G03X601160Y1130267I-175J-98D01*
G02X601124Y1130394I164J115D01*
G01X601128Y1130419D01*
G02X601350Y1130579I196J-38D01*
G01X601351D01*
G03X601374Y1130576I167J1190D01*
G01X601377D01*
G03X601501Y1130570I120J1195D01*
G01X602847D01*
G03X602944Y1130575I-13J1201D01*
G03X602981Y1130579I-111J1196D01*
G01X602987Y1130580D01*
G02X603124Y1130542I19J-199D01*
G01X603137Y1130532D01*
G02X603169Y1130265I-131J-151D01*
G01X603157Y1130250D01*
X603152Y1130244D01*
G03X602833Y1129429I882J-815D01*
G03X605237I1202J0D01*
G03X604918Y1130245I-1203J0D01*
G01X604906Y1130257D01*
G03X604900Y1130267I-175J-98D01*
G02X604864Y1130394I164J115D01*
G01X604868Y1130419D01*
G02X605090Y1130579I196J-38D01*
G01X605091D01*
G03X605114Y1130576I167J1190D01*
G01X605117D01*
G03X605241Y1130570I120J1195D01*
G01X606588D01*
G03X606853Y1130604I-19J1201D01*
G03X606857Y1130605I-289J1166D01*
G01X606881Y1130611D01*
X608669D01*
X608692Y1130605D01*
G03X608766Y1130589I291J1166D01*
G03X608982Y1130570I213J1182D01*
G01X617808D01*
G03X618073Y1130604I-19J1201D01*
G03X618077Y1130605I-289J1166D01*
G01X618101Y1130611D01*
X631308D01*
G02X631346Y1130607I-2J-200D01*
G02X631448Y1130554I-37J-196D01*
G01X631784Y1130218D01*
G02X631837Y1130116I-143J-139D01*
G02X631841Y1130078I-196J-40D01*
G01Y1127485D01*
G37*
G36*
G01X646495Y1138220D02*
X649263D01*
G02X649405Y1138161I0J-200D01*
G01X650090Y1137476D01*
G02X650149Y1137334I-141J-142D01*
G01Y1134538D01*
G02X650047Y1134364I-200J0D01*
G01X649695Y1134166D01*
X649588Y1134168D01*
X649541Y1134196D01*
G03X648917Y1134371I-625J-1027D01*
G03Y1131967I0J-1202D01*
G03X649261Y1132017I1J1202D01*
G01X649313Y1132033D01*
X649420Y1132006D01*
X649459Y1131967D01*
G02Y1131684I-141J-142D01*
G01X649116Y1131341D01*
G02X648974Y1131282I-142J141D01*
G01X648229D01*
X648209Y1131314D01*
X646869D01*
X646796Y1131284D01*
X646794Y1131282D01*
X646763D01*
G03X646621Y1131223I0J-200D01*
G01X646225Y1130827D01*
G03X646166Y1130685I141J-142D01*
G01Y1130654D01*
X645968Y1130456D01*
X645834Y1130438D01*
X645775Y1130472D01*
G03X645177Y1130631I-597J-1043D01*
G03Y1128227I0J-1202D01*
G03X645540Y1128283I0J1202D01*
G01X645586Y1128298D01*
X645679Y1128282D01*
X645979Y1128063D01*
G02X646060Y1127902I-119J-161D01*
G01Y1127215D01*
G02X645979Y1127054I-200J0D01*
G01X645679Y1126835D01*
X645586Y1126819D01*
X645540Y1126834D01*
G03X645177Y1126890I-363J-1146D01*
G03Y1124486I0J-1202D01*
G03X645540Y1124542I0J1202D01*
G01X645586Y1124557D01*
X645679Y1124541D01*
X645979Y1124322D01*
G02X646060Y1124161I-119J-161D01*
G01Y1123475D01*
G02X645979Y1123314I-200J0D01*
G01X645679Y1123095D01*
X645586Y1123079D01*
X645540Y1123094D01*
G03X645177Y1123150I-363J-1146D01*
G03Y1120746I0J-1202D01*
G03X645540Y1120802I0J1202D01*
G01X645586Y1120817D01*
X645679Y1120801D01*
X645979Y1120582D01*
G02X646060Y1120421I-119J-161D01*
G01Y1119735D01*
G02X645979Y1119574I-200J0D01*
G01X645679Y1119355D01*
X645586Y1119339D01*
X645540Y1119354D01*
G03X645177Y1119410I-363J-1146D01*
G03Y1117006I0J-1202D01*
G03X645540Y1117062I0J1202D01*
G01X645586Y1117077D01*
X645679Y1117061D01*
X645979Y1116842D01*
G02X646060Y1116681I-119J-161D01*
G01Y1115995D01*
G02X645979Y1115834I-200J0D01*
G01X645679Y1115615D01*
X645586Y1115599D01*
X645540Y1115614D01*
G03X645177Y1115670I-363J-1146D01*
G03Y1113266I0J-1202D01*
G03X645540Y1113322I0J1202D01*
G01X645586Y1113337D01*
X645679Y1113321D01*
X645979Y1113102D01*
G02X646060Y1112941I-119J-161D01*
G01Y1109605D01*
G02X646030Y1109498I-200J-2D01*
G03X645845Y1108858I1017J-641D01*
G03X646030Y1108218I1202J1D01*
G02X646060Y1108111I-170J-105D01*
G01Y1105864D01*
G02X646030Y1105757I-200J-2D01*
G03X645845Y1105117I1017J-641D01*
G03X646030Y1104477I1202J1D01*
G02X646060Y1104370I-170J-105D01*
G01Y1102124D01*
G02X646030Y1102017I-200J-2D01*
G03X645845Y1101377I1017J-641D01*
G03X646030Y1100737I1202J1D01*
G02X646060Y1100630I-170J-105D01*
G01Y1098384D01*
G02X646030Y1098277I-200J-2D01*
G03X645845Y1097637I1017J-641D01*
G03X646030Y1096997I1202J1D01*
G02X646060Y1096890I-170J-105D01*
G01Y1094644D01*
G02X646030Y1094537I-200J-2D01*
G03X645845Y1093897I1017J-641D01*
G03X646030Y1093257I1202J1D01*
G01X646045Y1093232D01*
X646060Y1093179D01*
Y1093065D01*
G03X646075Y1092990I200J1D01*
G01X646151Y1092802D01*
G02X646166Y1092726I-185J-76D01*
G01Y1091183D01*
G02X646107Y1091041I-200J0D01*
G01X644997Y1089931D01*
X644876Y1089907D01*
X644820Y1089932D01*
G03X644639Y1090004I-1504J-3518D01*
G02X644509Y1090187I70J187D01*
G03X642105I-1202J-30D01*
G02X641975Y1090004I-200J4D01*
G03X641369Y1089716I1333J-3587D01*
G01X641320Y1089688D01*
X641211Y1089689D01*
X640814Y1089932D01*
X640763Y1090029D01*
X640767Y1090085D01*
G03X640769Y1090157I-1200J69D01*
G03X638365I-1202J0D01*
G03X638367Y1090085I1202J-3D01*
G01X638371Y1090029D01*
X638320Y1089932D01*
X637923Y1089689D01*
X637814Y1089688D01*
X637765Y1089716D01*
G03X637159Y1090004I-1939J-3299D01*
G02X637029Y1090187I70J187D01*
G03X634625I-1202J-30D01*
G02X634495Y1090004I-200J4D01*
G03X633888Y1089716I1330J-3588D01*
G01X633839Y1089687D01*
X633730Y1089688D01*
X633333Y1089931D01*
X633282Y1090029D01*
X633286Y1090085D01*
G03X633288Y1090157I-1200J69D01*
G03X630884I-1202J0D01*
G03X630967Y1089717I1202J-1D01*
G01X630986Y1089671D01*
X630974Y1089573D01*
X630760Y1089258D01*
G02X630595Y1089171I-165J113D01*
G01X629837D01*
G02X629672Y1089258I0J200D01*
G01X629458Y1089573D01*
X629446Y1089671D01*
X629465Y1089717D01*
G03X629548Y1090157I-1119J439D01*
G03X628346Y1091359I-1202J0D01*
G03X628124Y1091338I2J-1202D01*
G01X628075Y1091329D01*
X627982Y1091358D01*
X627677Y1091663D01*
X627648Y1091756D01*
X627657Y1091805D01*
G03X627678Y1092027I-1181J224D01*
G03X627657Y1092249I-1202J-2D01*
G01X627648Y1092298D01*
X627677Y1092391D01*
X627982Y1092696D01*
X628075Y1092725D01*
X628124Y1092716D01*
G03X628346Y1092695I224J1181D01*
G03Y1095099I0J1202D01*
G03X628124Y1095078I2J-1202D01*
G01X628075Y1095069D01*
X627982Y1095098D01*
X627677Y1095403D01*
X627648Y1095496D01*
X627657Y1095545D01*
G03X627678Y1095767I-1181J224D01*
G03X627657Y1095989I-1202J-2D01*
G01X627648Y1096038D01*
X627677Y1096131D01*
X627982Y1096436D01*
X628075Y1096465D01*
X628124Y1096456D01*
G03X628346Y1096435I224J1181D01*
G03X629548Y1097637I0J1202D01*
G03X629527Y1097859I-1202J-2D01*
G01X629518Y1097908D01*
X629547Y1098001D01*
X629852Y1098306D01*
X629945Y1098335D01*
X629994Y1098326D01*
G03X630216Y1098305I224J1181D01*
G03X630438Y1098326I-2J1202D01*
G01X630487Y1098335D01*
X630580Y1098306D01*
X630885Y1098001D01*
X630914Y1097908D01*
X630905Y1097859D01*
G03X630884Y1097637I1181J-224D01*
G03X632086Y1098839I1202J0D01*
G03X631864Y1098818I2J-1202D01*
G01X631815Y1098809D01*
X631722Y1098838D01*
X631417Y1099143D01*
X631388Y1099236D01*
X631397Y1099285D01*
G03X631418Y1099507I-1181J224D01*
G03X631397Y1099729I-1202J-2D01*
G01X631388Y1099778D01*
X631417Y1099871D01*
X631722Y1100176D01*
X631815Y1100205D01*
X631864Y1100196D01*
G03X632086Y1100175I224J1181D01*
G03Y1102579I0J1202D01*
G03X631864Y1102558I2J-1202D01*
G01X631815Y1102549D01*
X631722Y1102578D01*
X631417Y1102883D01*
X631388Y1102976D01*
X631397Y1103025D01*
G03X631418Y1103247I-1181J224D01*
G03X631397Y1103469I-1202J-2D01*
G01X631388Y1103518D01*
X631417Y1103611D01*
X631722Y1103916D01*
X631815Y1103945D01*
X631864Y1103936D01*
G03X632086Y1103915I224J1181D01*
G03X630884Y1105117I0J1202D01*
G03X630905Y1104895I1202J2D01*
G01X630914Y1104846D01*
X630885Y1104753D01*
X630580Y1104448D01*
X630487Y1104419D01*
X630438Y1104428D01*
G03X630216Y1104449I-224J-1181D01*
G03Y1102045I0J-1202D01*
G03X630438Y1102066I-2J1202D01*
G01X630487Y1102075D01*
X630580Y1102046D01*
X630885Y1101741D01*
X630914Y1101648D01*
X630905Y1101599D01*
G03X630884Y1101377I1181J-224D01*
G03X630905Y1101155I1202J2D01*
G01X630914Y1101106D01*
X630885Y1101013D01*
X630580Y1100708D01*
X630487Y1100679D01*
X630438Y1100688D01*
G03X630216Y1100709I-224J-1181D01*
G03X629014Y1099507I0J-1202D01*
G03X629035Y1099285I1202J2D01*
G01X629044Y1099236D01*
X629015Y1099143D01*
X628710Y1098838D01*
X628617Y1098809D01*
X628568Y1098818D01*
G03X628346Y1098839I-224J-1181D01*
G03X628124Y1098818I2J-1202D01*
G01X628075Y1098809D01*
X627982Y1098838D01*
X627677Y1099143D01*
X627648Y1099236D01*
X627657Y1099285D01*
G03X627678Y1099507I-1181J224D01*
G03X626476Y1098305I-1202J0D01*
G03X626698Y1098326I-2J1202D01*
G01X626747Y1098335D01*
X626840Y1098306D01*
X627145Y1098001D01*
X627174Y1097908D01*
X627165Y1097859D01*
G03X627144Y1097637I1181J-224D01*
G03X627165Y1097415I1202J2D01*
G01X627174Y1097366D01*
X627145Y1097273D01*
X626840Y1096968D01*
X626747Y1096939D01*
X626698Y1096948D01*
G03X626476Y1096969I-224J-1181D01*
G03Y1094565I0J-1202D01*
G03X626698Y1094586I-2J1202D01*
G01X626747Y1094595D01*
X626840Y1094566D01*
X627145Y1094261D01*
X627174Y1094168D01*
X627165Y1094119D01*
G03X627144Y1093897I1181J-224D01*
G03X627165Y1093675I1202J2D01*
G01X627174Y1093626D01*
X627145Y1093533D01*
X626840Y1093228D01*
X626747Y1093199D01*
X626698Y1093208D01*
G03X626476Y1093229I-224J-1181D01*
G03Y1090825I0J-1202D01*
G03X626698Y1090846I-2J1202D01*
G01X626747Y1090855D01*
X626840Y1090826D01*
X627145Y1090521D01*
X627174Y1090428D01*
X627165Y1090379D01*
G03X627144Y1090157I1181J-224D01*
G03X627165Y1089935I1202J2D01*
G01X627174Y1089886D01*
X627145Y1089793D01*
X626840Y1089488D01*
X626747Y1089459D01*
X626698Y1089468D01*
G03X626476Y1089489I-224J-1181D01*
G03X625274Y1088287I0J-1202D01*
G03X625781Y1087306I1203J0D01*
G01X625817Y1087280D01*
X625861Y1087205D01*
X625890Y1086856D01*
G02X625832Y1086697I-199J-17D01*
G01X624326Y1085191D01*
G02X624167Y1085133I-142J141D01*
G01X623818Y1085162D01*
X623743Y1085206D01*
X623717Y1085242D01*
G03X622736Y1085749I-981J-696D01*
G03X621534Y1084547I0J-1202D01*
G03X622041Y1083566I1203J0D01*
G01X622077Y1083540D01*
X622121Y1083465D01*
X622150Y1083116D01*
G02X622092Y1082957I-199J-17D01*
G01X621940Y1082805D01*
G03X621881Y1082663I141J-142D01*
G01Y1081730D01*
G02X621831Y1081599I-200J1D01*
G03X621534Y1080807I905J-791D01*
G03X621831Y1080015I1202J-1D01*
G02X621881Y1079884I-150J-132D01*
G01Y1077989D01*
G02X621831Y1077858I-200J1D01*
G03X621534Y1077066I905J-791D01*
G03X621831Y1076274I1202J-1D01*
G02X621881Y1076143I-150J-132D01*
G01Y1074249D01*
G02X621831Y1074118I-200J1D01*
G03X621534Y1073326I905J-791D01*
G03X621831Y1072534I1202J-1D01*
G02X621881Y1072403I-150J-132D01*
G01Y1048526D01*
G02X621790Y1048358I-200J0D01*
G01X621467Y1048147D01*
X621367Y1048139D01*
X621320Y1048160D01*
G03X620715Y1048287I-604J-1375D01*
G03Y1045283I0J-1502D01*
G03X621320Y1045410I1J1502D01*
G01X621367Y1045431D01*
X621467Y1045423D01*
X621790Y1045212D01*
G02X621881Y1045044I-109J-168D01*
G01Y1041723D01*
G02X621759Y1041538I-200J-1D01*
G01X621363Y1041372D01*
X621245Y1041394D01*
X621201Y1041437D01*
G03X620151Y1041865I-1050J-1074D01*
G03Y1038861I0J-1502D01*
G03X621201Y1039289I0J1502D01*
G01X621245Y1039332D01*
X621363Y1039354D01*
X621759Y1039188D01*
G02X621881Y1039003I-78J-184D01*
G01Y1037998D01*
G03X621874Y1037778I3920J-235D01*
G01Y1035760D01*
G02X621820Y1035623I-200J0D01*
G01X621606Y1035396D01*
X621537Y1035363D01*
X621499Y1035361D01*
G03X620090Y1033862I93J-1499D01*
G03X620860Y1032550I1503J0D01*
G01X620910Y1032523D01*
X620964Y1032426D01*
X620949Y1031957D01*
X620888Y1031864D01*
X620836Y1031840D01*
G03X619977Y1030482I644J-1358D01*
G03X621481Y1028980I1502J0D01*
G01X621521D01*
X621594Y1028950D01*
X621822Y1028722D01*
G02X621881Y1028580I-141J-142D01*
G01Y1024883D01*
G02X621822Y1024741I-200J0D01*
G01X617186Y1020105D01*
G02X617044Y1020046I-142J141D01*
G01X556564D01*
G02X556422Y1020105I0J200D01*
G01X554870Y1021657D01*
G02X554811Y1021799I141J142D01*
G01Y1030759D01*
G02X554870Y1030901I200J0D01*
G01X556808Y1032839D01*
G02X556950Y1032898I142J-141D01*
G01X589166D01*
G03X589308Y1032957I0J200D01*
G01X590285Y1033934D01*
G02X590426Y1033993I142J-141D01*
G01X590747Y1033995D01*
X590819Y1033965D01*
X590848Y1033937D01*
G03X591898Y1033509I1050J1074D01*
G03X593400Y1035011I0J1502D01*
G03X592972Y1036061I-1502J0D01*
G01X592944Y1036090D01*
X592914Y1036162D01*
X592916Y1036483D01*
G02X592975Y1036624I200J-1D01*
G01X606018Y1049667D01*
G03X606077Y1049809I-141J142D01*
G01Y1100139D01*
G02X606136Y1100281I200J0D01*
G01X607882Y1102027D01*
X607938Y1102056D01*
X607969Y1102061D01*
G03X608962Y1103054I-193J1186D01*
G01X608967Y1103085D01*
X608996Y1103141D01*
X611623Y1105768D01*
X611679Y1105797D01*
X611710Y1105802D01*
G03X612702Y1106794I-194J1186D01*
G01X612707Y1106825D01*
X612736Y1106881D01*
X615363Y1109508D01*
X615419Y1109537D01*
X615450Y1109542D01*
G03X616442Y1110534I-194J1186D01*
G01X616447Y1110565D01*
X616476Y1110621D01*
X619103Y1113248D01*
X619159Y1113277D01*
X619190Y1113282D01*
G03X620182Y1114274I-194J1186D01*
G01X620187Y1114305D01*
X620216Y1114361D01*
X622843Y1116988D01*
X622899Y1117017D01*
X622930Y1117022D01*
G03X623922Y1118014I-194J1186D01*
G01X623927Y1118045D01*
X623956Y1118101D01*
X626583Y1120728D01*
X626639Y1120757D01*
X626670Y1120762D01*
G03X627662Y1121754I-194J1186D01*
G01X627667Y1121785D01*
X627696Y1121841D01*
X634064Y1128209D01*
X634120Y1128238D01*
X634151Y1128243D01*
G03X635143Y1129235I-194J1186D01*
G01X635148Y1129266D01*
X635177Y1129322D01*
X637804Y1131949D01*
X637860Y1131978D01*
X637891Y1131983D01*
G03X638883Y1132975I-194J1186D01*
G01X638888Y1133006D01*
X638917Y1133062D01*
X641544Y1135689D01*
X641600Y1135718D01*
X641631Y1135723D01*
G03X642623Y1136715I-194J1186D01*
G01X642628Y1136746D01*
X642657Y1136802D01*
X643858Y1138003D01*
G03X643917Y1138145I-141J142D01*
G01X643992Y1138220D01*
X644322D01*
G02X644522Y1138020I0J-200D01*
G01Y1137973D01*
X644481Y1137890D01*
X644444Y1137862D01*
G03X643975Y1136909I734J-953D01*
G03X646379I1202J0D01*
G03X646166Y1137593I-1202J1D01*
G01X646134Y1137639D01*
X646127Y1137750D01*
X646318Y1138113D01*
G02X646495Y1138220I177J-93D01*
G37*
G36*
G01X584103Y943307D02*
X584603Y943807D01*
X592603D01*
X594103Y942307D01*
Y930807D01*
X593103Y929807D01*
X585103D01*
X584103Y930807D01*
Y943307D01*
G37*
G36*
G01X697106Y54588D02*
X725589D01*
X725942Y54235D01*
Y52944D01*
X725589Y52591D01*
X697106D01*
G03X691169Y46654I0J-5937D01*
G01Y7874D01*
G02X685295Y2000I-5874J0D01*
G01X638051D01*
G02X632177Y7874I0J5874D01*
G01Y45760D01*
X634174D01*
Y7874D01*
G03X638049Y3998I3876J0D01*
G01X685295D01*
G03X689172Y7874I0J3877D01*
G01Y46654D01*
G02X697106Y54588I7934J0D01*
G37*
G36*
G01X690127Y1221504D02*
X690176Y1221532D01*
X690285Y1221531D01*
X690682Y1221288D01*
X690733Y1221191D01*
X690729Y1221135D01*
G03X690727Y1221062I1200J-69D01*
G03X691929Y1219860I1202J0D01*
G03X692150Y1219880I3J1202D01*
G01X692200Y1219890D01*
X692292Y1219861D01*
X692597Y1219556D01*
X692626Y1219463D01*
X692617Y1219414D01*
G03X692596Y1219192I1182J-224D01*
G03X693799Y1217989I1203J0D01*
G03X694021Y1218010I-2J1203D01*
G01X694070Y1218019D01*
X694163Y1217990D01*
X694468Y1217685D01*
X694497Y1217593D01*
X694487Y1217543D01*
G03X694467Y1217322I1182J-218D01*
G03X694488Y1217100I1202J2D01*
G01X694497Y1217051D01*
X694468Y1216958D01*
X694163Y1216653D01*
X694070Y1216624D01*
X694021Y1216633D01*
G03X693799Y1216654I-224J-1181D01*
G03X695001Y1215452I0J-1202D01*
G03X694980Y1215674I-1202J-2D01*
G01X694971Y1215723D01*
X695000Y1215816D01*
X695305Y1216121D01*
X695398Y1216150D01*
X695447Y1216141D01*
G03X695669Y1216120I224J1181D01*
G03X695891Y1216141I-2J1202D01*
G01X695940Y1216150D01*
X696033Y1216121D01*
X696338Y1215816D01*
X696367Y1215723D01*
X696358Y1215674D01*
G03X696337Y1215452I1181J-224D01*
G03X698741I1202J0D01*
G03X698720Y1215674I-1202J-2D01*
G01X698711Y1215723D01*
X698740Y1215816D01*
X699045Y1216121D01*
X699138Y1216150D01*
X699187Y1216141D01*
G03X699409Y1216120I224J1181D01*
G03X699631Y1216141I-2J1202D01*
G01X699680Y1216150D01*
X699773Y1216121D01*
X700078Y1215816D01*
X700107Y1215723D01*
X700098Y1215674D01*
G03X700077Y1215452I1181J-224D01*
G03X701279Y1216654I1202J0D01*
G03X701057Y1216633I2J-1202D01*
G01X701008Y1216624D01*
X700915Y1216653D01*
X700610Y1216958D01*
X700581Y1217051D01*
X700590Y1217100D01*
G03X700611Y1217322I-1181J224D01*
G03X700590Y1217544I-1202J-2D01*
G01X700581Y1217593D01*
X700610Y1217686D01*
X700915Y1217991D01*
X701008Y1218020D01*
X701057Y1218011D01*
G03X701279Y1217990I224J1181D01*
G03X702481Y1219187I0J1202D01*
G01Y1219194D01*
G03X702478Y1219282I-1202J3D01*
G01X702477Y1219289D01*
Y1219292D01*
G02X702497Y1219394I199J14D01*
G01Y1219395D01*
G02X702570Y1219476I179J-88D01*
G01X702856Y1219656D01*
G02X702858Y1219657I90J-178D01*
G01X702867Y1219662D01*
G02X702971Y1219692I105J-170D01*
G01X703026D01*
X703052Y1219677D01*
X703077Y1219670D01*
X703101Y1219656D01*
G03X703687Y1219378I1914J3278D01*
G01X703747Y1219355D01*
X703817Y1219254D01*
Y1219191D01*
G03X705019Y1217990I1202J1D01*
G03X706221Y1219164I0J1202D01*
G01X706222Y1219192D01*
X706240Y1219252D01*
G02X706286Y1219330I191J-60D01*
G01X706319Y1219365D01*
X706362Y1219381D01*
G03X706943Y1219658I-1337J3553D01*
G01X706968Y1219673D01*
X707017Y1219686D01*
G02X707170Y1219663I49J-194D01*
G01X707172Y1219662D01*
X707516Y1219447D01*
X707566Y1219348D01*
X707561Y1219291D01*
G03X707557Y1219194I1199J-98D01*
G01Y1219192D01*
G03X709963I1203J0D01*
G03X709959Y1219292I-1203J2D01*
G01X709954Y1219348D01*
X710004Y1219447D01*
X710145Y1219536D01*
X710146D01*
X710402Y1219695D01*
X710513Y1219696D01*
X710562Y1219667D01*
G03X711168Y1219377I1935J3266D01*
G02X711298Y1219190I-70J-187D01*
G03X713702I1202J2D01*
G02X713706Y1219228I200J-2D01*
G02X713832Y1219377I196J-38D01*
G03X714302Y1219589I-1323J3559D01*
G01X714303Y1219590D01*
X714326Y1219602D01*
X714373Y1219614D01*
X714483D01*
G02X714577Y1219591I1J-200D01*
G01X714593Y1219582D01*
X714844Y1219427D01*
G02X714939Y1219249I-105J-170D01*
G01Y1219231D01*
G03X714938Y1219193I1301J-53D01*
G01Y1219191D01*
G03X716240Y1217890I1302J1D01*
G03X717542Y1219192I0J1302D01*
G03X717541Y1219247I-1302J4D01*
G01Y1219248D01*
G02X717635Y1219425I200J7D01*
G01X717862Y1219566D01*
X717864D01*
X717930Y1219608D01*
G02X718033Y1219639I107J-169D01*
G01X718088Y1219640D01*
X718131Y1219616D01*
X718133D01*
X718178Y1219591D01*
G03X718301Y1219527I1813J3335D01*
G03X718533Y1219422I1680J3404D01*
G01X718553Y1219413D01*
X718646Y1219348D01*
G02X718722Y1219123I-114J-164D01*
G01X718689Y1219022D01*
G03X719980Y1217890I1291J170D01*
G03X721282Y1219192I0J1302D01*
G01Y1219222D01*
G02X721367Y1219385I200J-1D01*
G01X721407Y1219414D01*
X721429Y1219423D01*
G03X721641Y1219518I-1446J3510D01*
G03X721823Y1219612I-1651J3419D01*
G02X721825Y1219614I137J-135D01*
G01X721848Y1219626D01*
X721897Y1219638D01*
X721925Y1219637D01*
G02X722025Y1219608I-4J-200D01*
G01X722199Y1219502D01*
X722201D01*
X722324Y1219426D01*
G02X722419Y1219248I-105J-170D01*
G01Y1219247D01*
G03X722418Y1219194I1301J-51D01*
G01Y1219191D01*
G03X723720Y1217890I1302J1D01*
G03X725022Y1219192I0J1302D01*
G03X725021Y1219247I-1302J4D01*
G01Y1219248D01*
G02X725115Y1219425I200J7D01*
G01X725342Y1219566D01*
X725344D01*
X725400Y1219603D01*
G02X725420Y1219614I106J-170D01*
G01X725428Y1219618D01*
G02X725517Y1219639I89J-179D01*
G01X725572D01*
X725622Y1219625D01*
X725646Y1219611D01*
G03X725985Y1219433I1932J3267D01*
G01X726010Y1219421D01*
X726051Y1219386D01*
X726095Y1219322D01*
X726124Y1219279D01*
G02X726150Y1219226I-165J-114D01*
G01X726158Y1219199D01*
X726159Y1219169D01*
Y1219168D01*
G03X728763Y1219169I1302J24D01*
G01X728764Y1219198D01*
X728781Y1219253D01*
X728824Y1219317D01*
X728825Y1219319D01*
X728854Y1219362D01*
G03X728856Y1219364I-140J142D01*
G01X728871Y1219387D01*
X728915Y1219424D01*
X728943Y1219436D01*
G03X729126Y1219520I-1492J3492D01*
G03X729306Y1219613I-1652J3419D01*
G01X729352Y1219639D01*
X729457Y1219638D01*
X729540Y1219590D01*
G02X729546Y1219587I-86J-180D01*
G01X729805Y1219426D01*
G02X729900Y1219249I-105J-170D01*
G01Y1219244D01*
G03X729899Y1219192I1301J-51D01*
G03X732503I1302J0D01*
G03X732502Y1219247I-1302J4D01*
G01Y1219248D01*
G02X732596Y1219425I200J7D01*
G01X732823Y1219566D01*
X732825D01*
X732891Y1219608D01*
G02X732994Y1219639I107J-169D01*
G01X733049Y1219640D01*
X733092Y1219616D01*
X733094D01*
X733139Y1219591D01*
G03X733262Y1219527I1813J3335D01*
G03X733494Y1219422I1680J3404D01*
G01X733514Y1219413D01*
X733607Y1219348D01*
G02X733683Y1219123I-114J-164D01*
G01X733650Y1219022D01*
G03X734941Y1217890I1291J170D01*
G03X736243Y1219192I0J1302D01*
G01Y1219222D01*
G02X736328Y1219385I200J-1D01*
G01X736368Y1219414D01*
X736390Y1219423D01*
G03X736602Y1219518I-1446J3510D01*
G03X736784Y1219612I-1651J3419D01*
G02X736786Y1219614I137J-135D01*
G01X736809Y1219626D01*
X736858Y1219638D01*
X736886Y1219637D01*
G02X736986Y1219608I-4J-200D01*
G01X737160Y1219502D01*
X737162D01*
X737285Y1219426D01*
G02X737380Y1219248I-105J-170D01*
G01Y1219247D01*
G03X737379Y1219194I1301J-51D01*
G01Y1219191D01*
G03X738681Y1217890I1302J1D01*
G03X739983Y1219192I0J1302D01*
G03X739982Y1219247I-1302J4D01*
G01Y1219248D01*
G02X740076Y1219425I200J7D01*
G01X740303Y1219566D01*
X740305D01*
X740371Y1219608D01*
G02X740474Y1219639I107J-169D01*
G01X740529Y1219640D01*
X740572Y1219616D01*
X740574D01*
X740619Y1219591D01*
G03X740742Y1219527I1813J3335D01*
G03X740974Y1219422I1680J3404D01*
G01X740994Y1219413D01*
X741087Y1219348D01*
G02X741163Y1219123I-114J-164D01*
G01X741130Y1219022D01*
G03X742421Y1217890I1291J170D01*
G03X743723Y1219192I0J1302D01*
G01Y1219226D01*
G02X743818Y1219396I200J0D01*
G01X743848Y1219414D01*
X743863Y1219420D01*
G03X744360Y1219669I-1447J3509D01*
G02X744566Y1219668I102J-172D01*
G01X744568Y1219667D01*
X744917Y1219448D01*
X744967Y1219349D01*
X744962Y1219292D01*
G03X744958Y1219192I1199J-98D01*
G03X746161Y1217989I1203J0D01*
G03X746261Y1217993I2J1203D01*
G01X746317Y1217998D01*
X746416Y1217948D01*
X746505Y1217807D01*
Y1217806D01*
X746664Y1217550D01*
X746665Y1217439D01*
X746637Y1217390D01*
G03X746388Y1216890I3264J-1938D01*
G01X746387Y1216887D01*
X746381Y1216874D01*
G02X746261Y1216764I-183J80D01*
G01X746230Y1216754D01*
X746161D01*
G03X744859Y1215452I0J-1302D01*
G03X746081Y1214152I1302J0D01*
G01X746133Y1214149D01*
X746337Y1214019D01*
X746341Y1214016D01*
X746377Y1213992D01*
X746415Y1213948D01*
X746426Y1213921D01*
G03X746582Y1213608I3473J1535D01*
G01X746608Y1213560D01*
X746606Y1213453D01*
X746471Y1213232D01*
X746395Y1213108D01*
G02X746217Y1213013I-170J105D01*
G01X746216D01*
G03X746163Y1213014I-51J-1301D01*
G01X746160D01*
G03X744859Y1211712I1J-1302D01*
G03X746161Y1210410I1302J0D01*
G03X746216Y1210411I4J1302D01*
G01X746217D01*
G02X746394Y1210317I7J-200D01*
G01X746535Y1210090D01*
Y1210088D01*
X746577Y1210022D01*
G02X746608Y1209919I-169J-107D01*
G01X746609Y1209864D01*
X746583Y1209816D01*
X746582Y1209815D01*
G03X746382Y1209399I3316J-1850D01*
G02X746197Y1209274I-185J75D01*
G01X746161D01*
G03X744859Y1207972I0J-1302D01*
G03X746081Y1206672I1302J0D01*
G01X746133Y1206669D01*
X746337Y1206539D01*
X746341Y1206536D01*
X746377Y1206512D01*
X746415Y1206468D01*
X746426Y1206441D01*
G03X746582Y1206128I3473J1535D01*
G01X746608Y1206080D01*
X746606Y1205973D01*
X746471Y1205752D01*
X746395Y1205628D01*
G02X746217Y1205533I-170J105D01*
G01X746216D01*
G03X746163Y1205534I-51J-1301D01*
G01X746160D01*
G03Y1202930I1J-1302D01*
G01X746163D01*
G03X746285Y1202935I8J1302D01*
G03X746319Y1202907I143J138D01*
G01X746320D01*
X746389Y1202873D01*
G02X746499Y1202700I-90J-179D01*
G01X746500Y1202667D01*
X746607Y1202491D01*
X746609Y1202384D01*
X746583Y1202337D01*
G03X746388Y1201929I3322J-1838D01*
G01X746387Y1201926D01*
X746381Y1201913D01*
G02X746261Y1201803I-183J80D01*
G01X746230Y1201793D01*
X746161D01*
G03X744859Y1200491I0J-1302D01*
G03X746081Y1199191I1302J0D01*
G01X746133Y1199188D01*
X746337Y1199058D01*
X746341Y1199055D01*
X746377Y1199031D01*
X746415Y1198987D01*
X746426Y1198960D01*
G03X746582Y1198647I3473J1535D01*
G01X746608Y1198599D01*
X746606Y1198492D01*
X746471Y1198271D01*
X746395Y1198147D01*
G02X746217Y1198052I-170J105D01*
G01X746216D01*
G03X746163Y1198053I-51J-1301D01*
G01X746160D01*
G03X744859Y1196751I1J-1302D01*
G03X746161Y1195449I1302J0D01*
G03X746375Y1195467I-2J1302D01*
G01X746422Y1195475D01*
X746511Y1195447D01*
X746812Y1195160D01*
X746843Y1195072D01*
X746838Y1195024D01*
G03X746829Y1194881I1193J-147D01*
G03X749233I1202J0D01*
G03X749163Y1195286I-1202J1D01*
G02X749424Y1195539I188J67D01*
G03X749539Y1195500I475J1212D01*
G02X749597Y1195473I-54J-192D01*
G03X750440Y1195034I2175J3148D01*
G02X750570Y1194851I-70J-187D01*
G03X751772Y1193679I1202J30D01*
G03X752951Y1194647I0J1202D01*
G02X753131Y1194807I196J-39D01*
G03X753601Y1194876I-320J3813D01*
G02X753683I41J-196D01*
G03X754153Y1194807I790J3744D01*
G02X754333Y1194647I-16J-199D01*
G03X755512Y1193679I1179J234D01*
G03X756714Y1194851I0J1202D01*
G02X756844Y1195034I200J-4D01*
G03X757688Y1195473I-1330J3588D01*
G02X757746Y1195501I115J-164D01*
G03X758551Y1196178I-364J1250D01*
G01X758576Y1196229D01*
X758673Y1196290D01*
X759831D01*
X759928Y1196229D01*
X759953Y1196178D01*
G03X762291I1169J573D01*
G01X762316Y1196229D01*
X762413Y1196290D01*
X763571D01*
X763668Y1196229D01*
X763693Y1196178D01*
G03X764862Y1195449I1169J573D01*
G03X765076Y1195467I-2J1302D01*
G01X765123Y1195475D01*
X765212Y1195447D01*
X765513Y1195160D01*
X765544Y1195072D01*
X765539Y1195024D01*
G03X765530Y1194881I1193J-147D01*
G03X766732Y1193679I1202J0D01*
G03X766954Y1193700I-2J1202D01*
G01X767003Y1193709D01*
X767096Y1193680D01*
X767401Y1193375D01*
X767430Y1193282D01*
X767421Y1193233D01*
G03X767400Y1193011I1181J-224D01*
G03X768602Y1194213I1202J0D01*
G03X768380Y1194192I2J-1202D01*
G01X768331Y1194183D01*
X768238Y1194212D01*
X767933Y1194517D01*
X767904Y1194610D01*
X767913Y1194659D01*
G03X767934Y1194881I-1181J224D01*
G03X767925Y1195024I-1202J-4D01*
G01X767920Y1195072D01*
X767951Y1195160D01*
X768252Y1195447D01*
X768341Y1195475D01*
X768388Y1195467D01*
G03X768602Y1195449I216J1284D01*
G03X769771Y1196178I0J1302D01*
G01X769796Y1196229D01*
X769893Y1196290D01*
X771051D01*
X771148Y1196229D01*
X771173Y1196178D01*
G03X773511I1169J573D01*
G01X773536Y1196229D01*
X773633Y1196290D01*
X774792D01*
X774889Y1196229D01*
X774914Y1196178D01*
G03X777252I1169J573D01*
G01X777277Y1196229D01*
X777374Y1196290D01*
X778531D01*
X778628Y1196229D01*
X778653Y1196177D01*
G03X779823Y1195448I1170J574D01*
G01X783563D01*
G03X784507Y1195853I0J1303D01*
G01X784531Y1195879D01*
X784595Y1195911D01*
G02X784684Y1195932I89J-179D01*
G01X784959D01*
G02X785106Y1195868I0J-200D01*
G03X786063Y1195449I957J883D01*
G03X787077Y1195935I0J1301D01*
G02X787233Y1196010I156J-125D01*
G01X791204D01*
G03X792047Y1196101I3J3926D01*
G01X792094Y1196111D01*
X792186Y1196088D01*
X792501Y1195807D01*
X792535Y1195719D01*
X792530Y1195671D01*
G03X792523Y1195522I1495J-145D01*
G03X794025Y1194020I1502J0D01*
G03X794891Y1194295I0J1502D01*
G02X794950Y1194323I114J-164D01*
G03X795943Y1195248I-417J1443D01*
G02X796036Y1195355I188J-69D01*
G01X796143Y1195413D01*
G02X796284Y1195432I95J-176D01*
G03X796626Y1195392I344J1462D01*
G01X796644D01*
G03X798129Y1196894I-17J1502D01*
G03X797733Y1197910I-1501J0D01*
G01X797714Y1197931D01*
X797688Y1197983D01*
X797683Y1198014D01*
G02X797697Y1198129I197J34D01*
G01X797799Y1198358D01*
G02X797905Y1198462I183J-81D01*
G01X798156Y1198566D01*
G02X798233Y1198581I76J-185D01*
G01X803534D01*
X803641Y1198549D01*
X803664Y1198535D01*
G03X805240I788J1280D01*
G01X805263Y1198549D01*
X805370Y1198581D01*
X845117D01*
X845144Y1198554D01*
X855723D01*
G02X855756Y1198551I-2J-200D01*
G02X855863Y1198497I-32J-197D01*
G01X857649Y1196711D01*
G03X857791Y1196652I142J141D01*
G01X913312D01*
G02X913345Y1196649I-2J-200D01*
G02X913452Y1196595I-32J-197D01*
G01X914580Y1195467D01*
G02X914639Y1195325I-141J-142D01*
G01Y1134224D01*
X914540Y1134111D01*
X914465Y1134101D01*
G03X913159Y1132612I196J-1489D01*
G03X913659Y1131493I1502J0D01*
G01X913661Y1131491D01*
X913678Y1131475D01*
X913710Y1131430D01*
G02X913745Y1131291I-164J-115D01*
G01X913708Y1130973D01*
G02X913602Y1130819I-199J23D01*
G03X913284Y1130596I696J-1331D01*
G01Y1130595D01*
G03X913272Y1130584I1009J-1113D01*
G02X913209Y1130544I-137J146D01*
G01X913173Y1130530D01*
X912824D01*
X912754Y1130557D01*
X912726Y1130584D01*
G03X911699Y1130990I-1027J-1096D01*
G03X910197Y1129488I0J-1502D01*
G03X910804Y1128282I1502J0D01*
G01X910823Y1128268D01*
X910852Y1128234D01*
X910903Y1128134D01*
G02X910925Y1128039I-178J-91D01*
G01X910920Y1127758D01*
G02X910847Y1127607I-200J4D01*
G01X910827Y1127590D01*
X910818Y1127584D01*
G03X910614Y1127424I821J-1257D01*
G02X910551Y1127384I-137J146D01*
G01X910515Y1127370D01*
X910166D01*
X910096Y1127397D01*
X910068Y1127424D01*
G03X909041Y1127830I-1027J-1096D01*
G03X907539Y1126328I0J-1502D01*
G03X907700Y1125652I1502J1D01*
G01X907708Y1125635D01*
X907721Y1125611D01*
G02X907743Y1125539I-177J-93D01*
G01X907747Y1125500D01*
X907668Y1125199D01*
X907645Y1125168D01*
X907581Y1125081D01*
X907550Y1125061D01*
G03X907347Y1124902I821J-1258D01*
G01X907320Y1124875D01*
X907247Y1124845D01*
X906896D01*
X906826Y1124872D01*
X906798Y1124899D01*
G03X904744I-1027J-1096D01*
G01X904716Y1124872D01*
X904646Y1124845D01*
X904296D01*
X904226Y1124872D01*
X904198Y1124899D01*
G03X903171Y1125305I-1027J-1096D01*
G03Y1122301I0J-1502D01*
G03X904198Y1122707I0J1502D01*
G01X904226Y1122734D01*
X904296Y1122761D01*
X904646D01*
X904716Y1122734D01*
X904744Y1122707D01*
G03X906798I1027J1096D01*
G01X906826Y1122734D01*
X906896Y1122761D01*
X907246D01*
X907316Y1122734D01*
X907344Y1122707D01*
G03X908371Y1122301I1027J1096D01*
G03X909437Y1122745I0J1502D01*
G01X909465Y1122773D01*
X909539Y1122804D01*
X909903D01*
X909977Y1122773D01*
X910005Y1122745D01*
G03X911071Y1122301I1066J1058D01*
G03X912573Y1123784I0J1502D01*
G01Y1123804D01*
G03X912371Y1124556I-1502J0D01*
G01X912370Y1124557D01*
X912369Y1124560D01*
G02X912348Y1124703I174J99D01*
G01X912407Y1124963D01*
G02X912461Y1125060I195J-45D01*
G01X912489Y1125088D01*
X912503Y1125098D01*
G03X912655Y1125220I-862J1230D01*
G03X912668Y1125232I-1012J1110D01*
G01X912696Y1125259D01*
X912766Y1125286D01*
X913116D01*
X913186Y1125259D01*
X913214Y1125232D01*
G03X914221Y1124826I1027J1096D01*
G01X914240D01*
X914285Y1124817D01*
G02X914386Y1124762I-41J-196D01*
G01X914580Y1124568D01*
G02X914639Y1124426I-141J-142D01*
G01Y1111142D01*
X914609Y1111068D01*
X914580Y1111040D01*
X911432Y1107892D01*
G03X911373Y1107750I141J-142D01*
G01Y1016568D01*
X911343Y1016494D01*
X911314Y1016466D01*
X910653Y1015805D01*
G02X910516Y1015746I-142J141D01*
G01X910397Y1015744D01*
G02X910264Y1015791I-4J200D01*
G03X910002Y1015967I-964J-1152D01*
G01X909959Y1015989D01*
X909905Y1016067D01*
X909844Y1016482D01*
X909874Y1016572D01*
X909909Y1016606D01*
G03X910358Y1017677I-1053J1071D01*
G03X910116Y1018495I-1502J0D01*
G01X910095Y1018527D01*
X910080Y1018600D01*
X910139Y1018944D01*
X910178Y1019007D01*
X910208Y1019031D01*
G03X910798Y1020224I-911J1193D01*
G03X909830Y1021628I-1502J0D01*
G01X909786Y1021645D01*
X909724Y1021711D01*
X909604Y1022104D01*
X909619Y1022195D01*
X909647Y1022233D01*
G03X909924Y1023103I-1225J869D01*
G03X906920I-1502J0D01*
G03X907888Y1021699I1502J0D01*
G01X907932Y1021682D01*
X907994Y1021616D01*
X908114Y1021223D01*
X908099Y1021132D01*
X908071Y1021094D01*
G03X907794Y1020224I1225J-869D01*
G03X908036Y1019406I1502J0D01*
G01X908057Y1019374D01*
X908072Y1019301D01*
X908013Y1018957D01*
X907974Y1018894D01*
X907944Y1018870D01*
G03X907354Y1017677I911J-1193D01*
G03X908154Y1016349I1502J0D01*
G01X908197Y1016327D01*
X908251Y1016249D01*
X908312Y1015834D01*
X908282Y1015744D01*
X908247Y1015710D01*
G03X907798Y1014639I1053J-1071D01*
G03X908148Y1013675I1503J0D01*
G02X908195Y1013542I-153J-129D01*
G01X908193Y1013423D01*
G02X908134Y1013286I-200J5D01*
G01X906610Y1011762D01*
G02X906468Y1011703I-142J141D01*
G01X904657D01*
G03X904515Y1011644I0J-200D01*
G01X902499Y1009628D01*
G03X902456Y1009563I142J-141D01*
G01X902427Y1009495D01*
G02X902384Y1009430I-185J76D01*
G01X893769Y1000815D01*
G02X893627Y1000756I-142J141D01*
G01X788659D01*
X788617Y1000765D01*
X788596Y1000776D01*
G03X787950Y1000922I-646J-1357D01*
G01X787944D01*
G03X787298Y1000776I0J-1503D01*
G01X787277Y1000765D01*
X787235Y1000756D01*
X709659D01*
X709585Y1000786D01*
X709557Y1000815D01*
X703388Y1006984D01*
G02X703337Y1007071I141J141D01*
G01X696487Y1031277D01*
G02X696479Y1031331I192J56D01*
G01Y1071752D01*
G02X696480Y1071766I199J-7D01*
G01Y1071772D01*
G02X696569Y1071925I200J-14D01*
G01X696750Y1072045D01*
X696752D01*
X696827Y1072096D01*
G02X696937Y1072140I126J-156D01*
G01X696962Y1072142D01*
X697011Y1072135D01*
X697035Y1072125D01*
G03X697538Y1072024I503J1201D01*
G01X697539D01*
G03X697752Y1072042I-3J1302D01*
G01X697800Y1072049D01*
X697888Y1072022D01*
X698189Y1071734D01*
X698220Y1071647D01*
X698215Y1071599D01*
G03X698206Y1071455I1193J-147D01*
G03X699408Y1072657I1202J0D01*
G03X699265Y1072648I4J-1202D01*
G01X699218Y1072643D01*
X699130Y1072674D01*
X698843Y1072975D01*
X698815Y1073064D01*
X698823Y1073112D01*
G03X698841Y1073326I-1284J216D01*
G03X698833Y1073473I-1302J3D01*
G01X698828Y1073518D01*
X698857Y1073604D01*
X699142Y1073890D01*
X699227Y1073921D01*
X699272Y1073916D01*
G03X699408Y1073908I144J1280D01*
G03Y1076484I0J1288D01*
G03X699272Y1076476I8J-1288D01*
G01X699227Y1076471D01*
X699142Y1076502D01*
X698857Y1076788D01*
X698828Y1076874D01*
X698833Y1076919D01*
G03X698841Y1077066I-1294J144D01*
G03X698833Y1077213I-1302J3D01*
G01X698828Y1077258D01*
X698857Y1077344D01*
X699142Y1077630D01*
X699227Y1077661D01*
X699272Y1077656D01*
G03X699408Y1077648I144J1280D01*
G03Y1080224I0J1288D01*
G03X699273Y1080216I9J-1287D01*
G01X699227Y1080212D01*
X699142Y1080242D01*
X698858Y1080529D01*
X698828Y1080614D01*
X698834Y1080659D01*
G03X698842Y1080807I-1294J144D01*
G01Y1081084D01*
G02X698908Y1081232I200J0D01*
G01X699161Y1081460D01*
X699241Y1081486D01*
X699284Y1081482D01*
G03X699409Y1081475I130J1195D01*
G03Y1083879I0J1202D01*
G03X699284Y1083872I5J-1202D01*
G01X699241Y1083868D01*
X699161Y1083894D01*
X698908Y1084122D01*
G02X698842Y1084270I134J148D01*
G01Y1084550D01*
G03X698841Y1084608I-1303J7D01*
G01X698840Y1084626D01*
G03X698835Y1084685I-1300J-80D01*
G03X698761Y1085000I-1296J-138D01*
G03X698752Y1085023I-1218J-463D01*
G02X699005Y1085285I186J73D01*
G03X699409Y1085215I404J1131D01*
G03Y1087619I0J1202D01*
G03X699266Y1087610I4J-1202D01*
G01X699218Y1087605D01*
X699130Y1087636D01*
X698843Y1087937D01*
X698815Y1088026D01*
X698823Y1088073D01*
G03X698841Y1088287I-1283J216D01*
G03X698823Y1088501I-1302J-2D01*
G01X698815Y1088548D01*
X698843Y1088637D01*
X699130Y1088938D01*
X699218Y1088969D01*
X699266Y1088964D01*
G03X699409Y1088955I147J1193D01*
G03X698207Y1090157I0J1202D01*
G03X698216Y1090014I1202J4D01*
G01X698221Y1089966D01*
X698190Y1089878D01*
X697889Y1089591D01*
X697800Y1089563D01*
X697753Y1089571D01*
G03X697539Y1089589I-216J-1284D01*
G03X697325Y1089571I2J-1302D01*
G01X697278Y1089563D01*
X697189Y1089591D01*
X696888Y1089878D01*
X696857Y1089966D01*
X696862Y1090014D01*
G03X696871Y1090157I-1193J147D01*
G03X694467I-1202J0D01*
G03X694476Y1090014I1202J4D01*
G01X694481Y1089966D01*
X694450Y1089878D01*
X694149Y1089591D01*
X694060Y1089563D01*
X694013Y1089571D01*
G03X693799Y1089589I-216J-1284D01*
G03X693585Y1089571I2J-1303D01*
G01X693538Y1089563D01*
X693449Y1089591D01*
X693148Y1089878D01*
X693117Y1089966D01*
X693122Y1090014D01*
G03X693131Y1090157I-1193J147D01*
G03X691929Y1091359I-1202J0D01*
G03X690805Y1090582I0J-1201D01*
G01X690786Y1090534D01*
X690711Y1090469D01*
X690331Y1090387D01*
G02X690148Y1090441I-42J196D01*
G01X688720Y1091869D01*
G03X688578Y1091928I-142J-141D01*
G01X687819D01*
G02X687638Y1092042I0J200D01*
G01X687621Y1092079D01*
X687618Y1092117D01*
Y1092118D01*
G03X687603Y1092241I-1298J-96D01*
G01X687596Y1092288D01*
X687623Y1092377D01*
X687910Y1092678D01*
X687998Y1092709D01*
X688046Y1092704D01*
G03X688189Y1092695I147J1193D01*
G03X686987Y1093897I0J1202D01*
G03X686996Y1093754I1202J4D01*
G01X687001Y1093706D01*
X686970Y1093618D01*
X686669Y1093331D01*
X686580Y1093304D01*
X686533Y1093311D01*
G03X686105I-214J-1284D01*
G01X686058Y1093304D01*
X685969Y1093331D01*
X685668Y1093618D01*
X685637Y1093706D01*
X685642Y1093754D01*
G03X685651Y1093897I-1193J147D01*
G03X684449Y1095099I-1202J0D01*
G03X684322Y1095092I3J-1202D01*
G01X684279Y1095088D01*
X684199Y1095114D01*
X683946Y1095341D01*
G02X683880Y1095490I134J149D01*
G01Y1095725D01*
G03X683881Y1095767I-1301J52D01*
G03X683863Y1095981I-1302J-2D01*
G01X683855Y1096028D01*
X683883Y1096117D01*
X684170Y1096418D01*
X684258Y1096449D01*
X684306Y1096444D01*
G03X684449Y1096435I147J1193D01*
G03X683247Y1097637I0J1202D01*
G03X683317Y1097232I1202J-1D01*
G02X683056Y1096979I-188J-67D01*
G03X682904Y1097028I-475J-1213D01*
G03X682577Y1097070I-328J-1261D01*
G03X682365Y1097053I-2J-1303D01*
G01X682318Y1097045D01*
X682229Y1097072D01*
X681928Y1097359D01*
X681897Y1097447D01*
X681903Y1097495D01*
G03X681911Y1097637I-1194J139D01*
G03X680709Y1096435I-1202J0D01*
G03X680850Y1096443I3J1202D01*
G01X680898Y1096449D01*
X680985Y1096417D01*
X681272Y1096117D01*
X681299Y1096028D01*
X681292Y1095981D01*
G03X681274Y1095767I1285J-216D01*
G01Y1095490D01*
G02X681208Y1095342I-200J0D01*
G01X680955Y1095114D01*
X680876Y1095088D01*
X680833Y1095093D01*
G03X680709Y1095099I-120J-1196D01*
G03X679507Y1093897I0J-1202D01*
G03X679516Y1093754I1202J4D01*
G01X679521Y1093706D01*
X679490Y1093618D01*
X679189Y1093331D01*
X679100Y1093303D01*
X679053Y1093311D01*
G03X678624I-214J-1284D01*
G01X678577Y1093304D01*
X678488Y1093331D01*
X678187Y1093618D01*
X678156Y1093706D01*
X678161Y1093754D01*
G03X678170Y1093897I-1193J147D01*
G03X676968Y1095099I-1202J0D01*
G03X676840Y1095092I2J-1202D01*
G01X676798Y1095088D01*
X676718Y1095114D01*
X676464Y1095341D01*
G02X676398Y1095490I134J149D01*
G01Y1095695D01*
X676399Y1095703D01*
Y1095725D01*
G03X676400Y1095767I-1301J52D01*
G03X676382Y1095981I-1303J-2D01*
G01X676374Y1096028D01*
X676402Y1096117D01*
X676689Y1096418D01*
X676777Y1096449D01*
X676825Y1096444D01*
G03X676968Y1096435I147J1193D01*
G03X675766Y1097637I0J1202D01*
G03X675836Y1097233I1201J0D01*
G02X675574Y1096979I-188J-68D01*
G03X675538Y1096993I-490J-1207D01*
G03X675105Y1097070I-441J-1226D01*
G01X675093D01*
G03X675012Y1097068I-8J-1303D01*
G01X675001Y1097067D01*
X674999D01*
G03X674884Y1097053I100J-1298D01*
G01X674837Y1097045D01*
X674748Y1097073D01*
X674447Y1097360D01*
X674416Y1097448D01*
X674422Y1097495D01*
G03X674430Y1097637I-1194J139D01*
G03X673228Y1096435I-1202J0D01*
G03X673370Y1096443I3J1202D01*
G01X673417Y1096449D01*
X673505Y1096418D01*
X673792Y1096117D01*
X673819Y1096028D01*
X673811Y1095981D01*
G03X673794Y1095769I1285J-210D01*
G01Y1095490D01*
G02X673728Y1095342I-200J0D01*
G01X673475Y1095114D01*
X673395Y1095088D01*
X673353Y1095093D01*
G03X673228Y1095099I-120J-1196D01*
G03X672026Y1093897I0J-1202D01*
G03X672035Y1093754I1202J4D01*
G01X672040Y1093706D01*
X672009Y1093618D01*
X671708Y1093331D01*
X671619Y1093304D01*
X671572Y1093311D01*
G03X671144I-214J-1284D01*
G01X671097Y1093304D01*
X671008Y1093331D01*
X670707Y1093618D01*
X670676Y1093706D01*
X670681Y1093754D01*
G03X670690Y1093897I-1193J147D01*
G03X669488Y1095099I-1202J0D01*
G03X669360Y1095092I2J-1202D01*
G01X669318Y1095088D01*
X669238Y1095114D01*
X668984Y1095341D01*
G02X668918Y1095490I134J149D01*
G01Y1095728D01*
G03X668920Y1095767I-1298J86D01*
G01Y1095768D01*
G03X668902Y1095981I-1302J-3D01*
G01X668894Y1096028D01*
X668922Y1096117D01*
X669209Y1096418D01*
X669297Y1096449D01*
X669345Y1096444D01*
G03X669488Y1096435I147J1193D01*
G03X668286Y1097637I0J1202D01*
G03X668356Y1097232I1202J-1D01*
G02X668095Y1096979I-188J-67D01*
G03X667834Y1097051I-475J-1213D01*
G03X667615Y1097070I-222J-1284D01*
G03X667404Y1097053I-1J-1303D01*
G01X667356Y1097045D01*
X667267Y1097072D01*
X666967Y1097360D01*
X666936Y1097447D01*
X666942Y1097495D01*
G03X666950Y1097637I-1194J139D01*
G03X665748Y1096435I-1202J0D01*
G03X665888Y1096443I2J1202D01*
G01X665936Y1096449D01*
X666023Y1096417D01*
X666310Y1096117D01*
X666337Y1096028D01*
X666330Y1095980D01*
G03X666312Y1095767I1285J-216D01*
G01Y1095491D01*
G02X666246Y1095342I-200J-1D01*
G01X665994Y1095114D01*
X665914Y1095088D01*
X665871Y1095093D01*
G03X665748Y1095099I-120J-1196D01*
G03X664546Y1093897I0J-1202D01*
G03X664555Y1093754I1202J4D01*
G01X664560Y1093706D01*
X664529Y1093618D01*
X664228Y1093331D01*
X664139Y1093304D01*
X664092Y1093311D01*
G03X663664I-214J-1284D01*
G01X663617Y1093304D01*
X663528Y1093331D01*
X663227Y1093618D01*
X663196Y1093706D01*
X663201Y1093754D01*
G03X663210Y1093897I-1193J147D01*
G03X662008Y1095099I-1202J0D01*
G03X661880Y1095092I2J-1202D01*
G01X661838Y1095088D01*
X661758Y1095114D01*
X661504Y1095341D01*
G02X661438Y1095490I134J149D01*
G01Y1095728D01*
G03X661440Y1095767I-1298J86D01*
G01Y1095768D01*
G03X661422Y1095981I-1302J-3D01*
G01X661414Y1096028D01*
X661442Y1096117D01*
X661729Y1096418D01*
X661817Y1096449D01*
X661865Y1096444D01*
G03X662008Y1096435I147J1193D01*
G03X660806Y1097637I0J1202D01*
G03X660876Y1097232I1202J-1D01*
G02X660615Y1096979I-188J-67D01*
G03X660354Y1097051I-475J-1213D01*
G03X660135Y1097070I-222J-1284D01*
G03X659924Y1097053I-1J-1303D01*
G01X659876Y1097045D01*
X659787Y1097072D01*
X659487Y1097360D01*
X659456Y1097447D01*
X659462Y1097495D01*
G03X659470Y1097637I-1194J139D01*
G03X658268Y1096435I-1202J0D01*
G03X658408Y1096443I2J1202D01*
G01X658456Y1096449D01*
X658543Y1096417D01*
X658830Y1096117D01*
X658857Y1096028D01*
X658850Y1095980D01*
G03X658832Y1095767I1285J-216D01*
G01Y1095491D01*
G02X658766Y1095342I-200J-1D01*
G01X658514Y1095114D01*
X658434Y1095088D01*
X658391Y1095093D01*
G03X658268Y1095099I-120J-1196D01*
G03X657066Y1093897I0J-1202D01*
G03X657075Y1093754I1202J4D01*
G01X657080Y1093706D01*
X657049Y1093618D01*
X656748Y1093331D01*
X656659Y1093304D01*
X656612Y1093311D01*
G03X656183I-214J-1284D01*
G01X656136Y1093303D01*
X656047Y1093331D01*
X655746Y1093618D01*
X655715Y1093706D01*
X655720Y1093754D01*
G03X655729Y1093897I-1193J147D01*
G03X654527Y1095099I-1202J0D01*
G03X654400Y1095092I3J-1202D01*
G01X654357Y1095088D01*
X654277Y1095114D01*
X654024Y1095341D01*
G02X653958Y1095490I134J149D01*
G01Y1095725D01*
G03X653959Y1095767I-1301J52D01*
G03X653941Y1095981I-1302J-2D01*
G01X653933Y1096028D01*
X653961Y1096117D01*
X654248Y1096418D01*
X654336Y1096449D01*
X654384Y1096444D01*
G03X654527Y1096435I147J1193D01*
G03X653325Y1097637I0J1202D01*
G03X653395Y1097232I1202J-1D01*
G02X653134Y1096979I-188J-67D01*
G03X652982Y1097028I-475J-1213D01*
G03X652655Y1097070I-328J-1261D01*
G03X652443Y1097053I-2J-1303D01*
G01X652396Y1097045D01*
X652307Y1097072D01*
X652006Y1097359D01*
X651975Y1097447D01*
X651981Y1097495D01*
G03X651989Y1097637I-1194J139D01*
G03X650787Y1096435I-1202J0D01*
G03X650928Y1096443I3J1202D01*
G01X650976Y1096449D01*
X651063Y1096417D01*
X651350Y1096117D01*
X651377Y1096028D01*
X651370Y1095981D01*
G03X651352Y1095767I1285J-216D01*
G01Y1095490D01*
G02X651286Y1095342I-200J0D01*
G01X651033Y1095114D01*
X650954Y1095088D01*
X650911Y1095093D01*
G03X650787Y1095099I-120J-1196D01*
G03X649585Y1093897I0J-1202D01*
G03X649594Y1093754I1202J4D01*
G01X649599Y1093706D01*
X649568Y1093618D01*
X649267Y1093331D01*
X649178Y1093303D01*
X649131Y1093311D01*
G03X648917Y1093329I-216J-1284D01*
G01X648913D01*
G03X648703Y1093312I0J-1302D01*
G01X648655Y1093304D01*
X648566Y1093331D01*
X648266Y1093619D01*
X648235Y1093706D01*
X648240Y1093754D01*
G03X648249Y1093897I-1193J147D01*
G03X647231Y1095085I-1202J0D01*
G01X647158Y1095096D01*
X647062Y1095208D01*
Y1096326D01*
X647158Y1096438D01*
X647231Y1096449D01*
G03Y1098825I-184J1188D01*
G01X647158Y1098836D01*
X647062Y1098948D01*
Y1100066D01*
X647158Y1100178D01*
X647231Y1100189D01*
G03Y1102565I-184J1188D01*
G01X647158Y1102576D01*
X647062Y1102688D01*
Y1103806D01*
X647158Y1103918D01*
X647231Y1103929D01*
G03Y1106305I-184J1188D01*
G01X647158Y1106316D01*
X647062Y1106428D01*
Y1107547D01*
X647158Y1107659D01*
X647231Y1107670D01*
G03Y1110046I-184J1188D01*
G01X647158Y1110057D01*
X647062Y1110169D01*
Y1130051D01*
G02X647121Y1130193I200J0D01*
G01X647182Y1130254D01*
G02X647324Y1130313I142J-141D01*
G01X647546D01*
G02X647715Y1130220I0J-200D01*
G01X647730Y1130195D01*
G02X647760Y1130109I-169J-107D01*
G01X647764Y1130076D01*
X647745Y1129996D01*
X647736Y1129977D01*
G03X647615Y1129429I1180J-548D01*
G03X650219I1302J0D01*
G03X650106Y1129957I-1301J-2D01*
G01X650092Y1129988D01*
X650089Y1129995D01*
G02X650100Y1130188I180J87D01*
G01X650260Y1130444D01*
X650280Y1130476D01*
G02X650450Y1130570I170J-106D01*
G01X651124D01*
G02X651152Y1130568I0J-200D01*
G01X651204Y1130561D01*
X651274Y1130507D01*
X651294Y1130476D01*
X651471Y1130195D01*
G02X651499Y1130114I-171J-104D01*
G01X651504Y1130078D01*
X651485Y1129996D01*
X651476Y1129977D01*
G03X651355Y1129429I1180J-548D01*
G03X653959I1302J0D01*
G03X653846Y1129957I-1301J-2D01*
G01X653832Y1129988D01*
X653829Y1129995D01*
G02X653840Y1130188I180J87D01*
G01X654000Y1130444D01*
X654020Y1130476D01*
G02X654190Y1130570I170J-106D01*
G01X725927D01*
G02X725955Y1130568I0J-200D01*
G01X726007Y1130561D01*
X726077Y1130507D01*
X726097Y1130476D01*
X726274Y1130195D01*
G02X726302Y1130114I-171J-104D01*
G01X726307Y1130078D01*
X726288Y1129996D01*
X726279Y1129977D01*
G03X726158Y1129429I1180J-548D01*
G03X728762I1302J0D01*
G01Y1129430D01*
G03X728207Y1130496I-1302J0D01*
G01X728170Y1130522D01*
X728126Y1130597D01*
X728107Y1130808D01*
Y1130810D01*
X728096Y1130946D01*
G02X728095Y1130962I199J20D01*
G01Y1130966D01*
G02X728125Y1131072I200J1D01*
G01X728137Y1131091D01*
X730355Y1133309D01*
G03X730414Y1133451I-141J142D01*
G01Y1135251D01*
G02X730486Y1135405I200J0D01*
G01X730488Y1135407D01*
X730772Y1135632D01*
X730860Y1135652D01*
X730905Y1135641D01*
G03X731200Y1135607I296J1268D01*
G01X731201D01*
G03Y1138211I0J1302D01*
G01X731200D01*
G03X730905Y1138177I1J-1302D01*
G01X730860Y1138166D01*
X730772Y1138186D01*
X730490Y1138410D01*
G02X730414Y1138567I124J157D01*
G01Y1138991D01*
G02X730486Y1139145I200J0D01*
G01X730488Y1139147D01*
X730772Y1139372D01*
X730860Y1139392D01*
X730905Y1139381D01*
G03X731200Y1139347I296J1268D01*
G01X731201D01*
G03Y1141951I0J1302D01*
G01X731200D01*
G03X730905Y1141917I1J-1302D01*
G01X730860Y1141906D01*
X730772Y1141926D01*
X730490Y1142150D01*
G02X730414Y1142307I124J157D01*
G01Y1142731D01*
G02X730486Y1142885I200J0D01*
G01X730488Y1142887D01*
X730772Y1143112D01*
X730860Y1143132D01*
X730905Y1143121D01*
G03X731200Y1143087I296J1268D01*
G01X731201D01*
G03Y1145691I0J1302D01*
G01X731200D01*
G03X730905Y1145657I1J-1302D01*
G01X730860Y1145646D01*
X730772Y1145666D01*
X730490Y1145890D01*
G02X730414Y1146047I124J157D01*
G01Y1146471D01*
G02X730486Y1146625I200J0D01*
G01X730488Y1146627D01*
X730772Y1146852D01*
X730860Y1146872D01*
X730905Y1146861D01*
G03X731200Y1146827I296J1268D01*
G01X731201D01*
G03Y1149431I0J1302D01*
G01X731200D01*
G03X730905Y1149397I1J-1302D01*
G01X730860Y1149386D01*
X730772Y1149406D01*
X730490Y1149630D01*
G02X730414Y1149787I124J157D01*
G01Y1150211D01*
G02X730486Y1150365I200J0D01*
G01X730488Y1150367D01*
X730772Y1150592D01*
X730860Y1150612D01*
X730905Y1150601D01*
G03X731200Y1150567I296J1268D01*
G01X731201D01*
G03Y1153171I0J1302D01*
G01X731200D01*
G03X730905Y1153137I1J-1302D01*
G01X730860Y1153126D01*
X730772Y1153146D01*
X730490Y1153370D01*
G02X730414Y1153527I124J157D01*
G01Y1153952D01*
G02X730486Y1154106I200J0D01*
G01X730488Y1154108D01*
X730772Y1154333D01*
X730860Y1154353D01*
X730905Y1154342D01*
G03X731200Y1154308I296J1268D01*
G01X731201D01*
G03Y1156912I0J1302D01*
G01X731200D01*
G03X730905Y1156878I1J-1302D01*
G01X730860Y1156867D01*
X730772Y1156887D01*
X730490Y1157111D01*
G02X730414Y1157268I124J157D01*
G01Y1157692D01*
G02X730486Y1157846I200J0D01*
G01X730488Y1157848D01*
X730772Y1158073D01*
X730860Y1158093D01*
X730905Y1158082D01*
G03X731200Y1158048I296J1268D01*
G01X731201D01*
G03Y1160652I0J1302D01*
G01X731200D01*
G03X730905Y1160618I1J-1302D01*
G01X730860Y1160607D01*
X730772Y1160627D01*
X730490Y1160851D01*
G02X730414Y1161008I124J157D01*
G01Y1165172D01*
G02X730486Y1165326I200J0D01*
G01X730488Y1165328D01*
X730772Y1165553D01*
X730860Y1165573D01*
X730905Y1165562D01*
G03X731200Y1165528I296J1268D01*
G01X731201D01*
G03Y1168132I0J1302D01*
G01X731200D01*
G03X730905Y1168098I1J-1302D01*
G01X730860Y1168087D01*
X730772Y1168107D01*
X730490Y1168331D01*
G02X730414Y1168488I124J157D01*
G01Y1168912D01*
G02X730486Y1169066I200J0D01*
G01X730488Y1169068D01*
X730772Y1169293D01*
X730860Y1169313D01*
X730905Y1169302D01*
G03X731200Y1169268I296J1268D01*
G01X731201D01*
G03Y1171872I0J1302D01*
G01X731200D01*
G03X730905Y1171838I1J-1302D01*
G01X730860Y1171827D01*
X730772Y1171847D01*
X730490Y1172071D01*
G02X730414Y1172228I124J157D01*
G01Y1172652D01*
G02X730486Y1172806I200J0D01*
G01X730488Y1172808D01*
X730772Y1173033D01*
X730860Y1173053D01*
X730905Y1173042D01*
G03X731200Y1173008I296J1268D01*
G01X731201D01*
G03Y1175612I0J1302D01*
G01X731200D01*
G03X730905Y1175578I1J-1302D01*
G01X730860Y1175567D01*
X730772Y1175587D01*
X730490Y1175811D01*
G02X730414Y1175968I124J157D01*
G01Y1176393D01*
G02X730486Y1176547I200J0D01*
G01X730488Y1176549D01*
X730772Y1176774D01*
X730860Y1176794D01*
X730905Y1176783D01*
G03X731200Y1176749I296J1268D01*
G01X731201D01*
G03Y1179353I0J1302D01*
G01X731200D01*
G03X730905Y1179319I1J-1302D01*
G01X730860Y1179308D01*
X730772Y1179328D01*
X730490Y1179552D01*
G02X730414Y1179709I124J157D01*
G01Y1180133D01*
G02X730486Y1180287I200J0D01*
G01X730488Y1180289D01*
X730772Y1180514D01*
X730860Y1180534D01*
X730905Y1180523D01*
G03X731200Y1180489I296J1268D01*
G01X731201D01*
G03Y1183093I0J1302D01*
G01X731200D01*
G03X730905Y1183059I1J-1302D01*
G01X730860Y1183048D01*
X730772Y1183068D01*
X730490Y1183292D01*
G02X730414Y1183449I124J157D01*
G01Y1183873D01*
G02X730486Y1184027I200J0D01*
G01X730488Y1184029D01*
X730772Y1184254D01*
X730860Y1184274D01*
X730905Y1184263D01*
G03X731200Y1184229I296J1268D01*
G01X731201D01*
G03Y1186833I0J1302D01*
G01X731200D01*
G03X730905Y1186799I1J-1302D01*
G01X730860Y1186788D01*
X730772Y1186808D01*
X730490Y1187032D01*
G02X730414Y1187189I124J157D01*
G01Y1187613D01*
G02X730486Y1187767I200J0D01*
G01X730488Y1187769D01*
X730772Y1187994D01*
X730860Y1188014D01*
X730905Y1188003D01*
G03X731200Y1187969I296J1268D01*
G01X731201D01*
G03Y1190573I0J1302D01*
G01X731200D01*
G03X730905Y1190539I1J-1302D01*
G01X730860Y1190528D01*
X730772Y1190548D01*
X730490Y1190772D01*
G02X730414Y1190929I124J157D01*
G01Y1191353D01*
G02X730486Y1191507I200J0D01*
G01X730488Y1191509D01*
X730772Y1191734D01*
X730860Y1191754D01*
X730905Y1191743D01*
G03X731200Y1191709I296J1268D01*
G01X731201D01*
G03Y1194313I0J1302D01*
G01X731200D01*
G03X730905Y1194279I1J-1302D01*
G01X730860Y1194268D01*
X730772Y1194288D01*
X730490Y1194512D01*
G02X730414Y1194669I124J157D01*
G01Y1195093D01*
G02X730486Y1195247I200J0D01*
G01X730488Y1195249D01*
X730772Y1195474D01*
X730860Y1195494D01*
X730905Y1195483D01*
G03X731200Y1195449I296J1268D01*
G01X731201D01*
G03Y1198053I0J1302D01*
G03X729906Y1196883I0J-1302D01*
G01X729900Y1196825D01*
X729828Y1196734D01*
X729584Y1196649D01*
X729432Y1196596D01*
G02X729281Y1196604I-66J189D01*
G01X729249Y1196619D01*
X728712Y1197156D01*
X728696Y1197196D01*
X728695Y1197198D01*
X728681Y1197233D01*
G03X727944Y1197948I-1201J-501D01*
G01X727904Y1197964D01*
X727368Y1198500D01*
G02X727358Y1198511I143J140D01*
G01X727343Y1198528D01*
G02X727306Y1198724I152J130D01*
G01X727307Y1198725D01*
X727387Y1198949D01*
Y1198951D01*
X727427Y1199064D01*
G02X727431Y1199075I190J-63D01*
G02X727595Y1199196I184J-78D01*
G03X728762Y1200491I-135J1295D01*
G03X726158I-1302J0D01*
G03X726811Y1199362I1302J0D01*
G01X726834Y1199349D01*
X726871Y1199312D01*
X726922Y1199224D01*
G02X726945Y1199092I-174J-98D01*
G01X726940Y1199062D01*
G02X726760Y1198895I-197J32D01*
G01X726743Y1198894D01*
X726599D01*
G02X726459Y1198951I0J200D01*
G01X726354Y1199054D01*
X726353Y1199055D01*
G03X726212Y1199114I-142J-141D01*
G01X655995D01*
G02X655854Y1199172I0J200D01*
G01X654158Y1200868D01*
G02X654099Y1201010I141J142D01*
G01Y1217420D01*
G02X654156Y1217560I200J0D01*
G01X654157Y1217561D01*
X654936Y1218340D01*
G02X655155Y1218383I141J-141D01*
G01X655198Y1218365D01*
G03X655273Y1218349I78J184D01*
G01X655317D01*
G02X655459Y1218290I0J-200D01*
G01X655462Y1218287D01*
X655463Y1218286D01*
G03X656398Y1217890I935J906D01*
G03X657698Y1219112I0J1302D01*
G01X657701Y1219164D01*
X657831Y1219368D01*
X657834Y1219372D01*
X657858Y1219408D01*
X657902Y1219446D01*
X657929Y1219457D01*
G03X658242Y1219613I-1535J3473D01*
G01X658290Y1219639D01*
X658397Y1219637D01*
X658618Y1219502D01*
X658742Y1219426D01*
G02X658837Y1219248I-105J-170D01*
G01Y1219247D01*
G03X658836Y1219194I1301J-51D01*
G01Y1219191D01*
G03X660138Y1217890I1302J1D01*
G03X661440Y1219192I0J1302D01*
G03X661439Y1219247I-1302J4D01*
G01Y1219248D01*
G02X661533Y1219425I200J7D01*
G01X661760Y1219566D01*
X661762D01*
X661828Y1219608D01*
G02X661931Y1219639I107J-169D01*
G01X661986Y1219640D01*
X662033Y1219615D01*
G02X662035Y1219613I-135J-137D01*
G03X662451Y1219413I1850J3316D01*
G02X662576Y1219228I-75J-185D01*
G01Y1219192D01*
G03X663878Y1217890I1302J0D01*
G03X665178Y1219112I0J1302D01*
G01X665181Y1219164D01*
X665311Y1219368D01*
X665314Y1219372D01*
X665338Y1219408D01*
X665382Y1219446D01*
X665409Y1219457D01*
G03X665722Y1219613I-1535J3473D01*
G01X665770Y1219639D01*
X665877Y1219637D01*
X666098Y1219502D01*
X666222Y1219426D01*
G02X666317Y1219248I-105J-170D01*
G01Y1219247D01*
G03X666316Y1219194I1301J-51D01*
G01Y1219191D01*
G03X667618Y1217890I1302J1D01*
G03X668920Y1219192I0J1302D01*
G03X668919Y1219247I-1302J4D01*
G01Y1219248D01*
G02X669013Y1219425I200J7D01*
G01X669240Y1219566D01*
X669242D01*
X669308Y1219608D01*
G02X669411Y1219639I107J-169D01*
G01X669466Y1219640D01*
X669513Y1219615D01*
G02X669515Y1219613I-135J-137D01*
G03X669931Y1219413I1850J3316D01*
G02X670056Y1219228I-75J-185D01*
G01Y1219192D01*
G03X671358Y1217890I1302J0D01*
G03X672658Y1219112I0J1302D01*
G01X672661Y1219164D01*
X672791Y1219368D01*
X672794Y1219372D01*
X672818Y1219408D01*
X672862Y1219446D01*
X672889Y1219457D01*
G03X673202Y1219613I-1535J3473D01*
G01X673250Y1219639D01*
X673357Y1219637D01*
X673578Y1219502D01*
X673702Y1219426D01*
G02X673797Y1219248I-105J-170D01*
G01Y1219247D01*
G03X673796Y1219194I1301J-51D01*
G01Y1219191D01*
G03X675098Y1217890I1302J1D01*
G03X676400Y1219192I0J1302D01*
G03X676399Y1219247I-1302J4D01*
G01Y1219248D01*
G02X676493Y1219425I200J7D01*
G01X676720Y1219566D01*
X676722D01*
X676788Y1219608D01*
G02X676891Y1219639I107J-169D01*
G01X676946Y1219640D01*
X676993Y1219615D01*
G02X676995Y1219613I-135J-137D01*
G03X677411Y1219413I1850J3316D01*
G02X677536Y1219228I-75J-185D01*
G01Y1219192D01*
G03X678838Y1217890I1302J0D01*
G03X680140Y1219171I0J1302D01*
G01X680141Y1219230D01*
X680230Y1219363D01*
G02X680252Y1219390I166J-112D01*
G02X680268Y1219405I145J-138D01*
G01X680294Y1219427D01*
X680323Y1219439D01*
G03X680354Y1219451I-1355J3546D01*
G01X680355Y1219452D01*
X680389Y1219467D01*
G03X680684Y1219613I-1535J3473D01*
G01X680732Y1219639D01*
X680838Y1219637D01*
X681034Y1219518D01*
X681036D01*
X681183Y1219427D01*
G02X681278Y1219249I-105J-170D01*
G03X681277Y1219194I1301J-51D01*
G01Y1219191D01*
G03X682579Y1217890I1302J1D01*
G03X683881Y1219192I0J1302D01*
G03X683880Y1219235I-1302J-9D01*
G01Y1219255D01*
G02X683971Y1219422I200J-1D01*
G01X683973Y1219424D01*
X684178Y1219551D01*
X684266Y1219605D01*
G02X684412Y1219630I104J-171D01*
G01X684464Y1219619D01*
X684490Y1219605D01*
G03X684987Y1219377I1827J3327D01*
G02X685117Y1219190I-70J-187D01*
G03X686319Y1217990I1202J2D01*
G03X687520Y1219136I0J1202D01*
G01X687521Y1219165D01*
X687539Y1219217D01*
X687633Y1219352D01*
X687678Y1219388D01*
X687707Y1219399D01*
G03X688678Y1219958I-1388J3534D01*
G02X688715Y1219981I123J-157D01*
G03X689270Y1220536I-526J1081D01*
G02X689293Y1220573I180J-86D01*
G03X689721Y1221247I-2973J2361D01*
G02X689815Y1221339I179J-89D01*
G03X690127Y1221504I-1631J3461D01*
G37*
G36*
G01X903643Y998300D02*
X917179D01*
G02X917321Y998241I0J-200D01*
G01X917979Y997583D01*
G02Y997300I-141J-141D01*
G01X916551Y995872D01*
X916509Y995847D01*
X916486Y995839D01*
G03X915430Y994405I446J-1434D01*
G03X916932Y992903I1502J0D01*
G03X918366Y993959I0J1502D01*
G01X918374Y993982D01*
X918399Y994024D01*
X919410Y995035D01*
G02X919551Y995094I142J-141D01*
G01X920386D01*
G02X920527Y995035I-1J-200D01*
G01X924406Y991156D01*
G02X924465Y991014I-141J-142D01*
G01Y967516D01*
G02X924374Y967349I-200J1D01*
G01X924049Y967138D01*
X923949Y967130D01*
X923902Y967151D01*
G03X923289Y967282I-613J-1371D01*
G03Y964278I0J-1502D01*
G03X923902Y964409I0J1502D01*
G01X923949Y964430D01*
X924049Y964422D01*
X924374Y964211D01*
G02X924465Y964044I-109J-168D01*
G01Y956363D01*
G02X924406Y956221I-200J0D01*
G01X920847Y952662D01*
X920808Y952646D01*
G03X919969Y951807I556J-1395D01*
G01X919953Y951768D01*
X914906Y946721D01*
X914791Y946697D01*
X914735Y946719D01*
G03X914193Y946820I-541J-1401D01*
G03X912691Y945318I0J-1502D01*
G03X912792Y944776I1502J-1D01*
G01X912814Y944720D01*
X912790Y944605D01*
X894244Y926059D01*
G02X894102Y926000I-142J141D01*
G01X843220D01*
G02X843071Y926066I0J200D01*
G01X842844Y926320D01*
X842818Y926400D01*
X842823Y926442D01*
G03X842831Y926602I-1494J155D01*
G03X839827I-1502J0D01*
G03X839835Y926442I1502J-5D01*
G01X839840Y926400D01*
X839814Y926320D01*
X839587Y926066D01*
G02X839438Y926000I-149J134D01*
G01X816748D01*
G03X816606Y925941I0J-200D01*
G01X783724Y893059D01*
G03X783665Y892917I141J-142D01*
G01Y888096D01*
X783650Y888059D01*
G03X783478Y887184I2134J-874D01*
G01Y784730D01*
G02X783419Y784589I-200J1D01*
G01X779889Y781059D01*
G02X779747Y781000I-142J141D01*
G01X741264D01*
G02X741122Y781059I0J200D01*
G01X739005Y783176D01*
G02X738949Y783283I141J142D01*
G01X733514Y814492D01*
X733576Y814611D01*
X733638Y814640D01*
G03X734502Y816000I-638J1360D01*
G03X733140Y817495I-1501J0D01*
G01X733073Y817502D01*
X732974Y817593D01*
X731271Y827369D01*
X731342Y827493D01*
X731410Y827519D01*
G03X732005Y827929I-530J1405D01*
G01X732033Y827961D01*
X732108Y827995D01*
X732488Y828002D01*
X732564Y827971D01*
X732594Y827940D01*
G03X733680Y827475I1086J1036D01*
G03Y830479I0J1502D01*
G03X732555Y829972I0J-1502D01*
G01X732527Y829940D01*
X732452Y829906D01*
X732072Y829899D01*
X731996Y829930D01*
X731966Y829961D01*
G03X730904Y830426I-1087J-1037D01*
G01X730832Y830427D01*
X730723Y830520D01*
X724012Y869050D01*
X724016Y869099D01*
X724024Y869123D01*
G03X724102Y869600I-1424J478D01*
G03X723779Y870531I-1503J0D01*
G01X723763Y870551D01*
X723743Y870595D01*
X718033Y903384D01*
G02X718131Y903592I197J34D01*
G01X718513Y903810D01*
X718638Y903798D01*
X718687Y903757D01*
G03X719661Y903398I974J1142D01*
G03Y906402I0J1502D01*
G03X718358Y905646I0J-1501D01*
G01X718326Y905591D01*
X718212Y905538D01*
X717779Y905614D01*
G02X717616Y905776I34J197D01*
G01X705041Y977985D01*
G02X705038Y978019I197J35D01*
G01Y988888D01*
G02X705097Y989030I200J0D01*
G01X714308Y998241D01*
G02X714450Y998300I142J-141D01*
G01X893669D01*
G02X893853Y998177I-1J-200D01*
G01X893877Y998120D01*
X893854Y998002D01*
X893516Y997665D01*
G02X893375Y997606I-142J141D01*
G01X890121D01*
G03X889197Y997224I-1J-1306D01*
G01X888019Y996046D01*
X887977Y996021D01*
X887954Y996013D01*
G03X886898Y994579I446J-1434D01*
G03X888400Y993077I1502J0D01*
G03X889497Y993554I-1J1502D01*
G01X889529Y993587D01*
X889611Y993620D01*
X890013Y993592D01*
X890090Y993549D01*
X890116Y993511D01*
G03X891343Y992876I1227J868D01*
G03X892194Y993140I0J1502D01*
G01X892227Y993163D01*
X892305Y993179D01*
X892662Y993112D01*
X892729Y993068D01*
X892751Y993035D01*
G03X894660Y992024I1908J1295D01*
G03X896291Y992699I1J2306D01*
G01X896785Y993193D01*
X896927Y993207D01*
X896987Y993167D01*
G03X897825Y992911I839J1246D01*
G03X899259Y993967I0J1502D01*
G01X899267Y993990D01*
X899292Y994032D01*
X903501Y998241D01*
G02X903643Y998300I142J-141D01*
G37*
G36*
G01X799468Y54588D02*
X827614D01*
X827756Y54446D01*
Y52733D01*
X827614Y52591D01*
X799468D01*
G03X793531Y46654I0J-5937D01*
G01Y7874D01*
G02X787657Y2000I-5874J0D01*
G01X740413D01*
G02X734539Y7874I0J5874D01*
G01Y46261D01*
X736536D01*
Y7874D01*
G03X740411Y3998I3876J0D01*
G01X787657D01*
G03X791534Y7874I0J3877D01*
G01Y46654D01*
G02X799468Y54588I7934J0D01*
G37*
G36*
G01X740015Y778950D02*
X755030D01*
G02X755170Y778893I0J-200D01*
G01X755171Y778892D01*
X755274Y778789D01*
G03X755416Y778730I142J141D01*
G01X779846D01*
G02X779986Y778673I0J-200D01*
G01X779987Y778672D01*
X782270Y776388D01*
G02X782329Y776246I-141J-142D01*
G01Y754286D01*
G03X782388Y754144I200J0D01*
G01X798357Y738175D01*
G02X798359Y738173I-140J-142D01*
G02X798416Y738033I-143J-140D01*
G01Y662267D01*
G03X798475Y662125I200J0D01*
G01X816597Y644003D01*
G02X816599Y644001I-140J-142D01*
G02X816656Y643861I-143J-140D01*
G01Y517947D01*
X816626Y517873D01*
X816597Y517845D01*
X795953Y497202D01*
G03X795290Y495601I1603J-1602D01*
G01Y469726D01*
G02X795231Y469584I-200J0D01*
G01X788273Y462627D01*
G03X787610Y461026I1603J-1602D01*
G01Y448519D01*
G03X788273Y446918I2266J1D01*
G01X792281Y442911D01*
G02X792328Y442838I-141J-142D01*
G01X792340Y442805D01*
Y416310D01*
G02X792281Y416168I-200J0D01*
G01X786138Y410025D01*
G02X786099Y409991I-282J284D01*
G01X786098Y409990D01*
G02X785906Y409962I-121J159D01*
G01X785858Y409980D01*
X785792Y410059D01*
X785378Y412141D01*
X785421Y412250D01*
X785469Y412284D01*
G03X786088Y413500I-884J1215D01*
G03X785718Y414487I-1501J0D01*
G01X785694Y414515D01*
X785669Y414582D01*
Y414918D01*
X785694Y414985D01*
X785718Y415013D01*
G03X786088Y416000I-1131J987D01*
G03X784586Y417502I-1502J0D01*
G03X784492Y417499I1J-1502D01*
G01X784416Y417494D01*
X784298Y417585D01*
X779642Y441056D01*
X779694Y441172D01*
X779749Y441204D01*
G03X780487Y442498I-765J1294D01*
G03X779197Y443985I-1502J0D01*
G01X779134Y443994D01*
X779041Y444081D01*
X775844Y460198D01*
G02X775840Y460235I196J40D01*
G01X775785Y464942D01*
X775871Y465052D01*
X775939Y465069D01*
G03X776807Y465655I-354J1460D01*
G02X776926Y465734I163J-116D01*
G01X777045Y465761D01*
G02X777188Y465740I44J-195D01*
G03X778080Y465504I892J1566D01*
G03X779882Y467306I0J1802D01*
G01Y470706D01*
G03X778080Y472508I-1802J0D01*
G03X777187Y472272I-1J-1802D01*
G02X777044Y472250I-100J173D01*
G01X776925Y472277D01*
G02X776806Y472356I44J195D01*
G03X775854Y472961I-1223J-872D01*
G01X775783Y472974D01*
X775691Y473083D01*
X775622Y479089D01*
X775720Y479203D01*
X775795Y479214D01*
G03X776806Y479829I-212J1487D01*
G02X776925Y479908I163J-116D01*
G01X777044Y479935D01*
G02X777187Y479913I43J-195D01*
G03X778080Y479676I894J1566D01*
G03X779882Y481479I0J1802D01*
G01Y484879D01*
G03X776278I-1802J0D01*
G01Y482580D01*
G02X776208Y482428I-200J0D01*
G01X775943Y482202D01*
X775859Y482178D01*
X775816Y482185D01*
G03X775760Y482192I-214J-1487D01*
G01X775685Y482201D01*
X775585Y482313D01*
X774948Y537469D01*
Y537488D01*
G02X775431Y537846I399J-33D01*
G03X775746Y537813I313J1470D01*
G03X777248Y539315I0J1502D01*
G03X777235Y539515I-1502J3D01*
G03X775925Y540807I-1489J-200D01*
G01X775865Y540813D01*
G03X775746Y540818I-123J-1498D01*
G01X775745D01*
G03X775397Y540777I1J-1503D01*
G02X774905Y541153I-92J389D01*
G01Y541157D01*
X774604Y567202D01*
G03X774603Y567276I-3926J-16D01*
G01Y567278D01*
X774601Y567420D01*
Y567422D01*
G03X774600Y567443I-200J1D01*
G01X774576Y567630D01*
Y567631D01*
G03X774572Y567659I-3888J-541D01*
G01X769103Y610114D01*
G03X769092Y610194I-3895J-495D01*
G01Y610195D01*
G03X769091Y610204I-199J-18D01*
G01X769087Y610224D01*
Y610226D01*
G03X769077Y610286I-3878J-615D01*
G01X745446Y745975D01*
X745452Y746031D01*
X745463Y746057D01*
G03X745561Y746441I-1394J560D01*
G01X745568Y746499D01*
G03X745572Y746617I-1499J110D01*
G03X745191Y747617I-1503J0D01*
G01X745172Y747638D01*
X745148Y747688D01*
X742636Y762111D01*
X742643Y762126D01*
G03X743494Y763480I-652J1354D01*
G03X742536Y764880I-1502J0D01*
G02X742527Y764884I77J185D01*
G03X742261Y764974I-612J-1372D01*
G01X742202Y764988D01*
X742120Y765074D01*
X741925Y766193D01*
G02X741959Y766343I197J34D01*
G01X742146Y766607D01*
X742213Y766650D01*
X742252Y766656D01*
G03X743502Y768137I-252J1481D01*
G03X742415Y769580I-1501J0D01*
G01X742368Y769594D01*
X742297Y769661D01*
X742160Y770067D01*
X742175Y770164D01*
X742205Y770204D01*
G03X742451Y770713I-1205J896D01*
G01X742462Y770754D01*
X742512Y770817D01*
X742841Y770996D01*
X742922Y771003D01*
X742962Y770990D01*
G03X743428Y770916I466J1428D01*
G03Y773920I0J1502D01*
G03X741953Y772699I0J-1501D01*
G02X741851Y772561I-196J38D01*
G01X741739Y772500D01*
G02X741568Y772490I-96J175D01*
G03X741471Y772526I-571J-1389D01*
G03X741512Y772879I-1481J351D01*
G03X740609Y774268I-1520J0D01*
G02X740493Y774416I81J183D01*
G01X740476Y774515D01*
G02X740576Y774724I197J34D01*
G01X740737Y774814D01*
G02X740905Y774826I97J-175D01*
G01X740907Y774825D01*
X740985Y774795D01*
X741011Y774772D01*
G03X741993Y774407I982J1138D01*
G03Y777411I0J1502D01*
G03X740670Y776619I0J-1501D01*
G01X740639Y776563D01*
X740525Y776506D01*
X740259Y776549D01*
G02X740093Y776712I31J198D01*
G01X739747Y778702D01*
G02X739872Y778923I197J35D01*
G02X740015Y778950I144J-373D01*
G37*
G36*
G01X953600Y1406349D02*
X958223D01*
G02X958365Y1406290I0J-200D01*
G01X961661Y1402994D01*
G03X961803Y1402935I142J141D01*
G01X1004976D01*
G02X1005118Y1402876I0J-200D01*
G01X1006127Y1401867D01*
G02X1006186Y1401725I-141J-142D01*
G01Y1399273D01*
X1006088Y1399161D01*
X1006012Y1399151D01*
G03Y1396173I199J-1489D01*
G01X1006088Y1396163D01*
X1006186Y1396051D01*
Y1384090D01*
G03X1006245Y1383948I200J0D01*
G01X1007495Y1382698D01*
G03X1007637Y1382639I142J141D01*
G01X1023089D01*
G02X1023231Y1382580I0J-200D01*
G01X1025283Y1380528D01*
G02X1025342Y1380386I-141J-142D01*
G01Y1358798D01*
G02X1025283Y1358656I-200J0D01*
G01X1023921Y1357294D01*
G02X1023779Y1357235I-142J141D01*
G01X1002596D01*
G03X1002454Y1357176I0J-200D01*
G01X1000221Y1354943D01*
G03X1000162Y1354801I141J-142D01*
G01Y1326500D01*
G02X1000103Y1326358I-200J0D01*
G01X993461Y1319716D01*
G02X993319Y1319657I-142J141D01*
G01X992270D01*
G02X992104Y1319745I0J200D01*
G01X991890Y1320059D01*
X991880Y1320158D01*
X991898Y1320204D01*
G03X992003Y1320756I-1397J552D01*
G03X988999I-1502J0D01*
G03X989104Y1320204I1502J0D01*
G01X989122Y1320158D01*
X989112Y1320059D01*
X988898Y1319745D01*
G02X988732Y1319657I-166J112D01*
G01X945982D01*
G02X945818Y1319744I1J200D01*
G01X945603Y1320057D01*
X945591Y1320154D01*
X945609Y1320200D01*
G03X945709Y1320739I-1403J539D01*
G03X942705I-1502J0D01*
G03X942805Y1320200I1503J0D01*
G01X942823Y1320154D01*
X942811Y1320057D01*
X942596Y1319744D01*
G02X942432Y1319657I-165J113D01*
G01X798549D01*
G02X798407Y1319716I0J200D01*
G01X788717Y1329406D01*
G02X788658Y1329548I141J142D01*
G01Y1329611D01*
G02X788858Y1329811I200J0D01*
G01X788890D01*
X788920Y1329801D01*
G03X789383Y1329728I463J1429D01*
G03X790489Y1330213I1J1502D01*
G02X790636Y1330278I148J-135D01*
G01X790930D01*
G02X791077Y1330213I-1J-200D01*
G03X792183Y1329728I1105J1017D01*
G03X793685Y1331230I0J1502D01*
G03X793200Y1332336I-1502J1D01*
G02X793135Y1332483I135J148D01*
G01Y1332777D01*
G02X793200Y1332924I200J-1D01*
G03X793685Y1334030I-1017J1105D01*
G03X792183Y1335532I-1502J0D01*
G03X791077Y1335047I-1J-1502D01*
G02X790930Y1334982I-148J135D01*
G01X790636D01*
G02X790489Y1335047I1J200D01*
G03X789383Y1335532I-1105J-1017D01*
G03X789126Y1335510I-1J-1502D01*
G01X789082Y1335502D01*
X788998Y1335525D01*
X788729Y1335751D01*
G02X788658Y1335904I129J153D01*
G01Y1346351D01*
G02X788717Y1346493I200J0D01*
G01X788720Y1346496D01*
Y1381336D01*
G02X788779Y1381478I200J0D01*
G01X793165Y1385864D01*
G02X793307Y1385923I142J-141D01*
G01X822264D01*
G02X822406Y1385864I0J-200D01*
G01X919357D01*
G02X919475Y1385826I1J-200D01*
G03X920360Y1385537I886J1213D01*
G03X921245Y1385826I-1J1502D01*
G02X921363Y1385864I117J-162D01*
G01X930140D01*
G02X930259Y1385824I-1J-200D01*
G03X931159Y1385525I899J1203D01*
G03X932059Y1385824I1J1502D01*
G02X932178Y1385864I120J-160D01*
G01X944371D01*
G03X944513Y1385923I0J200D01*
G01X950333Y1391743D01*
G02X950557Y1391784I142J-141D01*
G01X950956Y1391604D01*
X951019Y1391498D01*
X951015Y1391435D01*
G03X951012Y1391339I1499J-95D01*
G03X952514Y1392841I1502J0D01*
G03X951808Y1392665I0J-1502D01*
G01X951750Y1392634D01*
X951619Y1392653D01*
X951573Y1392700D01*
G02Y1392983I141J142D01*
G01X951675Y1393085D01*
G03X951734Y1393227I-141J142D01*
G01Y1393392D01*
G02X951803Y1393543I200J0D01*
G01X952063Y1393770D01*
X952145Y1393794D01*
X952189Y1393788D01*
G03X952395Y1393774I205J1488D01*
G03Y1396778I0J1502D01*
G03X952189Y1396764I-1J-1502D01*
G01X952145Y1396758D01*
X952063Y1396782D01*
X951803Y1397009D01*
G02X951734Y1397160I131J151D01*
G01Y1397876D01*
G02X951934Y1398076I200J0D01*
G01X953091D01*
G02X953233Y1398017I0J-200D01*
G01X955544Y1395706D01*
G02X955602Y1395564I-142J-141D01*
G01Y1388586D01*
G02X955544Y1388444I-200J-1D01*
G01X954783Y1387683D01*
G02X954637Y1387625I-141J142D01*
G01X954597D01*
X954524Y1387659D01*
X953819Y1388421D01*
G03X952716Y1388904I-1103J-1018D01*
G03X951214Y1387402I0J-1502D01*
G03X951613Y1386383I1501J0D01*
G01X952349Y1385587D01*
G02X952338Y1385305I-147J-135D01*
G01X951541Y1384567D01*
G03X951060Y1383465I1020J-1101D01*
G03X952561Y1381964I1501J0D01*
G03X953581Y1382363I1J1501D01*
G01X954327Y1383054D01*
G02X954471Y1383107I136J-147D01*
G01X955839Y1383053D01*
G03X955898Y1383052I55J1500D01*
G03X956960Y1383491I1J1501D01*
G01X959666Y1386197D01*
G03X960106Y1387259I-1062J1062D01*
G01Y1396891D01*
G03X959666Y1397953I-1502J0D01*
G01X955480Y1402139D01*
G03X954418Y1402578I-1061J-1062D01*
G01X951934D01*
G02X951734Y1402778I0J200D01*
G01Y1405186D01*
G02X951794Y1405329I200J0D01*
G01X952029Y1405557D01*
X952102Y1405586D01*
X952144Y1405585D01*
X952180D01*
G03X953433Y1406259I0J1502D01*
G02X953600Y1406349I167J-110D01*
G37*
G36*
G01X822554Y1626504D02*
X927703D01*
G02X927845Y1626445I0J-200D01*
G01X932332Y1621958D01*
G02X932391Y1621816I-141J-142D01*
G01Y1585734D01*
G03X932450Y1585592I200J0D01*
G01X940497Y1577545D01*
G03X940639Y1577486I142J141D01*
G01X956366D01*
G02X956508Y1577427I0J-200D01*
G01X960090Y1573845D01*
G02X960149Y1573703I-141J-142D01*
G01Y1545224D01*
G03X960208Y1545082I200J0D01*
G01X960222Y1545068D01*
Y1543190D01*
G03X960281Y1543048I200J0D01*
G01X964685Y1538644D01*
G03X964827Y1538585I142J141D01*
G01X1020051D01*
G02X1020193Y1538526I0J-200D01*
G01X1031736Y1526983D01*
G02X1031795Y1526841I-141J-142D01*
G01Y1492779D01*
G02X1031736Y1492637I-200J0D01*
G01X1031447Y1492348D01*
G02X1031305Y1492289I-142J141D01*
G01X957250D01*
X957246Y1492293D01*
X947172D01*
G02X947030Y1492352I0J200D01*
G01X944500Y1494882D01*
G03X944358Y1494941I-142J-141D01*
G01X933345D01*
G03X933203Y1494882I0J-200D01*
G01X917090Y1478769D01*
G03X917031Y1478627I141J-142D01*
G01Y1464953D01*
G02X916972Y1464811I-200J0D01*
G01X914131Y1461970D01*
G03X914072Y1461828I141J-142D01*
G01Y1460856D01*
G02X914013Y1460714I-200J0D01*
G01X913858Y1460559D01*
X913852D01*
X913446Y1460153D01*
G03X913387Y1460011I141J-142D01*
G01Y1446377D01*
G02X913328Y1446235I-200J0D01*
G01X913012Y1445919D01*
G02X912870Y1445860I-142J141D01*
G01X900424D01*
G02X900282Y1445919I0J200D01*
G01X900057Y1446144D01*
G02X899998Y1446286I141J142D01*
G01Y1459953D01*
G03X899939Y1460095I-200J0D01*
G01X899336Y1460698D01*
G02X899277Y1460840I141J142D01*
G01Y1462388D01*
G03X899218Y1462530I-200J0D01*
G01X894243Y1467505D01*
G02X894184Y1467647I141J142D01*
G01Y1473419D01*
G03X894125Y1473561I-200J0D01*
G01X888556Y1479130D01*
G03X888414Y1479189I-142J-141D01*
G01X880246D01*
G03X880104Y1479130I0J-200D01*
G01X872204Y1471230D01*
G03X872145Y1471088I141J-142D01*
G01Y1460906D01*
G02X872086Y1460764I-200J0D01*
G01X871408Y1460086D01*
G03X871349Y1459944I141J-142D01*
G01Y1446298D01*
G02X871290Y1446156I-200J0D01*
G01X871040Y1445906D01*
G02X870898Y1445847I-142J141D01*
G01X858576D01*
G02X858434Y1445906I0J200D01*
G01X857939Y1446401D01*
G02X857880Y1446543I141J142D01*
G01Y1459845D01*
G03X857821Y1459987I-200J0D01*
G01X853265Y1464543D01*
G03X853123Y1464602I-142J-141D01*
G01X828106D01*
G03X827964Y1464543I0J-200D01*
G01X826987Y1463566D01*
G03X826928Y1463424I141J-142D01*
G01Y1461709D01*
G02X826869Y1461567I-200J0D01*
G01X826719Y1461417D01*
G02X826577Y1461359I-141J142D01*
G01X824706D01*
G03X824564Y1461300I0J-200D01*
G01X822174Y1458910D01*
G03X822115Y1458768I141J-142D01*
G01Y1458505D01*
G02X822056Y1458363I-200J0D01*
G01X822029Y1458336D01*
X819764D01*
G03X819622Y1458277I0J-200D01*
G01X819287Y1457942D01*
G03X819228Y1457800I141J-142D01*
G01Y1446396D01*
G02X819169Y1446254I-200J0D01*
G01X818882Y1445967D01*
G02X818740Y1445908I-142J141D01*
G01X806246D01*
G02X806104Y1445967I0J200D01*
G01X805830Y1446241D01*
G02X805771Y1446383I141J142D01*
G01Y1459991D01*
G02X805830Y1460133I200J0D01*
G01X806276Y1460579D01*
G03X806335Y1460721I-141J142D01*
G01Y1467878D01*
G02X806429Y1468048I200J0D01*
G01X806762Y1468255D01*
X806865Y1468260D01*
X806912Y1468237D01*
G03X807576Y1468082I664J1347D01*
G03Y1471086I0J1502D01*
G03X806912Y1470931I0J-1502D01*
G01X806865Y1470908D01*
X806762Y1470913D01*
X806429Y1471120D01*
G02X806335Y1471290I106J170D01*
G01Y1474404D01*
G02X806394Y1474546I200J0D01*
G01X806713Y1474865D01*
G03X806772Y1475007I-141J142D01*
G01Y1523862D01*
G02X806831Y1524004I200J0D01*
G01X816897Y1534070D01*
G03X816956Y1534212I-141J142D01*
G01Y1620906D01*
G02X817015Y1621048I200J0D01*
G01X822412Y1626445D01*
G02X822554Y1626504I142J-141D01*
G37*
G36*
G01X949468Y54588D02*
X978644D01*
X978785Y54447D01*
Y52732D01*
X978644Y52591D01*
X949468D01*
G03X943531Y46654I0J-5937D01*
G01Y7874D01*
G02X937657Y2000I-5874J0D01*
G01X842776D01*
G02X836902Y7874I0J5874D01*
G01Y46658D01*
G03X836896Y46925I-5938J0D01*
G01X838895D01*
G02X838900Y46654I-7930J-282D01*
G01Y7874D01*
G03X842776Y3998I3876J0D01*
G01X937657D01*
G03X941534Y7874I0J3877D01*
G01Y46654D01*
G02X949468Y54588I7934J0D01*
G37*
G36*
G01X847020Y347993D02*
X847043Y348016D01*
G02X847184Y348074I141J-142D01*
G01X872596D01*
G02X872737Y348016I0J-200D01*
G01X873630Y347123D01*
X873643Y346978D01*
X873601Y346918D01*
G03X873359Y346356I1229J-862D01*
G02X873262Y346223I-196J41D01*
G03X872503Y344917I744J-1306D01*
G03X874005Y343415I1502J0D01*
G03X875477Y344617I0J1502D01*
G02X875574Y344751I196J-40D01*
G03X875693Y344826I-740J1306D01*
G01X875753Y344868D01*
X875898Y344855D01*
X885426Y335327D01*
G02X885481Y335151I-142J-141D01*
G01X885433Y334877D01*
G02X885394Y334789I-197J35D01*
G01X885378Y334769D01*
X885342Y334740D01*
X885320Y334730D01*
G03X884451Y333368I633J-1362D01*
G03X885953Y331866I1502J0D01*
G01X886008D01*
X886082Y331837D01*
X886312Y331608D01*
G02X886372Y331466I-140J-143D01*
G01Y331270D01*
G02X886312Y331128I-200J1D01*
G01X886082Y330899D01*
X886008Y330870D01*
X885968D01*
X885953D01*
G03Y327866I0J-1502D01*
G01X886008D01*
X886082Y327837D01*
X886312Y327608D01*
G02X886372Y327466I-140J-143D01*
G01Y327270D01*
G02X886312Y327128I-200J1D01*
G01X886082Y326899D01*
X886008Y326870D01*
X885968D01*
X885953D01*
G03Y323866I0J-1502D01*
G01X886008D01*
X886082Y323837D01*
X886312Y323608D01*
G02X886372Y323466I-140J-143D01*
G01Y323270D01*
G02X886312Y323128I-200J1D01*
G01X886082Y322899D01*
X886008Y322870D01*
X885968D01*
X885953D01*
G03Y319866I0J-1502D01*
G01X886008D01*
X886082Y319837D01*
X886312Y319608D01*
G02X886372Y319466I-140J-143D01*
G01Y319270D01*
G02X886314Y319129I-200J0D01*
G01X886087Y318901D01*
X886016Y318870D01*
X885975D01*
G03Y315866I14J-1502D01*
G01X886016D01*
X886087Y315835D01*
X886314Y315607D01*
G02X886372Y315466I-142J-141D01*
G01Y315270D01*
G02X886314Y315129I-200J0D01*
G01X886087Y314901D01*
X886016Y314870D01*
X885975D01*
G03Y311866I14J-1502D01*
G01X886016D01*
X886087Y311835D01*
X886314Y311607D01*
G02X886372Y311466I-142J-141D01*
G01Y311270D01*
G02X886314Y311129I-200J0D01*
G01X886087Y310901D01*
X886016Y310870D01*
X885975D01*
G03Y307866I14J-1502D01*
G01X886016D01*
X886087Y307835D01*
X886314Y307607D01*
G02X886372Y307466I-142J-141D01*
G01Y307270D01*
G02X886314Y307129I-200J0D01*
G01X886087Y306901D01*
X886016Y306870D01*
X885975D01*
G03Y303866I14J-1502D01*
G01X886016D01*
X886087Y303835D01*
X886314Y303607D01*
G02X886372Y303466I-142J-141D01*
G01Y291401D01*
G02X886311Y291258I-200J1D01*
G01X886076Y291029D01*
X886002Y291000D01*
X885960Y291001D01*
G03X885918Y291002I-57J-1501D01*
G03Y287998I0J-1502D01*
G03X885960Y287999I-15J1502D01*
G01X886002Y288000D01*
X886076Y287971D01*
X886311Y287742D01*
G02X886372Y287599I-139J-144D01*
G01Y286544D01*
G02X886316Y286406I-200J1D01*
G01X886098Y286178D01*
X886029Y286146D01*
X885990Y286144D01*
G03X884572Y284855I69J-1500D01*
G01X884564Y284798D01*
X884492Y284712D01*
X884098Y284580D01*
G02X883893Y284629I-63J190D01*
G01X878781Y289741D01*
G03X877150Y290416I-1630J-1631D01*
G01X875488D01*
G02X875347Y290475I1J200D01*
G01X848475Y317347D01*
G02X848416Y317488I141J142D01*
G01Y343050D01*
G03X847741Y344681I-2306J1D01*
G01X847049Y345373D01*
G02X846990Y345515I141J142D01*
G01Y347920D01*
X847020Y347993D01*
G37*
G36*
G01X909485Y387032D02*
G03X907855Y386357I0J-2306D01*
G01X899587Y378089D01*
G03X898912Y376459I1631J-1630D01*
G01Y352887D01*
G02X898860Y352752I-200J0D01*
G01X898780Y352665D01*
G02X898661Y352602I-148J135D01*
G03Y349626I208J-1488D01*
G02X898780Y349563I-29J-198D01*
G01X898860Y349476D01*
G02X898912Y349341I-148J-135D01*
G01Y346678D01*
G03X899587Y345048I2306J0D01*
G01X900483Y344152D01*
G02X900542Y344010I-141J-142D01*
G01Y342552D01*
G02X900342Y342352I-200J0D01*
G01X898634D01*
G02X898492Y342411I0J200D01*
G01X884779Y356124D01*
G02X884760Y356383I142J141D01*
G01Y356384D01*
G03X885054Y357276I-1208J893D01*
G03X883552Y358778I-1502J0D01*
G03X882660Y358484I1J-1502D01*
G01X882659D01*
G02X882400Y358503I-118J161D01*
G01X871001Y369902D01*
G03X869370Y370578I-1632J-1631D01*
G01X863080D01*
G02X863057Y370597I115J163D01*
G01X859996Y373658D01*
G02X859941Y373764I142J141D01*
G01X859935Y373794D01*
X859943Y373853D01*
X859955Y373881D01*
X859956Y373883D01*
G03X860088Y374494I-1370J616D01*
G01Y374520D01*
G03X859999Y375011I-1502J-19D01*
G03X858763Y375991I-1412J-512D01*
G02X858640Y376054I24J199D01*
G01X858560Y376140D01*
G02X858506Y376277I146J137D01*
G01Y398726D01*
X858565Y398822D01*
X858598Y398839D01*
G03X859139Y399295I-671J1345D01*
G03X858417Y401605I-1211J889D01*
G01X858388Y401615D01*
X858340Y401650D01*
X858258Y401761D01*
G02X858218Y401880I160J120D01*
G01Y402041D01*
G03X857554Y403644I-2267J0D01*
G01X855913Y405285D01*
X855903Y405300D01*
G03X855640Y405614I-1893J-1318D01*
G01X850871Y410383D01*
G02X850814Y410503I142J141D01*
G01X850813Y410508D01*
X850853Y410573D01*
G02X850855Y410575I139J-137D01*
G03X851093Y411387I-1264J811D01*
G01Y411442D01*
G03X850393Y412659I-1502J-54D01*
G01X850372Y412672D01*
X850340Y412706D01*
X850281Y412809D01*
G02X850254Y412909I173J100D01*
G01Y463482D01*
G02X850316Y463627I200J0D01*
G01X850421Y463727D01*
X850528Y463829D01*
G02X850673Y463882I136J-147D01*
G01X850674D01*
G03X850748Y463880I78J1500D01*
G03Y466884I0J1502D01*
G03X850674Y466882I4J-1502D01*
G01X850673D01*
G02X850528Y466935I-9J200D01*
G01X850421Y467037D01*
X850316Y467137D01*
G02X850254Y467282I138J145D01*
G01Y467482D01*
Y467489D01*
G02X850300Y467610I200J-7D01*
G02X850315Y467626I153J-129D01*
G01X850523Y467826D01*
G02X850592Y467869I138J-145D01*
G01X850629Y467883D01*
X850670Y467881D01*
G03X850732Y467880I55J1501D01*
G03Y470884I0J1502D01*
G03X850670Y470883I-7J-1502D01*
G01X850629Y470881D01*
X850592Y470895D01*
G02X850523Y470938I69J188D01*
G01X850315Y471138D01*
G02X850300Y471154I138J145D01*
G02X850254Y471275I154J128D01*
G01Y495554D01*
G02X850258Y495592I200J-2D01*
G02X850311Y495694I196J-37D01*
G01X850375Y495758D01*
G03X850434Y495900I-141J142D01*
G01Y512289D01*
G02X850493Y512431I200J0D01*
G01X855131Y517069D01*
G03X855806Y518699I-1631J1630D01*
G01Y548402D01*
G02X855865Y548544I200J0D01*
G01X858437Y551116D01*
G02X858719I141J-142D01*
G01X866170Y543665D01*
G03X867800Y542990I1630J1631D01*
G01X874651D01*
G03X875198Y543056I-1J2306D01*
G01X875199D01*
G02X875369Y543019I47J-194D01*
G01X875617Y542825D01*
G02X875694Y542668I-123J-158D01*
G01Y535499D01*
G03X876369Y533869I2306J0D01*
G01X914869Y495369D01*
G03X916499Y494694I1630J1631D01*
G01X922739D01*
G02X922881Y494635I0J-200D01*
G01X949912Y467603D01*
G02X949914Y467575I-198J-28D01*
G01Y466505D01*
G02X949878Y466392I-200J1D01*
G01X949803Y466283D01*
X949758Y466246D01*
X949733Y466236D01*
G03X948879Y465292I582J-1385D01*
G03Y464410I1435J-441D01*
G03X949733Y463466I1436J441D01*
G01X949758Y463456D01*
X949803Y463419D01*
X949878Y463310D01*
G02X949914Y463197I-164J-114D01*
G01Y403739D01*
G02X949912Y403711I-200J0D01*
G01X933293Y387091D01*
G02X933151Y387032I-142J141D01*
G01X932762D01*
G02X932699Y387042I-1J200D01*
G01X932694Y387044D01*
G02X932604Y387105I63J190D01*
G01X932586Y387127D01*
X932563Y387178D01*
X932559Y387206D01*
G03X931072Y388494I-1487J-214D01*
G03X929585Y387204I0J-1502D01*
G01X929575Y387130D01*
X929462Y387032D01*
X928757D01*
G02X928559Y387204I0J200D01*
G03X925585I-1487J-212D01*
G02X925387Y387032I-198J28D01*
G01X924757D01*
G02X924559Y387204I0J200D01*
G03X921585I-1487J-212D01*
G02X921387Y387032I-198J28D01*
G01X920757D01*
G02X920559Y387204I0J200D01*
G03X917585I-1487J-212D01*
G02X917387Y387032I-198J28D01*
G01X916682D01*
X916569Y387130D01*
X916559Y387204D01*
G03X913585I-1487J-212D01*
G01X913575Y387130D01*
X913462Y387032D01*
X912682D01*
X912569Y387130D01*
X912559Y387204D01*
G03X911072Y388494I-1487J-212D01*
G03X909571Y387031I0J-1501D01*
G03X909487Y387032I-69J-2305D01*
G01X909485D01*
G37*
G36*
G01X860415Y1265523D02*
X910642D01*
G02X910783Y1265464I-1J-200D01*
G01X914520Y1261727D01*
G02X914579Y1261586I-141J-142D01*
G01Y1222918D01*
G02X914505Y1222762I-200J-1D01*
G01X914228Y1222538D01*
X914140Y1222517D01*
X914096Y1222526D01*
G03X913784Y1222559I-313J-1469D01*
G03Y1219555I0J-1502D01*
G03X914096Y1219588I-1J1502D01*
G01X914140Y1219597D01*
X914228Y1219576D01*
X914505Y1219352D01*
G02X914579Y1219196I-126J-155D01*
G01Y1216446D01*
X914483Y1216334D01*
X914409Y1216323D01*
G03Y1213353I227J-1485D01*
G01X914483Y1213342D01*
X914579Y1213230D01*
Y1212176D01*
X914483Y1212064D01*
X914409Y1212053D01*
G03Y1209083I227J-1485D01*
G01X914483Y1209072D01*
X914579Y1208960D01*
Y1200624D01*
G02X914520Y1200482I-200J0D01*
G01X912927Y1198889D01*
G02X912785Y1198830I-142J141D01*
G01X860637D01*
G02X860495Y1198889I0J200D01*
G01X859213Y1200171D01*
G02X859154Y1200313I141J142D01*
G01Y1212553D01*
G02X859188Y1212665I200J0D01*
G01X859251Y1212757D01*
X859295Y1212793D01*
X859323Y1212805D01*
G03X867593Y1225118I-5031J12313D01*
G03X862143Y1235855I-13301J0D01*
G03X859335Y1237430I-7863J-10729D01*
G01X859307Y1237442D01*
X859262Y1237478D01*
X859188Y1237587D01*
G02X859154Y1237699I166J112D01*
G01Y1264262D01*
G02X859213Y1264404I200J0D01*
G01X860273Y1265464D01*
G02X860415Y1265523I142J-141D01*
G37*
G36*
G01X926358Y610315D02*
X926334D01*
X926310Y610321D01*
G03X925949Y610365I-361J-1459D01*
G03Y607361I0J-1502D01*
G01X925951D01*
G03X926114Y607370I-1J1502D01*
G01X926158Y607375D01*
X926198Y607362D01*
G02X926269Y607321I-62J-190D01*
G01X926495Y607120D01*
G02X926558Y606983I-137J-146D01*
G01Y499087D01*
Y499083D01*
G02X926540Y499004I-200J4D01*
G01X926435Y498960D01*
G02X926216Y499004I-77J185D01*
G01X925400Y499821D01*
G03X924476Y500204I-924J-923D01*
G01X921789D01*
G02X921768Y500222I119J160D01*
G01X887317Y534673D01*
X887302Y534707D01*
G03X886545Y535464I-1371J-614D01*
G01X886511Y535479D01*
X884863Y537127D01*
G02X884805Y537279I142J141D01*
G01X884821Y537577D01*
G02X884842Y537657I200J-10D01*
G01X884861Y537694D01*
X884895Y537721D01*
G03X885451Y538887I-945J1166D01*
G01Y538888D01*
G03X883949Y540390I-1502J0D01*
G01X883948D01*
G03X883402Y540287I0J-1501D01*
G02X883195Y540324I-74J186D01*
G03X882195Y540706I-1000J-1118D01*
G01X882194D01*
G03X881944Y540685I0J-1502D01*
G01X881901Y540677D01*
X881816Y540701D01*
X881549Y540926D01*
G02X881478Y541079I129J153D01*
G01Y548016D01*
G03X881095Y548940I-1306J0D01*
G01X874705Y555329D01*
G02X874661Y555548I141J142D01*
G01X874707Y555657D01*
X874728Y555671D01*
X876509D01*
X876514D01*
G02X876637Y555625I-5J-200D01*
G02X876663Y555599I-128J-154D01*
G01X876859Y555364D01*
G02X876899Y555287I-153J-128D01*
G01X876910Y555246D01*
X876903Y555202D01*
G03X876880Y554942I1479J-262D01*
G03X878382Y556444I1502J0D01*
G03X877915Y556369I2J-1502D01*
G01X877913D01*
X877911Y556368D01*
G02X877821Y556361I-60J191D01*
G01X877774Y556368D01*
X877472Y556587D01*
G02X877389Y556749I117J162D01*
G01Y561814D01*
G03X877330Y561956I-200J0D01*
G01X874839Y564447D01*
G02X874803Y564497I142J140D01*
G02X874781Y564588I178J91D01*
G01Y576804D01*
G02X874844Y576949I200J-1D01*
G01X875086Y577178D01*
X875162Y577205D01*
X875204Y577203D01*
G03X875290Y577201I78J1500D01*
G03Y580205I0J1502D01*
G03X875204Y580203I-8J-1502D01*
G01X875162Y580201D01*
X875086Y580228D01*
X874844Y580457D01*
G02X874781Y580602I137J146D01*
G01Y603524D01*
G02X874884Y603698I200J-1D01*
G01X875216Y603861D01*
G02X875325Y603880I88J-180D01*
G02X875425Y603840I-21J-199D01*
G01X875427Y603839D01*
G03X876351Y603521I924J1183D01*
G03Y606525I0J1502D01*
G03X875428Y606208I0J-1502D01*
G02X875426Y606206I-141J139D01*
G01X875425D01*
G02X875325Y606166I-121J159D01*
G02X875216Y606185I-21J199D01*
G01X874884Y606348D01*
G02X874781Y606522I97J175D01*
G01Y607024D01*
G02X874884Y607198I200J-1D01*
G01X875216Y607361D01*
G02X875325Y607380I88J-180D01*
G02X875425Y607340I-21J-199D01*
G01X875427Y607339D01*
G03X876351Y607021I924J1183D01*
G03Y610025I0J1502D01*
G03X875428Y609708I0J-1502D01*
G02X875426Y609706I-141J139D01*
G01X875425D01*
G02X875325Y609666I-121J159D01*
G02X875216Y609685I-21J199D01*
G01X874884Y609848D01*
G02X874781Y610022I97J175D01*
G01Y612176D01*
G02X874793Y612245I200J1D01*
G01X884824Y622276D01*
G03X885206Y623198I-924J923D01*
G01Y641516D01*
G02X885265Y641658I200J0D01*
G01X899382Y655775D01*
G02X899521Y655833I141J-142D01*
G01X899602Y655834D01*
X899646Y655835D01*
G02X899771Y655789I-3J-200D01*
G01X899773Y655787D01*
G03X900753Y655423I980J1137D01*
G03X902255Y656925I0J1502D01*
G03X901891Y657905I-1501J0D01*
G01X901889Y657907D01*
G02X901843Y658032I154J128D01*
G01X901844Y658076D01*
X901845Y658157D01*
G02X901903Y658296I200J-2D01*
G01X922543Y678936D01*
G02X922684Y678994I141J-142D01*
G01X924658D01*
G02X924705Y678988I-2J-200D01*
G03X925011Y678952I305J1272D01*
G03X925075Y678954I-9J1308D01*
G01X927963D01*
X927990Y678940D01*
G03X928704Y678759I715J1321D01*
G03Y681763I0J1502D01*
G01X928702D01*
G03X928003Y681590I1J-1502D01*
G01X927983Y681579D01*
X927934Y681566D01*
X925597D01*
X925525Y681595D01*
X925500Y681620D01*
X925427Y681797D01*
X925432Y681825D01*
X928399Y684792D01*
G02X928454Y684831I142J-141D01*
G01X928484Y684845D01*
X928518Y684849D01*
G03X929846Y686176I-165J1493D01*
G01Y686177D01*
X929850Y686211D01*
X929864Y686241D01*
G02X929903Y686296I180J-87D01*
G01X964367Y720760D01*
G02X964462Y720813I141J-142D01*
G01X964489Y720820D01*
X964543Y720817D01*
X964571Y720808D01*
G03X965042Y720732I472J1426D01*
G03X966478Y721796I0J1501D01*
G01X966491Y721835D01*
X966675Y722019D01*
G02X966740Y722017I26J-199D01*
G01X967065Y721954D01*
G02X967151Y721914I-39J-196D01*
G01X967152D01*
G02X967211Y721837I-125J-157D01*
G03X968589Y720932I1378J597D01*
G03X969665Y721386I0J1502D01*
G01X969691Y721412D01*
X969721Y721427D01*
G02X969792Y721446I86J-181D01*
G01X970055Y721467D01*
G02X970125Y721460I15J-199D01*
G01X970159Y721451D01*
X970189Y721429D01*
G03X971081Y721135I893J1208D01*
G03X971894Y721374I0J1502D01*
G01X971928Y721396D01*
X971967Y721403D01*
G02X972045Y721402I36J-197D01*
G01X972321Y721342D01*
G02X972394Y721309I-44J-195D01*
G01X972426Y721287D01*
X972447Y721254D01*
G03X973712Y720562I1265J810D01*
G03X975214Y722064I0J1502D01*
G03X974385Y723407I-1502J0D01*
G02X974312Y723468I88J180D01*
G01X974299Y723487D01*
X974281Y723530D01*
X974248Y723734D01*
Y723736D01*
X974225Y723884D01*
Y723933D01*
X975224Y724932D01*
G03X975606Y725854I-924J923D01*
G01Y731916D01*
G02X975665Y732058I200J0D01*
G01X976744Y733137D01*
G02X976799Y733176I142J-141D01*
G02X976818Y733184I87J-180D01*
G01X976923Y733140D01*
G02X977046Y732956I-77J-185D01*
G01Y731509D01*
X977030Y731477D01*
G03X976850Y730766I1322J-713D01*
G03X979854I1502J0D01*
G03X979674Y731477I-1502J-2D01*
G01X979658Y731509D01*
Y734807D01*
G03X979392Y735597I-1306J0D01*
G02X979352Y735735I159J121D01*
G01X979353Y735746D01*
X988001Y744394D01*
X988037Y744409D01*
G03X988848Y745220I-576J1387D01*
G01X988863Y745256D01*
X992247Y748640D01*
G02X992275Y748664I144J-139D01*
G02X992445Y748691I113J-165D01*
G01X992466Y748683D01*
G02X992557Y748607I-77J-185D01*
G01X992572Y748585D01*
X992588Y748530D01*
Y713206D01*
G02X992586Y713178I-200J0D01*
G01X977577Y698169D01*
G02X977510Y698171I-28J198D01*
G02X977492Y698175I34J197D01*
G01X977282Y698237D01*
X977154Y698275D01*
G02X977065Y698330I57J192D01*
G01X977048Y698349D01*
X977023Y698396D01*
X977017Y698425D01*
G03X973543Y701235I-3474J-742D01*
G03X969991Y697683I0J-3552D01*
G03X972801Y694209I3552J0D01*
G01X972803D01*
G02X972898Y694159I-42J-196D01*
G01X972915Y694142D01*
X972943Y694098D01*
X972989Y693944D01*
X973051Y693734D01*
G02X973055Y693716I-193J-52D01*
G02X973057Y693649I-196J-39D01*
G01X950519Y671111D01*
G02X950377Y671052I-142J141D01*
G01X929744D01*
G03X928820Y670669I0J-1306D01*
G01X926576Y668425D01*
G03X926194Y667503I924J-923D01*
G01Y662900D01*
G03X926510Y662048I1307J0D01*
G02X926558Y661918I-152J-130D01*
G01Y614252D01*
Y614243D01*
G02X926495Y614106I-200J9D01*
G01X926269Y613905D01*
G02X926198Y613864I-133J149D01*
G01X926158Y613851D01*
X926114Y613856D01*
G03X925956Y613865I-164J-1493D01*
G01X925944D01*
G03X924447Y612363I5J-1502D01*
G03X925949Y610861I1502J0D01*
G03X926310Y610905I0J1503D01*
G01X926334Y610911D01*
X926358D01*
G02X926558Y610711I0J-200D01*
G01Y610515D01*
G02X926358Y610315I-200J0D01*
G37*
G36*
G01X984563Y1156519D02*
X994198D01*
G02X994340Y1156460I0J-200D01*
G01X995933Y1154867D01*
G02X995992Y1154725I-141J-142D01*
G01Y1014818D01*
G02X995933Y1014676I-200J0D01*
G01X994107Y1012850D01*
G02X993965Y1012791I-142J141D01*
G01X990248D01*
G02X990085Y1012876I1J200D01*
G01X989869Y1013185D01*
X989856Y1013282D01*
X989873Y1013328D01*
G03X989963Y1013839I-1412J512D01*
G01Y1013841D01*
G03X989248Y1015121I-1503J0D01*
G01X989206Y1015146D01*
X989156Y1015228D01*
X989126Y1015649D01*
X989164Y1015738D01*
X989201Y1015769D01*
G03X989742Y1016923I-960J1154D01*
G03X989115Y1018144I-1502J0D01*
G02X989031Y1018306I116J163D01*
G01Y1018632D01*
G02X989115Y1018794I200J-1D01*
G03X989742Y1020015I-875J1221D01*
G03X986738I-1502J0D01*
G03X987365Y1018794I1502J0D01*
G02X987449Y1018632I-116J-163D01*
G01Y1018306D01*
G02X987365Y1018144I-200J1D01*
G03X986738Y1016923I875J-1221D01*
G03X987453Y1015643I1503J0D01*
G01X987495Y1015618D01*
X987545Y1015536D01*
X987575Y1015115D01*
X987537Y1015026D01*
X987500Y1014995D01*
G03X986959Y1013841I960J-1154D01*
G01Y1013839D01*
G03X987049Y1013328I1502J1D01*
G01X987066Y1013282D01*
X987053Y1013185D01*
X986837Y1012876D01*
G02X986674Y1012791I-164J115D01*
G01X927167D01*
G02X927025Y1012850I0J200D01*
G01X924342Y1015533D01*
G02X924283Y1015675I141J142D01*
G01Y1058129D01*
G02X924342Y1058271I200J0D01*
G01X925935Y1059864D01*
G02X926077Y1059923I142J-141D01*
G01X976309D01*
G03X976451Y1059982I0J200D01*
G01X980067Y1063598D01*
G03X980126Y1063740I-141J142D01*
G01Y1072440D01*
G02X980185Y1072582I200J0D01*
G01X986600Y1078997D01*
G03X986659Y1079139I-141J142D01*
G01Y1082085D01*
G03X986600Y1082227I-200J0D01*
G01X982947Y1085880D01*
G02X982888Y1086022I141J142D01*
G01Y1105143D01*
G03X982829Y1105285I-200J0D01*
G01X980029Y1108085D01*
G02X979970Y1108227I141J142D01*
G01Y1151926D01*
G02X980029Y1152068I200J0D01*
G01X984421Y1156460D01*
G02X984563Y1156519I142J-141D01*
G37*
G36*
G01X924266Y1265478D02*
G02X924272Y1265483I131J-151D01*
G02X924392Y1265523I120J-160D01*
G01X973477D01*
X974000Y1265000D01*
Y1239600D01*
X978556Y1235044D01*
Y1223170D01*
G02X978498Y1223029I-200J0D01*
G01X978271Y1222800D01*
X978199Y1222770D01*
X978159D01*
G03Y1219766I10J-1502D01*
G01X978199D01*
X978271Y1219736D01*
X978498Y1219507D01*
G02X978556Y1219366I-142J-141D01*
G01Y1216446D01*
X978460Y1216334D01*
X978386Y1216323D01*
G03Y1213353I228J-1485D01*
G01X978460Y1213342D01*
X978556Y1213230D01*
Y1212176D01*
X978460Y1212064D01*
X978386Y1212053D01*
G03Y1209083I228J-1485D01*
G01X978460Y1209072D01*
X978556Y1208960D01*
Y1064481D01*
G02X978497Y1064339I-200J0D01*
G01X977014Y1062856D01*
X976986Y1062827D01*
X976912Y1062797D01*
X924466D01*
G02X924266Y1062997I0J200D01*
G01Y1265478D01*
G37*
G36*
G01X917710Y1101902D02*
G03I-600J0D01*
G37*
G36*
G01X950723Y647451D02*
X946870Y643598D01*
G03X946488Y642676I924J-923D01*
G01Y632056D01*
G02X946288Y631856I-200J0D01*
G01X941994D01*
G02X941852Y631915I0J200D01*
G01X941254Y632513D01*
X941225Y632541D01*
X941195Y632615D01*
Y666900D01*
G02X941254Y667042I200J0D01*
G01X941851Y667639D01*
G02X941993Y667698I142J-141D01*
G01X949948D01*
G02X950090Y667639I0J-200D01*
G01X950723Y667006D01*
G02X950782Y666864I-141J-142D01*
G01Y647593D01*
G02X950723Y647451I-200J0D01*
G37*
G36*
G01X940209Y809432D02*
X943139D01*
G02X943163Y809411I-119J-160D01*
G01X943390Y809170D01*
X943418Y809094D01*
X943416Y809052D01*
G03X943414Y808965I1500J-78D01*
G03X944819Y807466I1502J0D01*
G01X944858Y807464D01*
X944926Y807432D01*
X945139Y807204D01*
G02X945194Y807067I-145J-138D01*
G01Y793500D01*
G03X945654Y792118I2306J0D01*
G02X945694Y791998I-160J-120D01*
G01Y788400D01*
Y788360D01*
G02X945494Y788160I-200J0D01*
G01X944434D01*
G02X944268Y788249I0J200D01*
G01X944055Y788567D01*
X944045Y788666D01*
X944064Y788713D01*
G03X944178Y789286I-1388J574D01*
G03X942676Y790788I-1502J0D01*
G03X941234Y789708I0J-1503D01*
G01X941219Y789656D01*
X941144Y789583D01*
X940759Y789485D01*
G02X940568Y789537I-50J194D01*
G01X934459Y795646D01*
G02X934400Y795788I141J142D01*
G01Y797297D01*
G02X934409Y797357I200J1D01*
G01X934436Y797441D01*
X934451Y797465D01*
G03Y799129I-1250J832D01*
G01X934436Y799153D01*
X934409Y799237D01*
G02X934400Y799297I191J59D01*
G01Y807157D01*
G02X934459Y807299I200J0D01*
G01X936176Y809017D01*
G02X936370Y809069I142J-141D01*
G02X936389Y809063I-51J-194D01*
G01X936785Y808913D01*
X936854Y808819D01*
X936858Y808760D01*
G03X938357Y807354I1499J96D01*
G03X939859Y808856I0J1502D01*
G03X939849Y809029I-1501J0D01*
G01X939844Y809071D01*
X939870Y809153D01*
X940060Y809366D01*
G02X940209Y809432I148J-134D01*
G37*
G36*
G01X944595Y1009901D02*
X1006683D01*
G02X1006825Y1009842I0J-200D01*
G01X1008025Y1008642D01*
G02X1008080Y1008468I-142J-141D01*
G01X1008018Y1008098D01*
X1007960Y1008021D01*
X1007916Y1008000D01*
G03X1007069Y1006648I656J-1352D01*
G03X1008571Y1005146I1502J0D01*
G03X1009923Y1005993I0J1503D01*
G01X1009944Y1006037D01*
X1010021Y1006095D01*
X1010391Y1006157D01*
G02X1010565Y1006102I33J-197D01*
G01X1012810Y1003857D01*
G02X1012869Y1003715I-141J-142D01*
G01Y998909D01*
G02X1012826Y998786I-200J1D01*
G03X1012507Y997860I1183J-926D01*
G03X1012826Y996934I1502J0D01*
G02X1012869Y996811I-157J-124D01*
G01Y989862D01*
G02X1012826Y989739I-200J1D01*
G03X1012507Y988813I1183J-926D01*
G03X1012826Y987887I1502J0D01*
G02X1012869Y987764I-157J-124D01*
G01Y981405D01*
G02X1012826Y981282I-200J1D01*
G03X1012507Y980356I1183J-926D01*
G03X1012826Y979430I1502J0D01*
G02X1012869Y979307I-157J-124D01*
G01Y956107D01*
G02X1012801Y955957I-200J0D01*
G01X1012542Y955730D01*
X1012460Y955705D01*
X1012416Y955711D01*
G03X1012219Y955724I-197J-1489D01*
G03Y952720I0J-1502D01*
G03X1012416Y952733I0J1502D01*
G01X1012460Y952739D01*
X1012542Y952714D01*
X1012801Y952487D01*
G02X1012869Y952337I-132J-150D01*
G01Y950053D01*
G02X1012738Y949865I-200J0D01*
G01X1012326Y949714D01*
X1012205Y949745D01*
X1012164Y949794D01*
G03X1011019Y950324I-1145J-972D01*
G03X1009795Y949692I0J-1501D01*
G02X1009632Y949608I-163J116D01*
G01X1009306D01*
G02X1009143Y949692I0J200D01*
G03X1007919Y950324I-1224J-869D01*
G03X1006655Y949634I0J-1503D01*
G02X1006487Y949542I-168J108D01*
G01X1006151D01*
G02X1005983Y949634I0J200D01*
G03X1004719Y950324I-1264J-813D01*
G03Y947320I0J-1502D01*
G03X1005983Y948010I0J1503D01*
G02X1006151Y948102I168J-108D01*
G01X1006487D01*
G02X1006655Y948010I0J-200D01*
G03X1007919Y947320I1264J813D01*
G03X1009143Y947952I0J1501D01*
G02X1009306Y948036I163J-116D01*
G01X1009632D01*
G02X1009795Y947952I0J-200D01*
G03X1011019Y947320I1224J869D01*
G03X1012164Y947850I0J1502D01*
G01X1012205Y947899D01*
X1012326Y947930D01*
X1012738Y947779D01*
G02X1012869Y947591I-69J-188D01*
G01Y929420D01*
G03X1012928Y929278I200J0D01*
G01X1016472Y925734D01*
G03X1016614Y925675I142J141D01*
G01X1035368D01*
G03X1035510Y925734I0J200D01*
G01X1039360Y929584D01*
G03X1039419Y929726I-141J142D01*
G01Y988294D01*
X1039430Y988326D01*
G03X1039511Y988813I-1421J487D01*
G03X1039430Y989300I-1502J0D01*
G01X1039419Y989332D01*
Y997341D01*
X1039430Y997373D01*
G03X1039511Y997860I-1421J487D01*
G03X1039430Y998347I-1502J0D01*
G01X1039419Y998379D01*
Y1003409D01*
G02X1039478Y1003551I200J0D01*
G01X1042717Y1006790D01*
G02X1042859Y1006849I142J-141D01*
G01X1074430D01*
G02X1074572Y1006790I0J-200D01*
G01X1078781Y1002581D01*
G02X1078839Y1002421I-141J-142D01*
G01X1073071Y939426D01*
G02X1073068Y939407I-199J22D01*
G01X1061001Y875593D01*
G02X1060946Y875489I-197J37D01*
G01X1057177Y871720D01*
G02X1057035Y871661I-142J141D01*
G01X1047180D01*
G02X1047028Y871731I0J200D01*
G01X1046801Y871995D01*
X1046778Y872079D01*
X1046784Y872122D01*
G03X1046802Y872352I-1484J232D01*
G03X1045741Y873788I-1502J0D01*
G02X1045667Y873829I58J192D01*
G03X1044800Y874158I-867J-978D01*
G01X1044328D01*
G02X1044187Y874217I1J200D01*
G01X1036777Y881627D01*
X1036753Y881667D01*
X1036745Y881690D01*
G03X1036424Y882219I-1246J-394D01*
G01X1026356Y892287D01*
G02X1026297Y892429I141J142D01*
G01Y896449D01*
G03X1026238Y896591I-200J0D01*
G01X1013836Y908993D01*
G02X1013778Y909139I142J141D01*
G01X1013786Y909470D01*
X1013820Y909544D01*
X1013851Y909572D01*
G03X1014344Y910685I-1010J1113D01*
G03X1012842Y912187I-1502J0D01*
G03X1011729Y911694I0J-1503D01*
G01X1011701Y911663D01*
X1011627Y911629D01*
X1011296Y911621D01*
G02X1011150Y911679I-5J200D01*
G01X958305Y964524D01*
G03X958163Y964583I-142J-141D01*
G01X958000D01*
G02X957858Y964642I0J200D01*
G01X942588Y979912D01*
G02X942529Y980054I141J142D01*
G01Y1007835D01*
G02X942588Y1007977I200J0D01*
G01X944453Y1009842D01*
G02X944595Y1009901I142J-141D01*
G37*
G36*
G01X933959Y1441555D02*
X1046284D01*
G02X1046426Y1441496I0J-200D01*
G01X1046891Y1441031D01*
G02X1046950Y1440889I-141J-142D01*
G01Y1424165D01*
G02X1046891Y1424023I-200J0D01*
G01X1029614Y1406746D01*
X1029563D01*
X1027973Y1405156D01*
G02X1027831Y1405097I-142J141D01*
G01X1006517D01*
G02X1006376Y1405156I1J200D01*
G01X1006154Y1405378D01*
G03X1006012Y1405436I-141J-142D01*
G01X993468D01*
G02X993327Y1405495I1J200D01*
G01X982440Y1416382D01*
G03X982298Y1416441I-142J-141D01*
G01X939372D01*
G02X939230Y1416500I0J200D01*
G01X932557Y1423173D01*
G02X932498Y1423315I141J142D01*
G01Y1440094D01*
G02X932557Y1440236I200J0D01*
G01X933817Y1441496D01*
G02X933959Y1441555I142J-141D01*
G37*
G36*
G01X954038Y1480156D02*
Y1451122D01*
G02X953979Y1450980I-200J0D01*
G01X953597Y1450598D01*
G02X953455Y1450539I-142J141D01*
G01X930362D01*
G02X930220Y1450598I0J200D01*
G01X929479Y1451339D01*
G02X929420Y1451481I141J142D01*
G01Y1481025D01*
G02X929479Y1481167I200J0D01*
G01X930392Y1482080D01*
G02X930534Y1482139I142J-141D01*
G01X952055D01*
G02X952197Y1482080I0J-200D01*
G01X953979Y1480298D01*
G02X954038Y1480156I-141J-142D01*
G37*
G36*
G01X986984Y1487199D02*
X1039022D01*
G02X1039220Y1487024I0J-200D01*
G03X1049000Y1467902I31264J3928D01*
G02X1049064Y1467755I-136J-147D01*
G01Y1451774D01*
G02X1049005Y1451633I-200J1D01*
G01X1048392Y1451020D01*
G02X1048250Y1450961I-142J141D01*
G01X958816D01*
X958794Y1450939D01*
X955821D01*
G02X955679Y1450998I0J200D01*
G01X955197Y1451480D01*
G02X955138Y1451622I141J142D01*
G01Y1480377D01*
G02X955197Y1480519I200J0D01*
G01X956419Y1481741D01*
G02X956561Y1481800I142J-141D01*
G01X981419D01*
G03X981561Y1481859I0J200D01*
G01X986842Y1487140D01*
G02X986984Y1487199I142J-141D01*
G37*
G36*
G01X990806Y324641D02*
X986466Y328981D01*
G03X986324Y329040I-142J-141D01*
G01X978698D01*
G02X978519Y329151I0J200D01*
G03X977150Y330000I-1369J-679D01*
G03X976137Y329616I0J-1528D01*
G02X975877Y329611I-133J150D01*
G02X975863Y329624I129J153D01*
G01X975391Y330096D01*
G02X975355Y330146I142J140D01*
G02X975333Y330237I178J91D01*
G01Y334211D01*
G02X975339Y334260I200J0D01*
G01X975368Y334374D01*
G03X975374Y334422I-194J49D01*
G01Y334828D01*
G02X975574Y335028I200J0D01*
G02X975759Y334904I0J-200D01*
G03X977150Y333970I1391J569D01*
G03Y336974I0J1502D01*
G03X975759Y336040I0J-1503D01*
G01X975736Y335984D01*
X975635Y335916D01*
X975574D01*
G02X975374Y336116I0J200D01*
G01Y336522D01*
G03X975368Y336570I-200J-1D01*
G01X975339Y336684D01*
G02X975333Y336733I194J49D01*
G01Y341221D01*
G02X975339Y341270I200J0D01*
G01X975374Y341407D01*
G02X975430Y341503I194J-49D01*
G01X975485Y341555D01*
G02X975623Y341610I138J-145D01*
G01X975631D01*
G03Y344614I0J1502D01*
G01X975622D01*
G02X975485Y344668I0J200D01*
G01X975433Y344717D01*
G02X975370Y344863I137J146D01*
G01Y344903D01*
X975403Y344979D01*
X975485Y345056D01*
G02X975601Y345109I137J-146D01*
G01X975612Y345110D01*
X975631D01*
G03X977133Y346612I0J1502D01*
G03X975712Y348112I-1502J0D01*
G02X975577Y348174I10J200D01*
G01X975388Y348374D01*
G02X975333Y348512I145J138D01*
G01Y353153D01*
G02X975342Y353211I200J-1D01*
G01X980503Y370243D01*
G02X980545Y370318I192J-58D01*
G01X980549Y370322D01*
X984394Y374167D01*
G02X984501Y374221I139J-143D01*
G02X984534Y374224I35J-197D01*
G01X1003326D01*
G02X1003359Y374221I-2J-200D01*
G02X1003466Y374167I-32J-197D01*
G01X1011029Y366604D01*
G03X1011171Y366545I142J141D01*
G01X1038120D01*
G03X1038262Y366604I0J200D01*
G01X1045825Y374167D01*
G02X1045932Y374221I139J-143D01*
G02X1045965Y374224I35J-197D01*
G01X1061636D01*
G02X1061669Y374221I-2J-200D01*
G02X1061776Y374167I-32J-197D01*
G01X1062386Y373557D01*
X1062387Y373556D01*
G02X1062445Y373420I-142J-141D01*
G02X1062444Y373399I-200J-1D01*
G01X1061829Y365749D01*
G02X1061720Y365587I-199J16D01*
G01X1061710Y365582D01*
G02X1061695Y365575I-92J178D01*
G02X1061619Y365560I-76J185D01*
G01X1061514D01*
G02X1061465Y365566I0J200D01*
G01X1061437Y365573D01*
X1061414Y365586D01*
G03X1060679Y365778I-735J-1311D01*
G03Y362774I0J-1502D01*
G01X1060680D01*
G03X1061213Y362872I-1J1502D01*
G01X1061257Y362889D01*
G02X1061426Y362871I65J-189D01*
G01X1061497Y362819D01*
G02X1061579Y362641I-117J-162D01*
G01X1061507Y361745D01*
G02X1061417Y361593I-200J16D01*
G01X1061404Y361585D01*
X1061386Y361574D01*
G02X1061301Y361544I-107J169D01*
G01X1061255Y361539D01*
X1061210Y361556D01*
G03X1060679Y361653I-531J-1405D01*
G03Y358649I0J-1502D01*
G03X1060982Y358680I-1J1502D01*
G01X1061003Y358684D01*
G02X1061064Y358681I21J-199D01*
G01X1061082Y358676D01*
G02X1061149Y358640I-60J-191D01*
G01X1061177Y358615D01*
G02X1061243Y358450I-133J-149D01*
G01X1060111Y344342D01*
G02X1060085Y344260I-199J18D01*
G01Y344259D01*
G03X1059885Y343511I1302J-749D01*
G01Y343509D01*
G03X1059981Y342981I1502J0D01*
G01X1059997Y342939D01*
X1055379Y285411D01*
G02X1055179Y285227I-199J16D01*
G01X1038753D01*
G03X1038678Y285212I1J-200D01*
G01X1038640Y285197D01*
X988259D01*
G02X988117Y285256I0J200D01*
G01X987801Y285572D01*
G02X987742Y285714I141J142D01*
G01Y289048D01*
G03X987683Y289190I-200J0D01*
G01X986444Y290429D01*
G03X986302Y290488I-142J-141D01*
G01X979964D01*
G02X979822Y290547I0J200D01*
G01X976499Y293870D01*
G02X976460Y293925I141J142D01*
G01X976447Y293952D01*
X976442Y293986D01*
G03X975465Y295208I-1490J-190D01*
G01X975464D01*
G02X975368Y295283I69J188D01*
G01X975351Y295307D01*
X975333Y295364D01*
Y303321D01*
G02X975533Y303521I200J0D01*
G01X986660D01*
G03X986802Y303580I0J200D01*
G01X990806Y307584D01*
G03X990865Y307726I-141J142D01*
G01Y324499D01*
G03X990806Y324641I-200J0D01*
G37*
G36*
G01X964962Y1566784D02*
X993823D01*
G02X993965Y1566725I0J-200D01*
G01X995797Y1564893D01*
G02X995856Y1564751I-141J-142D01*
G01Y1547091D01*
G02X995797Y1546949I-200J0D01*
G01X993903Y1545055D01*
G02X993761Y1544996I-142J141D01*
G01X965293D01*
G02X965151Y1545055I0J200D01*
G01X963569Y1546637D01*
G02X963510Y1546779I141J142D01*
G01Y1565332D01*
G02X963569Y1565474I200J0D01*
G01X964820Y1566725D01*
G02X964962Y1566784I142J-141D01*
G37*
G36*
G01X1051831Y54588D02*
X1080886D01*
X1081101Y54373D01*
Y52806D01*
X1080886Y52591D01*
X1051831D01*
G03X1045894Y46654I0J-5937D01*
G01Y7874D01*
G02X1040020Y2000I-5874J0D01*
G01X992776D01*
G02X986902Y7874I0J5874D01*
G01Y46654D01*
G03Y46659I-5936J2D01*
G01X988900D01*
G02Y46654I-7934J-2D01*
G01Y7874D01*
G03X992776Y3998I3876J0D01*
G01X1040020D01*
G03X1043896Y7874I0J3876D01*
G01Y46654D01*
G02X1051831Y54588I7935J-1D01*
G37*
G36*
G01X1072684Y675813D02*
X1070157Y644510D01*
G03X1070152Y644436I3880J-299D01*
G01X1067829Y606632D01*
Y606628D01*
X1064688Y566696D01*
Y566690D01*
X1063545Y555832D01*
G03X1063524Y555434I3870J-404D01*
G01X1063501Y545370D01*
G03X1063500Y545361I3844J-432D01*
G03X1063536Y544835I3892J2D01*
G01X1064158Y540271D01*
G02X1064081Y540085I-198J-27D01*
G01X1064080Y540084D01*
X1063911Y539957D01*
X1063794Y539870D01*
G02X1063762Y539852I-114J164D01*
G01X1063601D01*
X1063564Y539868D01*
G03X1062865Y540008I-696J-1663D01*
G01X1062823Y540009D01*
G03X1061062Y538207I42J-1803D01*
G01Y534806D01*
G03X1062863Y533004I1802J0D01*
G03X1062865I1J1802D01*
G03X1063757Y533240I0J1802D01*
G02X1063900Y533261I99J-174D01*
G01X1064020Y533234D01*
G02X1064139Y533155I-44J-195D01*
G03X1065055Y532557I1223J872D01*
G01X1065075Y532552D01*
X1065190Y532431D01*
G02X1065243Y532320I-145J-138D01*
G01X1066530Y522881D01*
Y522875D01*
X1066912Y519340D01*
G02X1066913Y519320I-199J-20D01*
G01X1067435Y470890D01*
Y470882D01*
X1065908Y420453D01*
X1065715Y414570D01*
X1065691Y413859D01*
Y413849D01*
X1065450Y410851D01*
G03X1065361Y410854I-95J-1499D01*
G03X1064097Y410163I0J-1502D01*
G02X1063827Y410099I-168J108D01*
G03X1062865Y410377I-962J-1525D01*
G03X1061062Y408574I0J-1803D01*
G01Y405174D01*
G03X1062865Y403371I1803J0D01*
G01X1062867D01*
G03X1063801Y403632I0J1803D01*
G01X1063824Y403646D01*
X1063851Y403654D01*
G02X1064001Y403637I54J-193D01*
G01X1064074Y403597D01*
X1064108Y403566D01*
X1064122Y403546D01*
G03X1064492Y403171I1238J851D01*
G03X1064726Y403035I869J1225D01*
G02X1064729Y403033I-108J-166D01*
G01X1064753Y403022D01*
X1064813Y402915D01*
X1064280Y396285D01*
G02X1064231Y396169I-199J16D01*
G03X1064139Y396052I1133J-986D01*
G02X1064020Y395973I-163J116D01*
G01X1063901Y395946D01*
G02X1063758Y395967I-44J195D01*
G03X1062865Y396204I-893J-1565D01*
G01X1062863D01*
G03X1062665Y396193I1J-1803D01*
G03X1061062Y394401I200J-1792D01*
G01Y391001D01*
G03X1062865Y389198I1803J0D01*
G03X1063079Y389211I-2J1803D01*
G03X1063373Y389272I-218J1789D01*
G01X1063374D01*
X1063401Y389280D01*
X1063421Y389286D01*
X1063517Y389266D01*
X1063522Y389262D01*
X1063623Y389179D01*
G02X1063697Y389008I-125J-156D01*
G01X1063305Y384132D01*
G02X1063202Y383973I-199J16D01*
G01X1063126Y383930D01*
G02X1063097Y383917I-96J176D01*
G02X1062934Y383929I-68J188D01*
G01X1062933D01*
G03X1062234Y384102I-700J-1329D01*
G03Y381098I0J-1502D01*
G01X1062237D01*
G03X1062716Y381177I-2J1502D01*
G01X1062736Y381184D01*
G02X1062903Y381146I43J-195D01*
G01X1062970Y381094D01*
G02X1063046Y380920I-123J-157D01*
G01X1062992Y380231D01*
G02X1062903Y380080I-199J16D01*
G01X1062864Y380054D01*
G02X1062852Y380046I-117J162D01*
G02X1062703Y380027I-98J175D01*
G01X1062693Y380030D01*
G03X1062234Y380102I-459J-1430D01*
G03Y377098I0J-1502D01*
G01X1062237D01*
G03X1062471Y377116I2J1502D01*
G02X1062628Y377064I21J-199D01*
G01X1062632Y377060D01*
X1062659Y377035D01*
G02X1062722Y376872I-136J-146D01*
G01X1062593Y375269D01*
G02X1062487Y375109I-199J17D01*
G01X1062415Y375070D01*
G02X1062319Y375047I-93J177D01*
G01X1062269D01*
X1062224Y375072D01*
G03X1061637Y375226I-589J-1048D01*
G01X1043882D01*
G02X1043740Y375285I0J200D01*
G01X1040203Y378822D01*
G02X1040144Y378964I141J142D01*
G01Y381036D01*
X1040158Y381071D01*
G03X1041568Y388578I-19292J7510D01*
G01Y388583D01*
G03X1000164I-20702J0D01*
G01Y388580D01*
G03X1003631Y377113I20702J2D01*
G01X1003671Y377053D01*
X1003657Y376912D01*
X1002030Y375285D01*
G02X1001888Y375226I-142J141D01*
G01X985299D01*
G02X985157Y375285I0J200D01*
G01X982844Y377598D01*
G02X982794Y377798I141J142D01*
G01X991876Y407764D01*
X991934Y407829D01*
X991965Y407842D01*
G03X992894Y409230I-572J1388D01*
G01Y409244D01*
G03X992892Y409298I-1501J-29D01*
G01Y409300D01*
G03X992626Y410087I-1501J-69D01*
G02X992624Y410091I176J91D01*
G01X992596Y410133D01*
Y410137D01*
X997693Y426953D01*
X1009884Y466883D01*
G03X1010021Y467521I-3723J1133D01*
G01X1010043Y467690D01*
G02X1010050Y467722I198J-27D01*
G01X1010359Y468741D01*
G03X1010494Y469368I-3758J1137D01*
G01X1023428Y567694D01*
G02X1023430Y567706I198J-27D01*
G01X1065214Y788672D01*
X1070891Y818644D01*
X1077785Y855035D01*
G02X1077873Y855156I194J-48D01*
G01X1078165Y855312D01*
G02X1078254Y855334I91J-178D01*
G01X1078331Y855318D01*
X1078344Y855313D01*
G03X1078920Y855198I576J1385D01*
G03X1080422Y856700I0J1502D01*
G03X1078921Y858202I-1502J0D01*
G01X1078919D01*
G03X1078878Y858201I16J-1502D01*
G01X1078877D01*
G02X1078729Y858262I-4J200D01*
G01X1078512Y858516D01*
G02X1078474Y858676I158J122D01*
G01X1085444Y895471D01*
G02X1085641Y895634I197J-37D01*
G01X1090223D01*
G02X1090370Y895570I0J-200D01*
G01X1090371Y895569D01*
G02X1090423Y895418I-147J-135D01*
G01X1089844Y888259D01*
X1087315Y856945D01*
X1082515Y797515D01*
X1080479Y772313D01*
X1079800Y763904D01*
X1079079Y754982D01*
X1073611Y687284D01*
Y687282D01*
G03X1073604Y687205I3872J-391D01*
G01X1072684Y675813D01*
G37*
G36*
G01X981687Y1101902D02*
G03I-600J0D01*
G37*
G36*
G01X1010578Y1187068D02*
G02X1010696Y1187030I1J-200D01*
G03X1011489Y1186587I2281J3152D01*
G01X1014365Y1185396D01*
G03X1014384Y1185388I1519J3582D01*
G01X1014385D01*
X1015714Y1184837D01*
G02X1015737Y1184826I-74J-185D01*
G02X1015785Y1184788I-99J-174D01*
G01X1015826Y1184744D01*
X1015841Y1184728D01*
X1015882Y1184661D01*
X1015888Y1184642D01*
G03X1017278Y1183662I1409J522D01*
G01X1017300D01*
G03X1017955Y1183814I-3J1502D01*
G01X1017976Y1183824D01*
X1018030Y1183837D01*
G02X1018108Y1183839I44J-195D01*
G01X1018132Y1183835D01*
X1024337Y1181265D01*
G02X1024460Y1181081I-77J-185D01*
G01Y1179336D01*
G02X1024359Y1179163I-200J1D01*
G01X1024011Y1178963D01*
X1023906Y1178964D01*
X1023859Y1178991D01*
G03X1023107Y1179193I-752J-1300D01*
G01X1023106D01*
G03Y1176189I0J-1502D01*
G01X1023107D01*
G03X1023859Y1176391I0J1502D01*
G01X1023906Y1176418D01*
X1024011Y1176419D01*
X1024356Y1176222D01*
X1024375Y1176202D01*
X1024401Y1176176D01*
G02X1024460Y1176034I-141J-142D01*
G01Y1166736D01*
G02X1024359Y1166563I-200J1D01*
G01X1024011Y1166363D01*
X1023906Y1166364D01*
X1023859Y1166391D01*
G03X1023107Y1166593I-752J-1300D01*
G01X1023106D01*
G03Y1163589I0J-1502D01*
G01X1023107D01*
G03X1023859Y1163791I0J1502D01*
G01X1023906Y1163818D01*
X1024011Y1163819D01*
X1024356Y1163622D01*
X1024375Y1163602D01*
X1024401Y1163576D01*
G02X1024460Y1163434I-141J-142D01*
G01Y1154136D01*
G02X1024359Y1153963I-200J1D01*
G01X1024011Y1153763D01*
X1023906Y1153764D01*
X1023859Y1153791D01*
G03X1023107Y1153993I-752J-1300D01*
G01X1023106D01*
G03Y1150989I0J-1502D01*
G01X1023107D01*
G03X1023859Y1151191I0J1502D01*
G01X1023906Y1151218D01*
X1024011Y1151219D01*
X1024356Y1151022D01*
X1024375Y1151002D01*
X1024401Y1150976D01*
G02X1024460Y1150834I-141J-142D01*
G01Y1141536D01*
G02X1024359Y1141363I-200J1D01*
G01X1024011Y1141163D01*
X1023906Y1141164D01*
X1023859Y1141191D01*
G03X1023107Y1141393I-752J-1300D01*
G01X1023106D01*
G03Y1138389I0J-1502D01*
G01X1023107D01*
G03X1023859Y1138591I0J1502D01*
G01X1023906Y1138618D01*
X1024011Y1138619D01*
X1024356Y1138422D01*
X1024375Y1138402D01*
X1024401Y1138376D01*
G02X1024460Y1138234I-141J-142D01*
G01Y1128936D01*
G02X1024359Y1128763I-200J1D01*
G01X1024011Y1128563D01*
X1023906Y1128564D01*
X1023859Y1128591D01*
G03X1023107Y1128793I-752J-1300D01*
G01X1023106D01*
G03Y1125789I0J-1502D01*
G01X1023107D01*
G03X1023859Y1125991I0J1502D01*
G01X1023906Y1126018D01*
X1024011Y1126019D01*
X1024356Y1125822D01*
X1024375Y1125802D01*
X1024401Y1125776D01*
G02X1024460Y1125634I-141J-142D01*
G01Y1116336D01*
G02X1024359Y1116163I-200J1D01*
G01X1024011Y1115963D01*
X1023906Y1115964D01*
X1023859Y1115991D01*
G03X1023107Y1116193I-752J-1300D01*
G01X1023106D01*
G03Y1113189I0J-1502D01*
G01X1023107D01*
G03X1023859Y1113391I0J1502D01*
G01X1023906Y1113418D01*
X1024011Y1113419D01*
X1024356Y1113222D01*
X1024375Y1113202D01*
X1024401Y1113176D01*
G02X1024460Y1113034I-141J-142D01*
G01Y1103736D01*
G02X1024359Y1103563I-200J1D01*
G01X1024011Y1103363D01*
X1023906Y1103364D01*
X1023859Y1103391D01*
G03X1023107Y1103593I-752J-1300D01*
G01X1023106D01*
G03Y1100589I0J-1502D01*
G01X1023107D01*
G03X1023859Y1100791I0J1502D01*
G01X1023906Y1100818D01*
X1024011Y1100819D01*
X1024356Y1100622D01*
X1024375Y1100602D01*
X1024401Y1100576D01*
G02X1024460Y1100434I-141J-142D01*
G01Y1097934D01*
X1024430Y1097860D01*
X1024401Y1097832D01*
X1010611Y1084042D01*
G03X1010552Y1083900I141J-142D01*
G01Y1058194D01*
G03X1010611Y1058052I200J0D01*
G01X1037528Y1031135D01*
G02X1037587Y1030993I-141J-142D01*
G01Y1023420D01*
X1037489Y1023248D01*
G03Y1020660I763J-1294D01*
G01X1037587Y1020488D01*
Y1010820D01*
X1037489Y1010648D01*
G03Y1008060I763J-1294D01*
G01X1037587Y1007888D01*
Y999382D01*
X1037518Y999281D01*
X1037460Y999258D01*
G03Y996462I549J-1398D01*
G01X1037518Y996439D01*
X1037587Y996338D01*
Y990335D01*
X1037518Y990234D01*
X1037460Y990211D01*
G03Y987415I549J-1398D01*
G01X1037518Y987392D01*
X1037587Y987291D01*
Y931097D01*
G02X1037528Y930955I-200J0D01*
G01X1036044Y929471D01*
G02X1035902Y929412I-142J141D01*
G01X1016385D01*
G02X1016243Y929471I0J200D01*
G01X1015064Y930650D01*
G02X1015005Y930792I141J142D01*
G01Y936758D01*
X1015084Y936863D01*
X1015148Y936883D01*
G03Y939761I-428J1439D01*
G01X1015084Y939781D01*
X1015005Y939886D01*
Y979230D01*
G03X1015512Y980356I-997J1126D01*
G03X1015508Y980464I-1503J-2D01*
G03X1015064Y981625I-1499J92D01*
G02X1015005Y981767I141J142D01*
G01Y987602D01*
G02X1015064Y987744I200J0D01*
G03Y989882I-1055J1069D01*
G02X1015005Y990024I141J142D01*
G01Y996649D01*
G02X1015064Y996791I200J0D01*
G03Y998929I-1055J1069D01*
G02X1015005Y999071I141J142D01*
G01Y1005366D01*
G03X1014946Y1005508I-200J0D01*
G01X1006256Y1014198D01*
G03X1006114Y1014257I-142J-141D01*
G01X997213Y1023158D01*
G02X997154Y1023300I141J142D01*
G01Y1157172D01*
X997184Y1157246D01*
X997213Y1157274D01*
X998222Y1158283D01*
G02X998254Y1158309I141J-141D01*
G01X998305Y1158342D01*
X998324Y1158350D01*
G03X1000069Y1159179I-4820J12398D01*
G03X1002228Y1160706I-6564J11570D01*
G03X996794Y1183647I-8714J10050D01*
G02X996643Y1183841I49J194D01*
G01Y1184346D01*
X996673Y1184420D01*
X996702Y1184448D01*
X999263Y1187009D01*
G02X999405Y1187068I142J-141D01*
G01X1010578D01*
G37*
G36*
G01X1008115Y1385339D02*
Y1397292D01*
G02X1008174Y1397434I200J0D01*
G01X1009408Y1398668D01*
G02X1009550Y1398727I142J-141D01*
G01X1030131D01*
G02X1030273Y1398668I0J-200D01*
G01X1031581Y1397360D01*
G02X1031640Y1397218I-141J-142D01*
G01Y1385364D01*
G02X1031581Y1385222I-200J0D01*
G01X1030949Y1384590D01*
G02X1030807Y1384531I-142J141D01*
G01X1008923D01*
G02X1008781Y1384590I0J200D01*
G01X1008174Y1385197D01*
G02X1008115Y1385339I141J142D01*
G37*
G36*
G01X1062097Y1175736D02*
X1063514Y1177153D01*
G02X1063631Y1177203I133J-150D01*
G01X1063918Y1177210D01*
G02X1063993Y1177197I4J-200D01*
G01X1064027Y1177184D01*
X1064056Y1177158D01*
G03X1064861Y1176849I805J894D01*
G03X1066063Y1178051I0J1202D01*
G03X1065637Y1178969I-1202J0D01*
G01X1065630Y1178975D01*
X1065624Y1178981D01*
G02Y1179263I142J141D01*
G01X1065765Y1179404D01*
G02X1065906Y1179462I141J-142D01*
G01X1067360D01*
G02X1067535Y1179357I-1J-200D01*
G01X1067619Y1179184D01*
Y1179182D01*
X1067649Y1179119D01*
G02X1067622Y1178910I-182J-83D01*
G01X1067617Y1178904D01*
X1067615Y1178902D01*
G03X1067310Y1178217I987J-850D01*
G01Y1178215D01*
G03X1067304Y1178155I1293J-160D01*
G01X1067301Y1178119D01*
G03X1067299Y1178051I1301J-72D01*
G03X1068601Y1176748I1303J0D01*
G01X1072342D01*
G03X1073644Y1178049I0J1302D01*
G03Y1178051I-1302J1D01*
G03X1073329Y1178902I-1303J2D01*
G01X1073327Y1178904D01*
X1073322Y1178910D01*
G02X1073295Y1179119I155J126D01*
G01X1073325Y1179182D01*
Y1179184D01*
X1073409Y1179357D01*
G02X1073584Y1179462I176J-95D01*
G01X1074840D01*
G02X1075020Y1179348I0J-200D01*
G01X1075169Y1179036D01*
Y1179034D01*
X1075175Y1179022D01*
G02X1075194Y1178910I-180J-88D01*
G01X1075191Y1178884D01*
X1075169Y1178834D01*
X1075150Y1178810D01*
G03X1074880Y1178051I932J-759D01*
G03X1077284I1202J0D01*
G01Y1178053D01*
G03X1077030Y1178791I-1202J-1D01*
G01X1077014Y1178811D01*
X1076970Y1178914D01*
X1076967Y1178939D01*
X1076976Y1178996D01*
X1076995Y1179035D01*
X1077144Y1179348D01*
G02X1077324Y1179462I180J-86D01*
G01X1077355D01*
G03X1079920Y1180460I-1J3797D01*
G01X1079946Y1180485D01*
X1080045Y1180525D01*
G02X1080083Y1180536I74J-186D01*
G02X1080119Y1180539I35J-197D01*
G01X1080354D01*
G02X1080554Y1180339I0J-200D01*
G01Y1180309D01*
X1080545Y1180279D01*
G03X1080490Y1179921I1147J-359D01*
G03X1080511Y1179698I1202J1D01*
G01X1080520Y1179649D01*
X1080491Y1179556D01*
X1080222Y1179286D01*
G02X1080045Y1179231I-141J142D01*
G01X1080044D01*
G03X1079822Y1179252I-224J-1181D01*
G03X1081024Y1178050I0J-1202D01*
G03X1081003Y1178273I-1202J-1D01*
G01X1080994Y1178322D01*
X1081023Y1178415D01*
X1081292Y1178685D01*
G02X1081469Y1178740I141J-142D01*
G01X1081470D01*
G03X1081692Y1178719I224J1181D01*
G03X1082894Y1179921I0J1202D01*
G03X1082883Y1180085I-1202J2D01*
G01X1082877Y1180127D01*
X1082902Y1180211D01*
X1083128Y1180471D01*
G02X1083279Y1180539I150J-132D01*
G01X1101615D01*
G02X1101652Y1180535I-3J-200D01*
G01X1101654D01*
G02X1101755Y1180482I-39J-196D01*
G01X1102206Y1180031D01*
G02X1102259Y1179930I-143J-140D01*
G01Y1179928D01*
G02X1102263Y1179891I-196J-40D01*
G01Y1179438D01*
G02X1102214Y1179307I-200J0D01*
G01X1102192Y1179280D01*
X1102127Y1179246D01*
X1102088Y1179241D01*
G03X1101396Y1177218I176J-1190D01*
G03X1102091Y1176861I867J833D01*
G01X1102097Y1176860D01*
X1102115Y1176858D01*
G02X1102225Y1176793I-42J-196D01*
G01X1102263Y1176749D01*
G03X1102618Y1176799I-2J1302D01*
G01X1102664Y1176812D01*
X1102708Y1176804D01*
G02X1102750Y1176791I-38J-196D01*
G03X1102753Y1176788I866J863D01*
G01X1102768Y1176773D01*
G03X1102895Y1176664I858J871D01*
G02X1102897Y1176662I-139J-141D01*
G01X1103036Y1176556D01*
G02X1103108Y1176414I-107J-144D01*
G01Y1172207D01*
G02X1103049Y1172075I-179J1D01*
G01X1102879Y1171946D01*
G03X1102747Y1171828I746J-968D01*
G02X1102708Y1171817I-74J186D01*
G01X1102664Y1171809D01*
X1102618Y1171822D01*
G03X1102263Y1171872I-357J-1252D01*
G03X1100961Y1170570I0J-1302D01*
G03X1101109Y1169968I1302J1D01*
G01Y1169967D01*
X1101110Y1169966D01*
G02X1101132Y1169869I-178J-91D01*
G01X1101130Y1169816D01*
X1101071Y1169719D01*
X1100920Y1169470D01*
G02X1100778Y1169383I-166J111D01*
G01X1100766Y1169382D01*
X1100027D01*
G02X1100009Y1169383I2J200D01*
G01X1100008D01*
G02X1099865Y1169472I24J198D01*
G01X1099823Y1169541D01*
X1099679Y1169778D01*
G02X1099654Y1169869I175J97D01*
G01X1099653Y1169919D01*
X1099683Y1169978D01*
X1099697Y1170007D01*
G03X1099825Y1170570I-1174J563D01*
G03X1097221I-1302J0D01*
G03X1097369Y1169968I1302J1D01*
G01Y1169967D01*
X1097370Y1169966D01*
G02X1097392Y1169869I-178J-91D01*
G01X1097390Y1169816D01*
X1097331Y1169719D01*
X1097180Y1169470D01*
G02X1097038Y1169383I-166J111D01*
G01X1097026Y1169382D01*
X1096287D01*
G02X1096269Y1169383I2J200D01*
G01X1096268D01*
G02X1096125Y1169472I24J198D01*
G01X1096083Y1169541D01*
X1095939Y1169778D01*
G02X1095914Y1169869I175J97D01*
G01X1095913Y1169919D01*
X1095943Y1169978D01*
X1095957Y1170007D01*
G03X1096085Y1170570I-1174J563D01*
G03X1093481I-1302J0D01*
G03X1093629Y1169968I1302J1D01*
G01Y1169967D01*
X1093630Y1169966D01*
G02X1093652Y1169869I-178J-91D01*
G01X1093650Y1169816D01*
X1093591Y1169719D01*
X1093440Y1169470D01*
G02X1093298Y1169383I-166J111D01*
G01X1093286Y1169382D01*
X1092547D01*
G02X1092529Y1169383I2J200D01*
G01X1092528D01*
G02X1092385Y1169472I24J198D01*
G01X1092343Y1169541D01*
X1092199Y1169778D01*
G02X1092174Y1169869I175J97D01*
G01X1092173Y1169919D01*
X1092203Y1169978D01*
X1092217Y1170007D01*
G03X1092345Y1170570I-1174J563D01*
G03X1089741I-1302J0D01*
G03X1089889Y1169968I1302J1D01*
G01Y1169967D01*
X1089890Y1169966D01*
G02X1089912Y1169869I-178J-91D01*
G01X1089910Y1169816D01*
X1089851Y1169719D01*
X1089700Y1169470D01*
G02X1089558Y1169383I-166J111D01*
G01X1089546Y1169382D01*
X1088806D01*
G02X1088788Y1169383I2J200D01*
G01X1088787D01*
G02X1088644Y1169472I24J198D01*
G01X1088602Y1169541D01*
X1088458Y1169778D01*
G02X1088433Y1169869I175J97D01*
G01X1088432Y1169919D01*
X1088462Y1169978D01*
X1088476Y1170007D01*
G03X1088604Y1170570I-1174J563D01*
G03X1086000I-1302J0D01*
G03X1086148Y1169968I1302J1D01*
G01Y1169967D01*
X1086149Y1169966D01*
G02X1086171Y1169869I-178J-91D01*
G01X1086169Y1169816D01*
X1086110Y1169719D01*
X1085959Y1169470D01*
G02X1085817Y1169383I-166J111D01*
G01X1085805Y1169382D01*
X1081326D01*
G02X1081308Y1169383I2J200D01*
G01X1081307D01*
G02X1081164Y1169472I24J198D01*
G01X1081122Y1169541D01*
X1080978Y1169778D01*
G02X1080953Y1169869I175J97D01*
G01X1080952Y1169919D01*
X1080982Y1169978D01*
X1080996Y1170007D01*
G03X1081124Y1170570I-1174J563D01*
G03X1078520I-1302J0D01*
G03X1079065Y1169511I1301J0D01*
G01X1079066Y1169510D01*
G02X1079146Y1169382I-117J-162D01*
G02X1079147Y1169378I-193J-50D01*
G01X1079161Y1169213D01*
Y1169211D01*
X1079173Y1169060D01*
G02X1079115Y1168902I-199J-16D01*
G01X1066530Y1156317D01*
G02X1066372Y1156259I-142J141D01*
G01X1066221Y1156271D01*
X1066219D01*
X1066054Y1156285D01*
G02X1066050Y1156286I46J194D01*
G02X1065922Y1156366I34J197D01*
G01X1065921Y1156367D01*
G03X1064862Y1156912I-1059J-756D01*
G03X1063560Y1155610I0J-1302D01*
G03X1064105Y1154551I1301J0D01*
G01X1064106Y1154550D01*
G02X1064186Y1154422I-117J-162D01*
G02X1064187Y1154418I-193J-50D01*
G01X1064201Y1154253D01*
Y1154251D01*
X1064213Y1154100D01*
G02X1064155Y1153942I-199J-16D01*
G01X1062789Y1152576D01*
G02X1062631Y1152518I-142J141D01*
G01X1062327Y1152543D01*
G02X1062310Y1152545I15J199D01*
G02X1062243Y1152569I33J197D01*
G01X1062236Y1152573D01*
G02X1062192Y1152610I106J170D01*
G01X1062181Y1152626D01*
G03X1061121Y1153172I-1060J-756D01*
G03X1059819Y1151870I0J-1302D01*
G03X1060353Y1150819I1301J0D01*
G02X1060376Y1150799I-119J-161D01*
G01X1060411Y1150764D01*
G02X1060422Y1150747I-162J-117D01*
G01X1060433Y1150728D01*
X1060446Y1150687D01*
X1060473Y1150360D01*
G02X1060415Y1150202I-199J-16D01*
G01X1059049Y1148836D01*
G02X1058891Y1148778I-142J141D01*
G01X1058586Y1148803D01*
G02X1058504Y1148829I18J199D01*
G01X1058466Y1148850D01*
X1058440Y1148887D01*
G03X1057381Y1149431I-1059J-759D01*
G03X1056079Y1148129I0J-1302D01*
G03X1056623Y1147070I1303J0D01*
G01X1056660Y1147044D01*
X1056681Y1147006D01*
G02X1056707Y1146924I-173J-100D01*
G01X1056732Y1146619D01*
G02X1056674Y1146461I-199J-16D01*
G01X1049444Y1139231D01*
G03X1049385Y1139089I141J-142D01*
G01Y1131933D01*
G02X1049295Y1131775I-200J9D01*
G01X1049285Y1131770D01*
X1048981Y1131593D01*
G02X1048887Y1131570I-93J177D01*
G01X1048788Y1131596D01*
X1048766Y1131608D01*
G03X1048044Y1131793I-723J-1319D01*
G01X1048043D01*
G03Y1128789I0J-1502D01*
G01X1048044D01*
G03X1048766Y1128974I-1J1504D01*
G01X1048788Y1128986D01*
X1048887Y1129012D01*
G02X1048981Y1128989I1J-200D01*
G01X1049266Y1128823D01*
X1049286Y1128811D01*
G02X1049293Y1128807I-96J-175D01*
G01X1049294D01*
X1049297Y1128805D01*
G02X1049385Y1128647I-112J-166D01*
G01Y1119333D01*
G02X1049295Y1119175I-200J9D01*
G01X1049285Y1119170D01*
X1048981Y1118993D01*
G02X1048887Y1118970I-93J177D01*
G01X1048788Y1118996D01*
X1048766Y1119008D01*
G03X1048044Y1119193I-723J-1319D01*
G01X1048043D01*
G03Y1116189I0J-1502D01*
G01X1048044D01*
G03X1048766Y1116374I-1J1504D01*
G01X1048788Y1116386D01*
X1048887Y1116412D01*
G02X1048981Y1116389I1J-200D01*
G01X1049266Y1116223D01*
X1049286Y1116211D01*
G02X1049293Y1116207I-96J-175D01*
G01X1049294D01*
X1049297Y1116205D01*
G02X1049385Y1116047I-112J-166D01*
G01Y1106733D01*
G02X1049295Y1106575I-200J9D01*
G01X1049285Y1106570D01*
X1048981Y1106393D01*
G02X1048887Y1106370I-93J177D01*
G01X1048788Y1106396D01*
X1048766Y1106408D01*
G03X1048044Y1106593I-723J-1319D01*
G01X1048043D01*
G03Y1103589I0J-1502D01*
G01X1048044D01*
G03X1048766Y1103774I-1J1504D01*
G01X1048788Y1103786D01*
X1048887Y1103812D01*
G02X1048981Y1103789I1J-200D01*
G01X1049266Y1103623D01*
X1049286Y1103611D01*
G02X1049293Y1103607I-96J-175D01*
G01X1049294D01*
X1049297Y1103605D01*
G02X1049385Y1103447I-112J-166D01*
G01Y1102537D01*
G02X1049341Y1102412I-200J0D01*
G03X1049339Y1102410I140J-142D01*
G02X1049327Y1102396I-158J123D01*
G01X1048330Y1101399D01*
G02X1048263Y1101355I-141J142D01*
G01X1048229Y1101341D01*
X1040954D01*
G02X1040947Y1101342I25J198D01*
G02X1040814Y1101413I21J199D01*
G01X1040745Y1101496D01*
X1040617Y1101651D01*
G02X1040577Y1101728I153J128D01*
G01X1040566Y1101770D01*
X1040574Y1101815D01*
G03X1040600Y1102091I-1476J278D01*
G03X1037596I-1502J0D01*
G01Y1102088D01*
G03X1037676Y1101605I1502J1D01*
G01X1037687Y1101574D01*
Y1101541D01*
G02X1037487Y1101341I-200J0D01*
G01X1037345D01*
G02X1037145Y1101541I0J200D01*
G01Y1150701D01*
G02X1037149Y1150738I200J-3D01*
G01Y1150740D01*
G02X1037202Y1150841I196J-39D01*
G01X1037715Y1151354D01*
G02X1037718Y1151357I143J-140D01*
G01X1037723Y1151361D01*
G02X1037854Y1151412I133J-149D01*
G01X1037939D01*
G02X1038009Y1151399I-1J-200D01*
G01X1038105Y1151363D01*
X1038131Y1151341D01*
G03X1039097Y1150989I966J1151D01*
G01X1039098D01*
G03X1040600Y1152491I0J1502D01*
G03X1040200Y1153512I-1503J0D01*
G01X1040175Y1153539D01*
X1040120Y1153675D01*
G02Y1153678I200J1D01*
G01Y1153717D01*
X1040135Y1153752D01*
G02X1040178Y1153817I185J-76D01*
G01X1055956Y1169595D01*
G02X1055984Y1169618I141J-143D01*
G02X1056084Y1169651I111J-167D01*
G01X1056369Y1169658D01*
G02X1056442Y1169645I2J-200D01*
G01X1056475Y1169632D01*
X1056504Y1169606D01*
G03X1057379Y1169268I875J964D01*
G01X1061120D01*
G03Y1171872I0J1302D01*
G01X1058716D01*
G02X1058532Y1171995I1J200D01*
G02X1058575Y1172214I184J78D01*
G01X1059696Y1173335D01*
G02X1059724Y1173358I141J-143D01*
G02X1059824Y1173391I111J-167D01*
G01X1060094Y1173398D01*
X1060106D01*
G02X1060182Y1173385I5J-200D01*
G01X1060216Y1173372D01*
X1060245Y1173346D01*
G03X1061120Y1173008I875J964D01*
G03X1062422Y1174310I0J1302D01*
G03X1062084Y1175185I-1302J0D01*
G01X1062058Y1175214D01*
X1062045Y1175248D01*
G02X1062032Y1175318I187J71D01*
G01X1062034Y1175387D01*
X1062040Y1175612D01*
G02X1062071Y1175704I199J-16D01*
G01X1062083Y1175720D01*
G02X1062097Y1175736I157J-123D01*
G37*
G36*
G01X1103494Y1160972D02*
G02X1103484Y1160954I-179J88D01*
G03X1103482Y1160950I178J-91D01*
G02X1103480Y1160947I-167J109D01*
G01X1103476Y1160942D01*
G02X1103460Y1160924I-157J124D01*
G01X1103084Y1160548D01*
G02X1102974Y1160492I-141J142D01*
G01X1102973D01*
G02X1102963Y1160491I-25J198D01*
G01X1102862Y1160507D01*
G02X1102853Y1160511I77J184D01*
G01X1102852D01*
X1102833Y1160521D01*
G03X1102265Y1160652I-569J-1170D01*
G01X1102263D01*
G03X1101465Y1160379I0J-1303D01*
G01X1101455Y1160371D01*
X1101439Y1160359D01*
X1101347Y1160326D01*
G02X1101279Y1160314I-68J188D01*
G01X1099507D01*
G02X1099439Y1160326I0J200D01*
G01X1099347Y1160359D01*
X1099331Y1160371D01*
X1099321Y1160379D01*
G03X1097725I-798J-1029D01*
G01X1097715Y1160371D01*
X1097699Y1160359D01*
X1097607Y1160326D01*
G02X1097539Y1160314I-68J188D01*
G01X1095767D01*
G02X1095699Y1160326I0J200D01*
G01X1095607Y1160359D01*
X1095591Y1160371D01*
X1095581Y1160379D01*
G03X1094783Y1160652I-798J-1030D01*
G03X1093483Y1159419I0J-1302D01*
G01X1093481Y1159381D01*
X1093463Y1159342D01*
G02X1093425Y1159288I-180J86D01*
G01X1087365Y1153228D01*
G02X1087305Y1153187I-141J142D01*
G01X1087272Y1153172D01*
X1087260Y1153171D01*
X1087234Y1153170D01*
G03X1086002Y1151938I68J-1300D01*
G01X1086000Y1151900D01*
X1085982Y1151861D01*
G02X1085944Y1151807I-180J86D01*
G01X1083624Y1149487D01*
G02X1083564Y1149446I-141J142D01*
G01X1083531Y1149431D01*
X1083519Y1149430D01*
X1083493Y1149429D01*
G03X1082262Y1148198I69J-1300D01*
G01X1082260Y1148160D01*
X1082242Y1148121D01*
G02X1082204Y1148067I-180J86D01*
G01X1079884Y1145747D01*
G02X1079824Y1145706I-141J142D01*
G01X1079791Y1145691D01*
X1079779Y1145690D01*
X1079753Y1145689D01*
G03X1078522Y1144458I69J-1300D01*
G01X1078520Y1144420D01*
X1078502Y1144381D01*
G02X1078464Y1144327I-180J86D01*
G01X1076144Y1142007D01*
G02X1076084Y1141966I-141J142D01*
G01X1076051Y1141951D01*
X1076039Y1141950D01*
X1076013Y1141949D01*
G03X1074782Y1140718I69J-1300D01*
G01X1074780Y1140680D01*
X1074762Y1140641D01*
G02X1074724Y1140587I-180J86D01*
G01X1072404Y1138267D01*
G02X1072344Y1138226I-141J142D01*
G01X1072311Y1138211D01*
X1072299Y1138210D01*
X1072273Y1138209D01*
G03X1071042Y1136978I69J-1300D01*
G01X1071040Y1136940D01*
X1071022Y1136901D01*
G02X1070984Y1136847I-180J86D01*
G01X1064924Y1130787D01*
G02X1064864Y1130746I-141J142D01*
G01X1064831Y1130731D01*
X1064819Y1130730D01*
X1064793Y1130729D01*
G03X1063560Y1129429I69J-1300D01*
G03X1064487Y1128182I1302J0D01*
G01X1064519Y1128172D01*
X1064570Y1128137D01*
X1064589Y1128110D01*
G02X1064629Y1127991I-160J-120D01*
G01Y1127126D01*
G02X1064598Y1127021I-200J2D01*
G01X1064589Y1127008D01*
G02X1064541Y1126960I-163J115D01*
G01X1064520Y1126945D01*
X1064486Y1126935D01*
G03X1064487Y1124441I376J-1247D01*
G01X1064519Y1124431D01*
X1064570Y1124396D01*
X1064589Y1124369D01*
G02X1064629Y1124250I-160J-120D01*
G01Y1123386D01*
G02X1064598Y1123281I-200J2D01*
G01X1064589Y1123268D01*
G02X1064541Y1123220I-163J115D01*
G01X1064520Y1123205D01*
X1064486Y1123195D01*
G03X1064487Y1120701I376J-1247D01*
G01X1064519Y1120691D01*
X1064570Y1120656D01*
X1064589Y1120629D01*
G02X1064629Y1120510I-160J-120D01*
G01Y1119646D01*
G02X1064598Y1119541I-200J2D01*
G01X1064589Y1119528D01*
G02X1064541Y1119480I-163J115D01*
G01X1064520Y1119465D01*
X1064486Y1119455D01*
G03X1064487Y1116961I376J-1247D01*
G01X1064519Y1116951D01*
X1064570Y1116916D01*
X1064589Y1116889D01*
G02X1064629Y1116770I-160J-120D01*
G01Y1115906D01*
G02X1064598Y1115801I-200J2D01*
G01X1064589Y1115788D01*
G02X1064541Y1115740I-163J115D01*
G01X1064520Y1115725D01*
X1064486Y1115715D01*
G03X1064487Y1113221I376J-1247D01*
G01X1064519Y1113211D01*
X1064570Y1113176D01*
X1064589Y1113149D01*
G02X1064629Y1113030I-160J-120D01*
G01Y1112166D01*
G02X1064598Y1112061I-200J2D01*
G01X1064589Y1112048D01*
G02X1064541Y1112000I-163J115D01*
G01X1064520Y1111985D01*
X1064486Y1111975D01*
G03X1064487Y1109481I376J-1247D01*
G01X1064519Y1109471D01*
X1064570Y1109436D01*
X1064589Y1109409D01*
G02X1064629Y1109290I-160J-120D01*
G01Y1108426D01*
G02X1064598Y1108321I-200J2D01*
G01X1064589Y1108308D01*
G02X1064541Y1108260I-163J115D01*
G01X1064520Y1108245D01*
X1064486Y1108235D01*
G03X1064487Y1105741I376J-1247D01*
G01X1064519Y1105731D01*
X1064570Y1105696D01*
X1064589Y1105669D01*
G02X1064629Y1105550I-160J-120D01*
G01Y1104685D01*
G02X1064598Y1104580I-200J2D01*
G01X1064589Y1104567D01*
G02X1064541Y1104519I-163J115D01*
G01X1064520Y1104504D01*
X1064486Y1104494D01*
G03X1064487Y1102000I376J-1247D01*
G01X1064519Y1101990D01*
X1064570Y1101955D01*
X1064589Y1101928D01*
G02X1064629Y1101809I-160J-120D01*
G01Y1100945D01*
G02X1064598Y1100840I-200J2D01*
G01X1064589Y1100827D01*
G02X1064541Y1100779I-163J115D01*
G01X1064520Y1100764D01*
X1064486Y1100754D01*
G03X1064487Y1098260I376J-1247D01*
G01X1064519Y1098250D01*
X1064570Y1098215D01*
X1064589Y1098188D01*
G02X1064629Y1098069I-160J-120D01*
G01Y1097205D01*
G02X1064598Y1097100I-200J2D01*
G01X1064589Y1097087D01*
G02X1064541Y1097039I-163J115D01*
G01X1064520Y1097024D01*
X1064486Y1097014D01*
G03X1064487Y1094520I376J-1247D01*
G01X1064519Y1094510D01*
X1064570Y1094475D01*
X1064589Y1094448D01*
G02X1064629Y1094329I-160J-120D01*
G01Y1093465D01*
G02X1064598Y1093360I-200J2D01*
G01X1064589Y1093347D01*
G02X1064541Y1093299I-163J115D01*
G01X1064520Y1093284D01*
X1064486Y1093274D01*
G03X1064487Y1090780I376J-1247D01*
G01X1064519Y1090770D01*
X1064570Y1090735D01*
X1064589Y1090708D01*
G02X1064629Y1090589I-160J-120D01*
G01Y1089725D01*
G02X1064598Y1089620I-200J2D01*
G01X1064589Y1089607D01*
G02X1064541Y1089559I-163J115D01*
G01X1064520Y1089544D01*
X1064486Y1089534D01*
G03X1064487Y1087040I376J-1247D01*
G01X1064519Y1087030D01*
X1064570Y1086995D01*
X1064589Y1086968D01*
G02X1064629Y1086849I-160J-120D01*
G01Y1085985D01*
G02X1064598Y1085880I-200J2D01*
G01X1064589Y1085867D01*
G02X1064541Y1085819I-163J115D01*
G01X1064520Y1085804D01*
X1064486Y1085794D01*
G03X1064487Y1083300I376J-1247D01*
G01X1064519Y1083290D01*
X1064570Y1083255D01*
X1064589Y1083228D01*
G02X1064629Y1083109I-160J-120D01*
G01Y1082245D01*
G02X1064598Y1082140I-200J2D01*
G01X1064589Y1082127D01*
G02X1064541Y1082079I-163J115D01*
G01X1064520Y1082064D01*
X1064486Y1082054D01*
G03X1064487Y1079560I376J-1247D01*
G01X1064519Y1079550D01*
X1064570Y1079515D01*
X1064589Y1079488D01*
G02X1064629Y1079369I-160J-120D01*
G01Y1078504D01*
G02X1064598Y1078399I-200J2D01*
G01X1064589Y1078386D01*
G02X1064541Y1078338I-163J115D01*
G01X1064520Y1078323D01*
X1064486Y1078313D01*
G03X1064487Y1075819I375J-1247D01*
G01X1064519Y1075809D01*
X1064570Y1075774D01*
X1064589Y1075747D01*
G02X1064629Y1075628I-160J-120D01*
G01Y1074764D01*
G02X1064598Y1074659I-200J2D01*
G01X1064589Y1074646D01*
G02X1064541Y1074598I-163J115D01*
G01X1064520Y1074583D01*
X1064486Y1074573D01*
G03X1064487Y1072079I376J-1247D01*
G01X1064519Y1072069D01*
X1064570Y1072034D01*
X1064589Y1072007D01*
G02X1064629Y1071888I-160J-120D01*
G01Y1047251D01*
Y1038620D01*
Y1038493D01*
G02X1064628Y1038477I-200J4D01*
G02X1064505Y1038308I-199J16D01*
G03Y1035532I574J-1388D01*
G02X1064628Y1035363I-76J-185D01*
G02X1064629Y1035347I-199J-20D01*
G01Y1026428D01*
G02X1064607Y1026337I-200J0D01*
G02X1064571Y1026287I-178J90D01*
G01X1061348Y1023064D01*
G02X1061298Y1023028I-140J142D01*
G02X1061207Y1023006I-91J178D01*
G01X1051896D01*
G02X1051825Y1023019I0J200D01*
G02X1051773Y1023048I70J187D01*
G03X1049715I-1029J-1094D01*
G02X1049663Y1023019I-122J158D01*
G02X1049592Y1023006I-71J187D01*
G01X1048912D01*
G02X1048821Y1023028I0J200D01*
G02X1048771Y1023064I90J178D01*
G01X1047997Y1023838D01*
G02X1047961Y1023888I142J140D01*
G02X1047939Y1023979I178J91D01*
G01Y1034159D01*
X1047945Y1034183D01*
G03X1047987Y1034536I-1460J353D01*
G03Y1034538I-1502J1D01*
G03Y1034540I-1502J1D01*
G03X1047945Y1034893I-1502J0D01*
G01X1047939Y1034917D01*
Y1042062D01*
G02X1047961Y1042153I200J0D01*
G02X1047997Y1042203I178J-90D01*
G01X1050550Y1044756D01*
G03X1050609Y1044898I-141J142D01*
G01Y1076332D01*
G03X1050550Y1076474I-200J0D01*
G01X1050444Y1076580D01*
G02X1050408Y1076630I142J140D01*
G02X1050386Y1076721I178J91D01*
G01Y1102039D01*
X1050387D01*
Y1138200D01*
G02X1050445Y1138341I200J0D01*
G01X1055744Y1143640D01*
G02X1055894Y1143698I141J-142D01*
G01X1055987Y1143692D01*
X1056208Y1143677D01*
G02X1056280Y1143656I-19J-199D01*
G01X1056317Y1143636D01*
X1056344Y1143601D01*
G02X1056346Y1143599I-139J-141D01*
G03X1057381Y1143087I1035J790D01*
G03X1058683Y1144389I0J1302D01*
G03X1058170Y1145425I-1303J0D01*
G01X1058150Y1145440D01*
X1058123Y1145472D01*
X1058114Y1145490D01*
G02X1058093Y1145562I178J91D01*
G01X1058078Y1145783D01*
X1058072Y1145876D01*
G02X1058130Y1146026I200J9D01*
G01X1059484Y1147380D01*
G02X1059634Y1147438I141J-142D01*
G01X1059727Y1147432D01*
X1059948Y1147417D01*
G02X1060020Y1147396I-19J-199D01*
G01X1060057Y1147376D01*
X1060084Y1147341D01*
G02X1060086Y1147339I-139J-141D01*
G03X1061121Y1146827I1035J790D01*
G03X1062423Y1148129I0J1302D01*
G03X1061910Y1149165I-1303J0D01*
G01X1061890Y1149180D01*
X1061863Y1149212D01*
X1061854Y1149230D01*
G02X1061833Y1149302I178J91D01*
G01X1061818Y1149523D01*
X1061812Y1149616D01*
G02X1061870Y1149766I200J9D01*
G01X1063225Y1151121D01*
G02X1063375Y1151179I141J-142D01*
G01X1063468Y1151173D01*
X1063689Y1151158D01*
G02X1063761Y1151137I-19J-199D01*
G01X1063798Y1151117D01*
X1063825Y1151082D01*
G02X1063827Y1151080I-139J-141D01*
G03X1064862Y1150568I1035J790D01*
G03X1066164Y1151870I0J1302D01*
G03X1065651Y1152906I-1303J0D01*
G01X1065631Y1152921D01*
X1065604Y1152953D01*
X1065595Y1152971D01*
G02X1065574Y1153043I178J91D01*
G01X1065559Y1153264D01*
X1065553Y1153357D01*
G02X1065611Y1153507I200J9D01*
G01X1066965Y1154861D01*
G02X1067115Y1154919I141J-142D01*
G01X1067208Y1154913D01*
X1067429Y1154898D01*
G02X1067501Y1154877I-19J-199D01*
G01X1067538Y1154857D01*
X1067565Y1154822D01*
G02X1067567Y1154820I-139J-141D01*
G03X1068602Y1154308I1035J790D01*
G03X1069904Y1155610I0J1302D01*
G03X1069391Y1156646I-1303J0D01*
G01X1069371Y1156661D01*
X1069344Y1156693D01*
X1069335Y1156711D01*
G02X1069314Y1156783I178J91D01*
G01X1069299Y1157004D01*
X1069293Y1157097D01*
G02X1069351Y1157247I200J9D01*
G01X1078185Y1166081D01*
G02X1078335Y1166139I141J-142D01*
G01X1078428Y1166133D01*
X1078649Y1166118D01*
G02X1078721Y1166097I-19J-199D01*
G01X1078758Y1166077D01*
X1078785Y1166042D01*
G02X1078787Y1166040I-139J-141D01*
G03X1079822Y1165528I1035J790D01*
G03X1081124Y1166830I0J1302D01*
G03X1081097Y1167093I-1302J-1D01*
G01X1081088Y1167138D01*
X1081098Y1167180D01*
G02X1081133Y1167253I194J-48D01*
G01X1081236Y1167380D01*
X1081334Y1167500D01*
G02X1081489Y1167574I155J-126D01*
G01X1085635D01*
G02X1085790Y1167500I0J-200D01*
G01X1085888Y1167380D01*
X1085991Y1167253D01*
G02X1086026Y1167180I-159J-121D01*
G01X1086036Y1167138D01*
X1086027Y1167093D01*
G03X1086000Y1166830I1275J-264D01*
G03X1088604I1302J0D01*
G03X1088577Y1167093I-1302J-1D01*
G01X1088568Y1167138D01*
X1088578Y1167180D01*
G02X1088613Y1167253I194J-48D01*
G01X1088716Y1167380D01*
X1088814Y1167500D01*
G02X1088969Y1167574I155J-126D01*
G01X1089376D01*
G02X1089531Y1167500I0J-200D01*
G01X1089629Y1167380D01*
X1089732Y1167253D01*
G02X1089767Y1167180I-159J-121D01*
G01X1089777Y1167138D01*
X1089768Y1167093D01*
G03X1089741Y1166830I1275J-264D01*
G03X1092345I1302J0D01*
G03X1092314Y1167115I-1302J3D01*
G01X1092303Y1167163D01*
X1092313Y1167204D01*
G02X1092348Y1167278I195J-47D01*
G02X1092351Y1167281I142J-139D01*
G01X1092548Y1167527D01*
G02X1092704Y1167602I156J-125D01*
G01X1093122D01*
G02X1093278Y1167527I0J-200D01*
G01X1093475Y1167281D01*
G02X1093478Y1167278I-139J-142D01*
G02X1093513Y1167204I-160J-121D01*
G01X1093523Y1167163D01*
X1093512Y1167115D01*
G03X1093481Y1166830I1271J-282D01*
G03X1096085I1302J0D01*
G03X1096054Y1167115I-1302J3D01*
G01X1096043Y1167163D01*
X1096053Y1167204D01*
G02X1096088Y1167278I195J-47D01*
G02X1096091Y1167281I142J-139D01*
G01X1096288Y1167527D01*
G02X1096444Y1167602I156J-125D01*
G01X1096862D01*
G02X1097018Y1167527I0J-200D01*
G01X1097215Y1167281D01*
G02X1097218Y1167278I-139J-142D01*
G02X1097253Y1167204I-160J-121D01*
G01X1097263Y1167163D01*
X1097252Y1167115D01*
G03X1097221Y1166830I1271J-282D01*
G03X1099825I1302J0D01*
G03X1099794Y1167115I-1302J3D01*
G01X1099783Y1167163D01*
X1099793Y1167204D01*
G02X1099828Y1167278I195J-47D01*
G02X1099831Y1167281I142J-139D01*
G01X1100028Y1167527D01*
G02X1100184Y1167602I156J-125D01*
G01X1102433D01*
G02X1102524Y1167580I0J-200D01*
G02X1102574Y1167544I-90J-178D01*
G01X1103236Y1166882D01*
X1103457Y1166660D01*
X1103460Y1166656D01*
X1103438Y1166673D01*
X1103487Y1166624D01*
G02X1103518Y1166517I-169J-107D01*
G01Y1161061D01*
G02X1103496Y1160974I-200J4D01*
G03X1103494Y1160972I134J-136D01*
G37*
G36*
G01X1065692Y1061742D02*
X1065688Y1061746D01*
Y1071889D01*
G03X1065660Y1072147I-1258J-6D01*
G01X1065656Y1072187D01*
G02X1065675Y1072273I200J1D01*
G01X1065701Y1072330D01*
X1065731Y1072356D01*
G03Y1074296I-869J970D01*
G01X1065701Y1074322D01*
X1065675Y1074379D01*
G02X1065656Y1074465I181J85D01*
G01X1065660Y1074505D01*
G03X1065688Y1074763I-1230J264D01*
G01Y1075629D01*
G03X1065659Y1075897I-1259J-1D01*
G01X1065654Y1075940D01*
G02X1065686Y1076048I200J0D01*
G01X1065701Y1076072D01*
G03X1066163Y1077066I-840J995D01*
G03X1065722Y1078042I-1302J-1D01*
G01X1065685Y1078085D01*
X1065639Y1078157D01*
G03X1065688Y1078503I-1210J348D01*
G01Y1079370D01*
G03X1065660Y1079628I-1258J-6D01*
G01X1065656Y1079668D01*
G02X1065675Y1079754I200J1D01*
G01X1065701Y1079811D01*
X1065731Y1079837D01*
G03Y1081777I-869J970D01*
G01X1065701Y1081803D01*
X1065675Y1081860D01*
G02X1065656Y1081946I181J85D01*
G01X1065660Y1081986D01*
G03X1065688Y1082244I-1230J264D01*
G01Y1083110D01*
G03X1065660Y1083368I-1258J-6D01*
G01X1065656Y1083408D01*
G02X1065675Y1083494I200J1D01*
G01X1065701Y1083551D01*
X1065731Y1083577D01*
G03Y1085517I-869J970D01*
G01X1065701Y1085543D01*
X1065675Y1085600D01*
G02X1065656Y1085686I181J85D01*
G01X1065660Y1085726D01*
G03X1065688Y1085984I-1230J264D01*
G01Y1086850D01*
G03X1065660Y1087108I-1258J-6D01*
G01X1065656Y1087148D01*
G02X1065675Y1087234I200J1D01*
G01X1065701Y1087291D01*
X1065731Y1087317D01*
G03Y1089257I-869J970D01*
G01X1065701Y1089283D01*
X1065675Y1089340D01*
G02X1065656Y1089426I181J85D01*
G01X1065660Y1089466D01*
G03X1065688Y1089724I-1230J264D01*
G01Y1090590D01*
G03X1065660Y1090848I-1258J-6D01*
G01X1065656Y1090888D01*
G02X1065675Y1090974I200J1D01*
G01X1065701Y1091031D01*
X1065731Y1091057D01*
G03Y1092997I-869J970D01*
G01X1065701Y1093023D01*
X1065675Y1093080D01*
G02X1065656Y1093166I181J85D01*
G01X1065660Y1093206D01*
G03X1065688Y1093464I-1230J264D01*
G01Y1094330D01*
G03X1065660Y1094588I-1258J-6D01*
G01X1065656Y1094628D01*
G02X1065675Y1094714I200J1D01*
G01X1065701Y1094771D01*
X1065731Y1094797D01*
G03Y1096737I-869J970D01*
G01X1065701Y1096763D01*
X1065675Y1096820D01*
G02X1065656Y1096906I181J85D01*
G01X1065660Y1096946D01*
G03X1065688Y1097204I-1230J264D01*
G01Y1098070D01*
G03X1065660Y1098328I-1258J-6D01*
G01X1065656Y1098368D01*
G02X1065675Y1098454I200J1D01*
G01X1065701Y1098511D01*
X1065731Y1098537D01*
G03Y1100477I-869J970D01*
G01X1065701Y1100503D01*
X1065675Y1100560D01*
G02X1065656Y1100646I181J85D01*
G01X1065660Y1100686D01*
G03X1065688Y1100944I-1230J264D01*
G01Y1101810D01*
G03X1065660Y1102068I-1258J-6D01*
G01X1065656Y1102108D01*
G02X1065675Y1102194I200J1D01*
G01X1065701Y1102251D01*
X1065731Y1102277D01*
G03Y1104217I-869J970D01*
G01X1065701Y1104243D01*
X1065675Y1104300D01*
G02X1065656Y1104386I181J85D01*
G01X1065660Y1104426D01*
G03X1065688Y1104684I-1230J264D01*
G01Y1105551D01*
G03X1065660Y1105809I-1258J-6D01*
G01X1065656Y1105849D01*
G02X1065675Y1105935I200J1D01*
G01X1065701Y1105992D01*
X1065731Y1106018D01*
G03Y1107958I-869J970D01*
G01X1065701Y1107984D01*
X1065675Y1108041D01*
G02X1065656Y1108127I181J85D01*
G01X1065660Y1108167D01*
G03X1065688Y1108425I-1230J264D01*
G01Y1109291D01*
G03X1065660Y1109549I-1258J-6D01*
G01X1065656Y1109589D01*
G02X1065675Y1109675I200J1D01*
G01X1065701Y1109732D01*
X1065731Y1109758D01*
G03Y1111698I-869J970D01*
G01X1065701Y1111724D01*
X1065675Y1111781D01*
G02X1065656Y1111867I181J85D01*
G01X1065660Y1111907D01*
G03X1065688Y1112165I-1230J264D01*
G01Y1113031D01*
G03X1065660Y1113289I-1258J-6D01*
G01X1065656Y1113329D01*
G02X1065675Y1113415I200J1D01*
G01X1065701Y1113472D01*
X1065731Y1113498D01*
G03Y1115438I-869J970D01*
G01X1065701Y1115464D01*
X1065675Y1115521D01*
G02X1065656Y1115607I181J85D01*
G01X1065660Y1115647D01*
G03X1065688Y1115905I-1230J264D01*
G01Y1116771D01*
G03X1065660Y1117029I-1258J-6D01*
G01X1065656Y1117069D01*
G02X1065675Y1117155I200J1D01*
G01X1065701Y1117212D01*
X1065731Y1117238D01*
G03Y1119178I-869J970D01*
G01X1065701Y1119204D01*
X1065675Y1119261D01*
G02X1065656Y1119347I181J85D01*
G01X1065660Y1119387D01*
G03X1065688Y1119645I-1230J264D01*
G01Y1120511D01*
G03X1065660Y1120769I-1258J-6D01*
G01X1065656Y1120809D01*
G02X1065675Y1120895I200J1D01*
G01X1065701Y1120952D01*
X1065731Y1120978D01*
G03Y1122918I-869J970D01*
G01X1065701Y1122944D01*
X1065675Y1123001D01*
G02X1065656Y1123087I181J85D01*
G01X1065660Y1123127D01*
G03X1065688Y1123385I-1230J264D01*
G01Y1124251D01*
G03X1065660Y1124509I-1258J-6D01*
G01X1065656Y1124549D01*
G02X1065675Y1124635I200J1D01*
G01X1065701Y1124692D01*
X1065731Y1124718D01*
G03Y1126658I-869J970D01*
G01X1065701Y1126684D01*
X1065675Y1126741D01*
G02X1065656Y1126827I181J85D01*
G01X1065660Y1126867D01*
G03X1065688Y1127125I-1230J264D01*
G01Y1127992D01*
G03X1065660Y1128250I-1258J-6D01*
G01X1065656Y1128290D01*
G02X1065675Y1128376I200J1D01*
G01X1065701Y1128433D01*
X1065731Y1128459D01*
G03X1066164Y1129429I-870J970D01*
G03X1066068Y1129919I-1302J-1D01*
G01X1066053Y1129955D01*
Y1129956D01*
X1066044Y1129977D01*
X1066035Y1130023D01*
X1066038Y1130063D01*
X1066042Y1130083D01*
G02X1066095Y1130178I195J-46D01*
G01X1071593Y1135676D01*
G02X1071698Y1135731I141J-142D01*
G01X1071707Y1135733D01*
X1071773Y1135737D01*
X1071790Y1135730D01*
G03X1072340Y1135607I552J1179D01*
G01X1072342D01*
G03X1073644Y1136909I0J1302D01*
G03X1073548Y1137399I-1302J-1D01*
G01X1073533Y1137435D01*
Y1137436D01*
X1073524Y1137457D01*
X1073515Y1137503D01*
X1073518Y1137543D01*
X1073522Y1137563D01*
G02X1073575Y1137658I195J-46D01*
G01X1075333Y1139416D01*
G02X1075438Y1139471I141J-142D01*
G01X1075447Y1139473D01*
X1075513Y1139477D01*
X1075530Y1139470D01*
G03X1076080Y1139347I552J1179D01*
G01X1076082D01*
G03X1077384Y1140649I0J1302D01*
G03X1077288Y1141139I-1302J-1D01*
G01X1077273Y1141175D01*
Y1141176D01*
X1077264Y1141197D01*
X1077255Y1141243D01*
X1077258Y1141283D01*
X1077262Y1141303D01*
G02X1077315Y1141398I195J-46D01*
G01X1079073Y1143156D01*
G02X1079178Y1143211I141J-142D01*
G01X1079187Y1143213D01*
X1079253Y1143217D01*
X1079270Y1143210D01*
G03X1079820Y1143087I552J1179D01*
G01X1079822D01*
G03X1081124Y1144389I0J1302D01*
G03X1081028Y1144879I-1302J-1D01*
G01X1081013Y1144915D01*
Y1144916D01*
X1081004Y1144937D01*
X1080995Y1144983D01*
X1080998Y1145023D01*
X1081002Y1145043D01*
G02X1081055Y1145138I195J-46D01*
G01X1082813Y1146896D01*
G02X1082918Y1146951I141J-142D01*
G01X1082927Y1146953D01*
X1082993Y1146957D01*
X1083010Y1146950D01*
G03X1083560Y1146827I552J1179D01*
G01X1083562D01*
G03X1084864Y1148129I0J1302D01*
G03X1084768Y1148619I-1302J-1D01*
G01X1084753Y1148655D01*
Y1148656D01*
X1084744Y1148677D01*
X1084735Y1148723D01*
X1084738Y1148763D01*
X1084742Y1148783D01*
G02X1084795Y1148878I195J-46D01*
G01X1086555Y1150638D01*
G02X1086603Y1150673I140J-142D01*
G02X1086659Y1150693I95J-176D01*
G01X1086689Y1150698D01*
X1086746Y1150692D01*
X1086776Y1150679D01*
G03X1087302Y1150568I526J1191D01*
G03X1088604Y1151870I0J1302D01*
G03X1088493Y1152396I-1302J0D01*
G01X1088480Y1152426D01*
X1088474Y1152483D01*
X1088479Y1152513D01*
G02X1088499Y1152569I196J-39D01*
G02X1088534Y1152617I177J-92D01*
G01X1092721Y1156804D01*
G03X1092780Y1156946I-141J142D01*
G01Y1157063D01*
G02X1092784Y1157101I200J-2D01*
G02X1092837Y1157203I196J-37D01*
G01X1092885Y1157251D01*
G02X1093027Y1157310I142J-141D01*
G01X1093685D01*
G02X1093870Y1157184I-1J-200D01*
G01X1093985Y1156869D01*
X1094003Y1156819D01*
G02X1094007Y1156705I-190J-64D01*
G01X1093999Y1156677D01*
X1093967Y1156626D01*
X1093942Y1156605D01*
G03X1093481Y1155611I842J-994D01*
G01Y1155610D01*
G03X1096085I1302J0D01*
G01Y1155611D01*
G03X1095645Y1156587I-1303J0D01*
G01X1095623Y1156606D01*
X1095559Y1156707D01*
X1095551Y1156735D01*
X1095552Y1156765D01*
G02X1095565Y1156825I200J-12D01*
G01X1095581Y1156869D01*
X1095696Y1157184D01*
G02X1095881Y1157310I186J-74D01*
G01X1097425D01*
G02X1097610Y1157184I-1J-200D01*
G01X1097725Y1156869D01*
X1097743Y1156819D01*
G02X1097747Y1156705I-190J-64D01*
G01X1097739Y1156677D01*
X1097707Y1156626D01*
X1097682Y1156605D01*
G03X1097221Y1155611I842J-994D01*
G01Y1155610D01*
G03X1099825I1302J0D01*
G01Y1155611D01*
G03X1099385Y1156587I-1303J0D01*
G01X1099363Y1156606D01*
X1099299Y1156707D01*
X1099291Y1156735D01*
X1099292Y1156765D01*
G02X1099305Y1156825I200J-12D01*
G01X1099321Y1156869D01*
X1099436Y1157184D01*
G02X1099621Y1157310I186J-74D01*
G01X1102043D01*
G02X1102080Y1157306I-3J-200D01*
G01X1102082D01*
G02X1102183Y1157253I-39J-196D01*
G01X1102591Y1156845D01*
G02X1102614Y1156818I-140J-143D01*
G03X1102751Y1156653I1007J697D01*
G01X1103025Y1156378D01*
X1103150Y1156253D01*
G02X1103158Y1156242I-139J-109D01*
G02X1103163Y1156239I-88J-153D01*
G01X1103182Y1156219D01*
G02X1103216Y1156116I-143J-104D01*
G01Y1153470D01*
G02X1103190Y1153379I-177J1D01*
G01X1103174Y1153358D01*
X1103173Y1153356D01*
X1103152Y1153335D01*
G02X1103147Y1153331I-113J136D01*
G01X1103134Y1153322D01*
X1103081Y1153285D01*
X1103068Y1153275D01*
X1103007Y1153233D01*
G03X1103003Y1153231I87J-180D01*
G01X1102967Y1153205D01*
X1102903Y1153159D01*
G03X1102817Y1153089I729J-983D01*
G02X1102797Y1153085I-49J194D01*
G01X1102749Y1153079D01*
X1102720Y1153089D01*
G03X1102265Y1153172I-457J-1218D01*
G01X1102263D01*
G03Y1150568I0J-1302D01*
G01X1102265D01*
G03X1102720Y1150651I-2J1301D01*
G01X1102749Y1150661D01*
X1102797Y1150655D01*
X1102799D01*
X1102805Y1150649D01*
X1102948Y1150548D01*
X1102952Y1150546D01*
X1103148Y1150410D01*
X1103162Y1150396D01*
G02X1103164Y1150394I-124J-126D01*
G01X1103176Y1150381D01*
G02X1103216Y1150282I-137J-113D01*
G01Y1149729D01*
G02X1103190Y1149638I-177J1D01*
G01X1103176Y1149619D01*
X1103149Y1149592D01*
G02X1103147Y1149590I-126J124D01*
G01X1103134Y1149581D01*
X1103081Y1149544D01*
X1103068Y1149534D01*
X1103007Y1149492D01*
G03X1103003Y1149490I87J-180D01*
G01X1102967Y1149464D01*
X1102903Y1149418D01*
G03X1102817Y1149348I729J-983D01*
G02X1102797Y1149344I-49J194D01*
G01X1102749Y1149338D01*
X1102720Y1149348D01*
G03X1102265Y1149431I-457J-1218D01*
G01X1102263D01*
G03Y1146827I0J-1302D01*
G01X1102265D01*
G03X1102720Y1146910I-2J1301D01*
G01X1102749Y1146920D01*
X1102797Y1146914D01*
X1102799D01*
X1102805Y1146908D01*
X1102948Y1146807D01*
X1102952Y1146805D01*
X1103148Y1146669D01*
X1103162Y1146655D01*
G02X1103164Y1146653I-124J-126D01*
G01X1103176Y1146640D01*
G02X1103216Y1146541I-137J-113D01*
G01Y1145989D01*
G02X1103190Y1145898I-177J1D01*
G01X1103176Y1145879D01*
X1103149Y1145852D01*
G02X1103147Y1145850I-126J124D01*
G01X1103134Y1145841D01*
X1103081Y1145804D01*
X1103068Y1145794D01*
X1103007Y1145752D01*
G03X1103003Y1145750I87J-180D01*
G01X1102967Y1145724D01*
X1102903Y1145678D01*
G03X1102817Y1145608I729J-983D01*
G02X1102797Y1145604I-49J194D01*
G01X1102749Y1145598D01*
X1102720Y1145608D01*
G03X1102265Y1145691I-457J-1218D01*
G01X1102263D01*
G03Y1143087I0J-1302D01*
G01X1102265D01*
G03X1102720Y1143170I-2J1301D01*
G01X1102749Y1143180D01*
X1102797Y1143174D01*
X1102799D01*
X1102805Y1143168D01*
X1102948Y1143067D01*
X1102952Y1143065D01*
X1103148Y1142929D01*
X1103162Y1142915D01*
G02X1103164Y1142913I-124J-126D01*
G01X1103176Y1142900D01*
G02X1103216Y1142801I-137J-113D01*
G01Y1142466D01*
G02X1103213Y1142391I-174J-31D01*
G02X1103211Y1142384I-171J45D01*
G02X1103210Y1142382I-155J76D01*
G02X1103207Y1142369I-174J33D01*
G01X1103206Y1142368D01*
G02X1103204Y1142363I-165J63D01*
G03X1103202Y1142356I191J-58D01*
G02X1103201Y1142354I-157J77D01*
G02X1103199Y1142351I-148J96D01*
G02X1103193Y1142339I-161J73D01*
G01X1103187Y1142329D01*
G02X1103163Y1142299I-149J95D01*
G01X1102759Y1141896D01*
G02X1102757Y1141895I-89J176D01*
G01X1102721Y1141886D01*
X1102667Y1141887D01*
X1102641Y1141895D01*
G03X1102264Y1141951I-378J-1246D01*
G01X1102263D01*
G03X1100961Y1140649I0J-1302D01*
G01Y1140648D01*
G03X1101017Y1140271I1302J1D01*
G01X1101025Y1140245D01*
X1101026Y1140191D01*
X1101018Y1140161D01*
G02X1100967Y1140072I-193J52D01*
G01X1099100Y1138205D01*
G02X1099011Y1138154I-141J142D01*
G01X1098981Y1138146D01*
X1098927Y1138147D01*
X1098901Y1138155D01*
G03X1098524Y1138211I-378J-1246D01*
G01X1098523D01*
G03X1097221Y1136909I0J-1302D01*
G01Y1136908D01*
G03X1097277Y1136531I1302J1D01*
G01X1097285Y1136505D01*
X1097286Y1136451D01*
X1097278Y1136421D01*
G02X1097227Y1136332I-193J52D01*
G01X1095360Y1134465D01*
G02X1095271Y1134414I-141J142D01*
G01X1095241Y1134406D01*
X1095187Y1134407D01*
X1095161Y1134415D01*
G03X1094784Y1134471I-378J-1246D01*
G01X1094783D01*
G03X1093481Y1133169I0J-1302D01*
G01Y1133168D01*
G03X1093537Y1132791I1302J1D01*
G01X1093545Y1132765D01*
X1093546Y1132711D01*
X1093538Y1132681D01*
G02X1093487Y1132592I-193J52D01*
G01X1091620Y1130725D01*
G02X1091531Y1130674I-141J142D01*
G01X1091501Y1130666D01*
X1091447Y1130667D01*
X1091421Y1130675D01*
G03X1091044Y1130731I-378J-1246D01*
G01X1091043D01*
G03X1089741Y1129429I0J-1302D01*
G01Y1129428D01*
G03X1089797Y1129051I1302J1D01*
G01X1089805Y1129025D01*
X1089806Y1128971D01*
X1089798Y1128941D01*
G02X1089747Y1128852I-193J52D01*
G01X1084139Y1123244D01*
G02X1084050Y1123193I-141J142D01*
G01X1084020Y1123185D01*
X1083966Y1123186D01*
X1083940Y1123194D01*
G03X1083563Y1123250I-378J-1246D01*
G01X1083562D01*
G03X1082260Y1121948I0J-1302D01*
G01Y1121947D01*
G03X1082316Y1121570I1302J1D01*
G01X1082324Y1121544D01*
X1082325Y1121490D01*
X1082317Y1121460D01*
G02X1082266Y1121371I-193J52D01*
G01X1080399Y1119504D01*
G02X1080310Y1119453I-141J142D01*
G01X1080280Y1119445D01*
X1080226Y1119446D01*
X1080200Y1119454D01*
G03X1079823Y1119510I-378J-1246D01*
G01X1079822D01*
G03X1078520Y1118208I0J-1302D01*
G03X1079015Y1117186I1303J0D01*
G01X1079042Y1117164D01*
X1079100Y1117048D01*
G02X1079121Y1116959I-179J-89D01*
G01Y1115717D01*
G02X1079100Y1115628I-200J0D01*
G01X1079042Y1115512D01*
X1079015Y1115489D01*
G03Y1113447I807J-1021D01*
G01X1079042Y1113424D01*
X1079100Y1113308D01*
G02X1079121Y1113219I-179J-89D01*
G01Y1111977D01*
G02X1079100Y1111888I-200J0D01*
G01X1079042Y1111772D01*
X1079015Y1111749D01*
G03Y1109707I807J-1021D01*
G01X1079042Y1109684D01*
X1079100Y1109568D01*
G02X1079121Y1109479I-179J-89D01*
G01Y1108237D01*
G02X1079100Y1108148I-200J0D01*
G01X1079042Y1108032D01*
X1079015Y1108009D01*
G03Y1105967I807J-1021D01*
G01X1079042Y1105944D01*
X1079100Y1105828D01*
G02X1079121Y1105739I-179J-89D01*
G01Y1104496D01*
G02X1079100Y1104407I-200J0D01*
G01X1079042Y1104291D01*
X1079015Y1104268D01*
G03Y1102226I807J-1021D01*
G01X1079042Y1102203D01*
X1079100Y1102087D01*
G02X1079121Y1101998I-179J-89D01*
G01Y1100756D01*
G02X1079100Y1100667I-200J0D01*
G01X1079042Y1100551D01*
X1079015Y1100528D01*
G03Y1098486I807J-1021D01*
G01X1079042Y1098463D01*
X1079100Y1098347D01*
G02X1079121Y1098258I-179J-89D01*
G01Y1097016D01*
G02X1079100Y1096927I-200J0D01*
G01X1079042Y1096811D01*
X1079015Y1096788D01*
G03Y1094746I807J-1021D01*
G01X1079042Y1094723D01*
X1079100Y1094607D01*
G02X1079121Y1094518I-179J-89D01*
G01Y1093276D01*
G02X1079100Y1093187I-200J0D01*
G01X1079042Y1093071D01*
X1079015Y1093048D01*
G03Y1091006I807J-1021D01*
G01X1079042Y1090983D01*
X1079100Y1090867D01*
G02X1079121Y1090778I-179J-89D01*
G01Y1089536D01*
G02X1079100Y1089447I-200J0D01*
G01X1079042Y1089331D01*
X1079015Y1089308D01*
G03Y1087266I807J-1021D01*
G01X1079042Y1087243D01*
X1079100Y1087127D01*
G02X1079121Y1087038I-179J-89D01*
G01Y1085796D01*
G02X1079100Y1085707I-200J0D01*
G01X1079042Y1085591D01*
X1079015Y1085568D01*
G03Y1083526I807J-1021D01*
G01X1079042Y1083503D01*
X1079100Y1083387D01*
G02X1079121Y1083298I-179J-89D01*
G01Y1082056D01*
G02X1079100Y1081967I-200J0D01*
G01X1079042Y1081851D01*
X1079015Y1081828D01*
G03Y1079786I807J-1021D01*
G01X1079042Y1079763D01*
X1079100Y1079647D01*
G02X1079121Y1079558I-179J-89D01*
G01Y1078315D01*
G02X1079100Y1078226I-200J0D01*
G01X1079042Y1078110D01*
X1079015Y1078087D01*
G03Y1076045I807J-1021D01*
G01X1079042Y1076022D01*
X1079100Y1075906D01*
G02X1079121Y1075817I-179J-89D01*
G01Y1074575D01*
G02X1079100Y1074486I-200J0D01*
G01X1079042Y1074370D01*
X1079015Y1074347D01*
G03Y1072305I807J-1021D01*
G01X1079042Y1072282D01*
X1079100Y1072166D01*
G02X1079121Y1072077I-179J-89D01*
G01Y1046649D01*
G02X1079037Y1046486I-200J0D01*
G03X1078408Y1045264I873J-1222D01*
G03X1078984Y1044081I1503J0D01*
G01X1079023Y1044051D01*
X1079064Y1043957D01*
X1078750Y1040388D01*
X1078659Y1039358D01*
X1078598Y1039270D01*
X1078549Y1039248D01*
G03X1077676Y1037884I629J-1364D01*
G03X1078320Y1036651I1502J0D01*
G01X1078364Y1036620D01*
X1078410Y1036523D01*
X1078095Y1032958D01*
G02X1078070Y1032887I-197J30D01*
G01X1077999Y1032816D01*
X1077978Y1032804D01*
G03X1077253Y1031518I778J-1286D01*
G03X1077265Y1031330I1502J1D01*
G01Y1031329D01*
G02X1077187Y1031145I-198J-24D01*
G01X1076909Y1030936D01*
G02X1076811Y1030897I-120J160D01*
G01X1076759Y1030891D01*
X1076710Y1030913D01*
G03X1076113Y1031037I-598J-1378D01*
G01X1076110D01*
G03Y1028033I0J-1502D01*
G01X1076111D01*
G03X1077018Y1028338I0J1502D01*
G01X1077029Y1028347D01*
G02X1077235Y1028354I109J-168D01*
G01X1077555Y1028177D01*
G02X1077658Y1027984I-96J-175D01*
G01X1076808Y1018338D01*
G02X1076750Y1018214I-199J18D01*
G01X1072061Y1013525D01*
G03X1072042Y1013507I1023J-1099D01*
G02X1072040Y1013505I-142J140D01*
G03X1072032Y1013498I985J-1134D01*
G02X1071909Y1013442I-140J143D01*
G01X1071788Y1013434D01*
G02X1071774Y1013433I-21J199D01*
G01X1071657Y1013471D01*
G03X1070779Y1013754I-878J-1219D01*
G01X1070778D01*
G03X1069276Y1012252I0J-1502D01*
G01Y1012251D01*
G03X1069602Y1011317I1502J0D01*
G02X1069587Y1011051I-156J-125D01*
G01X1068582Y1010046D01*
G02X1068532Y1010010I-140J142D01*
G02X1068441Y1009988I-91J178D01*
G01X1052227D01*
G02X1052103Y1010031I0J200D01*
G02X1052062Y1010075I124J157D01*
G03X1050920Y1010846I-1318J-721D01*
G01X1050879Y1010851D01*
G03X1050746Y1010857I-134J-1497D01*
G01X1050744D01*
G03X1049786Y1010511I1J-1503D01*
G01X1049757Y1010487D01*
X1049686Y1010463D01*
X1049649Y1010465D01*
G02X1049518Y1010523I10J200D01*
G01X1047997Y1012044D01*
G02X1047961Y1012094I142J140D01*
G02X1047939Y1012185I178J91D01*
G01Y1018472D01*
G02X1047943Y1018509I200J-3D01*
G01Y1018511D01*
G02X1047996Y1018612I196J-39D01*
G01X1049552Y1020168D01*
G02X1049653Y1020221I140J-143D01*
G01X1049655D01*
G02X1049692Y1020225I40J-196D01*
G01X1060206D01*
G03X1060348Y1020284I0J200D01*
G01X1065570Y1025506D01*
G03X1065629Y1025648I-141J142D01*
G01Y1025929D01*
X1065631Y1025930D01*
Y1025972D01*
G02X1065646Y1026048I200J0D01*
G01X1065661Y1026084D01*
X1065688Y1026111D01*
Y1035347D01*
G03X1065673Y1035539I-1259J-2D01*
G01X1065706Y1035555D01*
G03Y1038285I-627J1365D01*
G01X1065673Y1038301D01*
G03X1065688Y1038493I-1244J194D01*
G01Y1038864D01*
G02X1065782Y1039033I200J-1D01*
G01X1066116Y1039240D01*
X1066219Y1039245D01*
X1066266Y1039221D01*
G03X1066932Y1039065I667J1346D01*
G01X1066933D01*
G03Y1042069I0J1502D01*
G01X1066932D01*
G03X1066266Y1041913I1J-1502D01*
G01X1066219Y1041889D01*
X1066116Y1041894D01*
X1065782Y1042101D01*
G02X1065688Y1042270I106J170D01*
G01Y1061739D01*
X1065692Y1061742D01*
G37*
G36*
G01X1154193Y54588D02*
X1182695D01*
X1183133Y54150D01*
Y53029D01*
X1182695Y52591D01*
X1154193D01*
G03X1148256Y46654I0J-5937D01*
G01Y7874D01*
G02X1142382Y2000I-5874J0D01*
G01X1095138D01*
G02X1089264Y7874I0J5874D01*
G01Y46558D01*
X1091262D01*
Y7874D01*
G03X1095138Y3998I3876J0D01*
G01X1142382D01*
G03X1146258Y7874I0J3876D01*
G01Y46654D01*
G02X1154193Y54588I7935J-1D01*
G37*
G36*
G01X1242350Y1253176D02*
X1246717D01*
G02X1246738Y1253175I1J-200D01*
G01X1246739D01*
G02X1246859Y1253117I-22J-199D01*
G01X1256183Y1243793D01*
G03X1256325Y1243734I142J141D01*
G01X1281429D01*
G03X1281571Y1243793I0J200D01*
G01X1288432Y1250654D01*
G02X1288555Y1250712I142J-141D01*
G01X1288565Y1250713D01*
X1375781D01*
X1375893Y1250616D01*
X1375904Y1250542D01*
G03X1377390Y1249258I1486J218D01*
G03X1377949Y1249366I0J1501D01*
G01X1377996Y1249385D01*
X1378094Y1249374D01*
X1378410Y1249160D01*
G02X1378498Y1248995I-112J-166D01*
G01Y1245820D01*
G02X1378410Y1245655I-200J1D01*
G01X1378094Y1245441D01*
X1377996Y1245430D01*
X1377949Y1245449D01*
G03X1377390Y1245557I-559J-1393D01*
G03Y1242553I0J-1502D01*
G03X1377949Y1242661I0J1501D01*
G01X1377996Y1242680D01*
X1378094Y1242669D01*
X1378410Y1242455D01*
G02X1378498Y1242290I-112J-166D01*
G01Y1204570D01*
G02X1378439Y1204428I-200J0D01*
G01X1373654Y1199643D01*
G03X1373595Y1199501I141J-142D01*
G01Y1190630D01*
G03X1373654Y1190488I200J0D01*
G01X1378439Y1185703D01*
G02X1378497Y1185583I-141J-142D01*
G01X1378498Y1185572D01*
Y1159195D01*
G02X1378439Y1159053I-200J0D01*
G01X1376793Y1157407D01*
G02X1376651Y1157348I-142J141D01*
G01X1374617D01*
G03X1374541Y1157333I0J-200D01*
G01X1374474Y1157305D01*
G02X1374397Y1157290I-76J185D01*
G01X1311596D01*
G02X1311528Y1157302I0J200D01*
G01X1311436Y1157335D01*
X1311408Y1157357D01*
G03X1310193Y1157796I-1215J-1462D01*
G01X1299009D01*
G03X1298553Y1157741I-2J-1901D01*
G03X1298353Y1157680I454J-1846D01*
G01X1298286Y1157655D01*
G03X1298269Y1157649I58J-191D01*
G01X1298201Y1157616D01*
G03X1297665Y1157240I808J-1721D01*
G01X1288622Y1148197D01*
G03X1288154Y1147428I1344J-1345D01*
G03X1288121Y1147309I1815J-567D01*
G03X1288066Y1146853I1846J-454D01*
G01Y1134901D01*
G03X1288121Y1134445I1901J-2D01*
G03X1288233Y1134120I1846J454D01*
G01X1288246Y1134093D01*
G03X1288622Y1133557I1721J808D01*
G01X1295250Y1126929D01*
G02X1295306Y1126755I-141J-142D01*
G01X1295246Y1126387D01*
X1295189Y1126309D01*
X1295146Y1126288D01*
G03X1294813Y1123824I669J-1345D01*
G01X1294845Y1123796D01*
X1294879Y1123722D01*
X1294890Y1123350D01*
X1294860Y1123273D01*
X1294831Y1123244D01*
G03X1294391Y1122182I1062J-1062D01*
G03X1297395I1502J0D01*
G03X1296895Y1123302I-1502J1D01*
G01X1296863Y1123329D01*
X1296829Y1123403D01*
X1296818Y1123775D01*
X1296848Y1123852D01*
X1296877Y1123881D01*
G03X1297160Y1124274I-1061J1063D01*
G02X1297307Y1124382I179J-89D01*
G01X1297627Y1124434D01*
G02X1297801Y1124378I32J-197D01*
G01X1299913Y1122266D01*
G02X1299972Y1122125I-141J-142D01*
G01Y1086916D01*
G02X1299772Y1086730I-200J15D01*
G01X1257781D01*
G03X1257639Y1086671I0J-200D01*
G01X1238109Y1067141D01*
G02X1237967Y1067082I-142J141D01*
G01X1149928D01*
G02X1149786Y1067141I0J200D01*
G01X1147860Y1069067D01*
X1147832Y1069121D01*
X1147827Y1069151D01*
G03X1147619Y1069898I-3868J-675D01*
G01X1147606Y1069933D01*
Y1070209D01*
G02X1147719Y1070390I200J1D01*
G01X1148098Y1070570D01*
X1148212Y1070557D01*
X1148257Y1070520D01*
G03X1149014Y1070252I757J935D01*
G03Y1072656I0J1202D01*
G03X1148257Y1072388I0J-1203D01*
G01X1148212Y1072351D01*
X1148098Y1072338D01*
X1147719Y1072518D01*
G02X1147606Y1072699I87J180D01*
G01Y1073842D01*
G02X1147716Y1074021I200J0D01*
G01X1148087Y1074207D01*
X1148198Y1074197D01*
X1148245Y1074163D01*
G03X1149014Y1073908I769J1032D01*
G03Y1076482I0J1287D01*
G03X1148245Y1076227I0J-1287D01*
G01X1148198Y1076193D01*
X1148087Y1076183D01*
X1147716Y1076369D01*
G02X1147606Y1076548I90J179D01*
G01Y1077582D01*
G02X1147716Y1077761I200J0D01*
G01X1148087Y1077947D01*
X1148198Y1077937D01*
X1148245Y1077903D01*
G03X1149014Y1077648I769J1032D01*
G03Y1080222I0J1287D01*
G01X1148979D01*
X1148925Y1080221D01*
X1148831Y1080272D01*
X1148594Y1080662D01*
X1148592Y1080769D01*
X1148619Y1080816D01*
G03X1148862Y1081345I-3346J1857D01*
G02X1149045Y1081475I187J-70D01*
G03X1150217Y1082677I-30J1202D01*
G03X1149249Y1083856I-1202J0D01*
G02X1149089Y1084036I39J196D01*
G03X1149020Y1084506I-3813J-320D01*
G02Y1084588I196J41D01*
G03X1149089Y1085058I-3744J790D01*
G02X1149249Y1085238I199J-16D01*
G03X1150217Y1086417I-234J1179D01*
G03X1149045Y1087619I-1202J0D01*
G02X1148862Y1087749I4J200D01*
G03X1148574Y1088355I-3587J-1333D01*
G01X1148546Y1088404D01*
X1148547Y1088513D01*
X1148790Y1088910D01*
X1148887Y1088961D01*
X1148943Y1088957D01*
G03X1149015Y1088955I69J1200D01*
G03X1147813Y1090157I0J1202D01*
G03X1147907Y1089692I1202J1D01*
G02X1147601Y1089456I-184J-77D01*
G03X1147412Y1089591I-2318J-3045D01*
G02X1147324Y1089757I112J166D01*
G01Y1092807D01*
G03X1147265Y1092949I-200J0D01*
G01X1146503Y1093711D01*
X1146473Y1093789D01*
X1146475Y1093833D01*
G03X1146477Y1093897I-1200J70D01*
G03X1145275Y1095099I-1202J0D01*
G03X1145053Y1095078I2J-1202D01*
G01X1145004Y1095069D01*
X1144911Y1095098D01*
X1144606Y1095403D01*
X1144577Y1095496D01*
X1144586Y1095545D01*
G03X1144607Y1095766I-1181J224D01*
G01Y1095781D01*
G03X1144586Y1095989I-1202J-16D01*
G01X1144577Y1096038D01*
X1144606Y1096131D01*
X1144911Y1096436D01*
X1145004Y1096465D01*
X1145053Y1096456D01*
G03X1145275Y1096435I224J1181D01*
G03X1144073Y1097637I0J1202D01*
G03X1144094Y1097415I1202J2D01*
G01X1144103Y1097366D01*
X1144074Y1097273D01*
X1143769Y1096968D01*
X1143676Y1096939D01*
X1143627Y1096948D01*
G03X1143405Y1096969I-224J-1181D01*
G03X1143183Y1096948I2J-1202D01*
G01X1143134Y1096939D01*
X1143041Y1096968D01*
X1142736Y1097273D01*
X1142707Y1097366D01*
X1142716Y1097415D01*
G03X1142737Y1097637I-1181J224D01*
G03X1140333I-1202J0D01*
G03X1140342Y1097494I1202J4D01*
G01X1140347Y1097446D01*
X1140316Y1097359D01*
X1140015Y1097071D01*
X1139926Y1097044D01*
X1139878Y1097052D01*
G03X1139663Y1097070I-216J-1285D01*
G03X1139451Y1097053I-2J-1303D01*
G01X1139404Y1097045D01*
X1139315Y1097072D01*
X1139014Y1097359D01*
X1138983Y1097447D01*
X1138989Y1097495D01*
G03X1138997Y1097637I-1194J139D01*
G03X1136593I-1202J0D01*
G03X1136614Y1097415I1202J2D01*
G01X1136623Y1097366D01*
X1136594Y1097272D01*
X1136290Y1096968D01*
X1136195Y1096939D01*
X1136147Y1096948D01*
G03X1135924Y1096969I-224J-1181D01*
G03X1135702Y1096948I2J-1202D01*
G01X1135653Y1096939D01*
X1135560Y1096968D01*
X1135255Y1097273D01*
X1135226Y1097366D01*
X1135235Y1097415D01*
G03X1135256Y1097637I-1181J224D01*
G03X1132852I-1202J0D01*
G03X1132861Y1097494I1202J4D01*
G01X1132866Y1097446D01*
X1132835Y1097359D01*
X1132534Y1097071D01*
X1132445Y1097044D01*
X1132397Y1097052D01*
G03X1132182Y1097070I-216J-1284D01*
G03X1131970Y1097053I-2J-1302D01*
G01X1131923Y1097045D01*
X1131834Y1097072D01*
X1131533Y1097359D01*
X1131502Y1097447D01*
X1131508Y1097495D01*
G03X1131516Y1097637I-1194J139D01*
G03X1129112I-1202J0D01*
G03X1129133Y1097415I1202J2D01*
G01X1129142Y1097366D01*
X1129113Y1097273D01*
X1128808Y1096968D01*
X1128715Y1096939D01*
X1128666Y1096948D01*
G03X1128444Y1096969I-224J-1181D01*
G03X1128222Y1096948I2J-1202D01*
G01X1128173Y1096939D01*
X1128080Y1096968D01*
X1127775Y1097273D01*
X1127746Y1097366D01*
X1127755Y1097415D01*
G03X1127776Y1097637I-1181J224D01*
G03X1125372I-1202J0D01*
G03X1125381Y1097494I1202J4D01*
G01X1125386Y1097446D01*
X1125355Y1097359D01*
X1125053Y1097071D01*
X1124965Y1097044D01*
X1124917Y1097052D01*
G03X1124701Y1097070I-216J-1285D01*
G03X1124490Y1097053I-1J-1303D01*
G01X1124442Y1097045D01*
X1124353Y1097072D01*
X1124053Y1097360D01*
X1124022Y1097447D01*
X1124028Y1097495D01*
G03X1124036Y1097637I-1194J139D01*
G03X1121632I-1202J0D01*
G03X1121653Y1097415I1202J2D01*
G01X1121662Y1097366D01*
X1121633Y1097273D01*
X1121328Y1096968D01*
X1121235Y1096939D01*
X1121186Y1096948D01*
G03X1120964Y1096969I-224J-1181D01*
G03X1120742Y1096948I2J-1202D01*
G01X1120693Y1096939D01*
X1120600Y1096968D01*
X1120295Y1097273D01*
X1120266Y1097366D01*
X1120275Y1097415D01*
G03X1120296Y1097637I-1181J224D01*
G03X1117892I-1202J0D01*
G03X1117901Y1097494I1202J4D01*
G01X1117906Y1097446D01*
X1117875Y1097359D01*
X1117573Y1097071D01*
X1117485Y1097044D01*
X1117437Y1097052D01*
G03X1117221Y1097070I-216J-1285D01*
G03X1117010Y1097053I-1J-1303D01*
G01X1116962Y1097045D01*
X1116873Y1097072D01*
X1116573Y1097360D01*
X1116542Y1097447D01*
X1116548Y1097495D01*
G03X1116556Y1097637I-1194J139D01*
G03X1114152I-1202J0D01*
G03X1114173Y1097415I1202J2D01*
G01X1114182Y1097366D01*
X1114153Y1097273D01*
X1113848Y1096968D01*
X1113755Y1096939D01*
X1113706Y1096948D01*
G03X1113484Y1096969I-224J-1181D01*
G03X1113261Y1096948I1J-1202D01*
G01X1113213Y1096939D01*
X1113118Y1096968D01*
X1112814Y1097272D01*
X1112785Y1097366D01*
X1112794Y1097415D01*
G03X1112815Y1097637I-1181J224D01*
G03X1110411I-1202J0D01*
G03X1110420Y1097494I1202J4D01*
G01X1110425Y1097446D01*
X1110394Y1097359D01*
X1110093Y1097071D01*
X1110004Y1097044D01*
X1109956Y1097052D01*
G03X1109741Y1097070I-216J-1285D01*
G03X1109529Y1097053I-2J-1303D01*
G01X1109482Y1097045D01*
X1109393Y1097072D01*
X1109092Y1097359D01*
X1109061Y1097447D01*
X1109067Y1097495D01*
G03X1109075Y1097637I-1194J139D01*
G03X1106671I-1202J0D01*
G03X1106692Y1097415I1202J2D01*
G01X1106701Y1097366D01*
X1106672Y1097273D01*
X1106367Y1096968D01*
X1106274Y1096939D01*
X1106225Y1096948D01*
G03X1106003Y1096969I-224J-1181D01*
G03X1105781Y1096948I2J-1202D01*
G01X1105732Y1096939D01*
X1105639Y1096968D01*
X1105334Y1097273D01*
X1105305Y1097366D01*
X1105314Y1097415D01*
G03X1105335Y1097637I-1181J224D01*
G03X1104133Y1098839I-1202J0D01*
G03X1103692Y1098755I0J-1202D01*
G01X1103657Y1098741D01*
X1103619D01*
G02X1103419Y1098941I0J200D01*
G01Y1099134D01*
G02X1103421Y1099158I200J-5D01*
G01X1103426Y1099202D01*
X1103434Y1099237D01*
G03X1103465Y1099507I-1171J271D01*
G01Y1099572D01*
G03X1103463Y1099595I-199J-6D01*
G01Y1099597D01*
X1103458Y1099640D01*
Y1099641D01*
X1103456Y1099657D01*
X1103446Y1099731D01*
G03X1103442Y1099753I-199J-25D01*
G01X1103426Y1099815D01*
X1103419Y1099865D01*
Y1100073D01*
G02X1103619Y1100273I200J0D01*
G01X1103657D01*
X1103692Y1100259D01*
G03X1104133Y1100175I441J1118D01*
G03Y1102579I0J1202D01*
G03X1103692Y1102495I0J-1202D01*
G01X1103657Y1102481D01*
X1103619D01*
G02X1103419Y1102681I0J200D01*
G01Y1102874D01*
G02X1103421Y1102898I200J-5D01*
G01X1103426Y1102942D01*
X1103434Y1102977D01*
G03X1103465Y1103247I-1171J271D01*
G01Y1103312D01*
G03X1103463Y1103335I-199J-6D01*
G01Y1103337D01*
X1103458Y1103380D01*
Y1103381D01*
X1103456Y1103397D01*
X1103446Y1103471D01*
G03X1103442Y1103493I-199J-25D01*
G01X1103426Y1103555D01*
X1103419Y1103605D01*
Y1103813D01*
G02X1103619Y1104013I200J0D01*
G01X1103657D01*
X1103692Y1103999D01*
G03X1104133Y1103915I441J1118D01*
G03Y1106319I0J1202D01*
G03X1103692Y1106235I0J-1202D01*
G01X1103657Y1106221D01*
X1103619D01*
G02X1103419Y1106421I0J200D01*
G01Y1106615D01*
G02X1103421Y1106639I200J-5D01*
G01X1103426Y1106683D01*
X1103434Y1106718D01*
G03X1103465Y1106988I-1171J271D01*
G01Y1107053D01*
G03X1103463Y1107076I-199J-6D01*
G01Y1107078D01*
X1103458Y1107121D01*
Y1107122D01*
X1103456Y1107138D01*
X1103446Y1107212D01*
G03X1103442Y1107234I-199J-25D01*
G01X1103426Y1107296D01*
X1103419Y1107346D01*
Y1107554D01*
G02X1103619Y1107754I200J0D01*
G01X1103657D01*
X1103692Y1107740D01*
G03X1104133Y1107656I441J1118D01*
G03Y1110060I0J1202D01*
G03X1103692Y1109976I0J-1202D01*
G01X1103657Y1109962D01*
X1103619D01*
G02X1103419Y1110162I0J200D01*
G01Y1110355D01*
G02X1103421Y1110379I200J-5D01*
G01X1103426Y1110423D01*
X1103434Y1110458D01*
G03X1103465Y1110728I-1171J271D01*
G01Y1110793D01*
G03X1103463Y1110816I-199J-6D01*
G01Y1110818D01*
X1103458Y1110861D01*
Y1110862D01*
X1103456Y1110878D01*
X1103446Y1110952D01*
G03X1103442Y1110974I-199J-25D01*
G01X1103426Y1111036D01*
X1103419Y1111086D01*
Y1114095D01*
G02X1103421Y1114119I200J-5D01*
G01X1103426Y1114163D01*
X1103429Y1114176D01*
Y1114178D01*
G03X1103465Y1114468I-1166J292D01*
G01Y1114533D01*
G03X1103463Y1114556I-199J-6D01*
G01Y1114558D01*
X1103458Y1114601D01*
Y1114602D01*
X1103456Y1114618D01*
X1103446Y1114692D01*
G03X1103442Y1114714I-199J-25D01*
G01X1103426Y1114776D01*
X1103419Y1114826D01*
Y1117835D01*
G02X1103421Y1117859I200J-5D01*
G01X1103426Y1117903D01*
X1103429Y1117916D01*
Y1117918D01*
G03X1103465Y1118208I-1166J292D01*
G01Y1118273D01*
G03X1103463Y1118296I-199J-6D01*
G01Y1118298D01*
X1103458Y1118341D01*
Y1118342D01*
X1103456Y1118358D01*
X1103446Y1118432D01*
G03X1103442Y1118454I-199J-25D01*
G01X1103426Y1118516D01*
X1103419Y1118566D01*
Y1121575D01*
G02X1103421Y1121599I200J-5D01*
G01X1103426Y1121643D01*
X1103429Y1121656D01*
Y1121658D01*
G03X1103465Y1121948I-1166J292D01*
G01Y1122013D01*
G03X1103463Y1122036I-199J-6D01*
G01Y1122038D01*
X1103458Y1122081D01*
Y1122082D01*
X1103456Y1122098D01*
X1103446Y1122172D01*
G03X1103442Y1122194I-199J-25D01*
G01X1103426Y1122256D01*
X1103419Y1122306D01*
Y1125315D01*
G02X1103421Y1125339I200J-5D01*
G01X1103426Y1125383D01*
X1103429Y1125396D01*
Y1125398D01*
G03X1103465Y1125688I-1166J292D01*
G01Y1125753D01*
G03X1103463Y1125776I-199J-6D01*
G01Y1125778D01*
X1103458Y1125821D01*
Y1125822D01*
X1103456Y1125838D01*
X1103446Y1125912D01*
G03X1103442Y1125934I-199J-25D01*
G01X1103426Y1125996D01*
X1103419Y1126046D01*
Y1129056D01*
G02X1103421Y1129080I200J-5D01*
G01X1103426Y1129124D01*
X1103429Y1129137D01*
Y1129139D01*
G03X1103465Y1129429I-1166J292D01*
G01Y1129494D01*
G03X1103463Y1129517I-199J-6D01*
G01Y1129519D01*
X1103458Y1129562D01*
Y1129563D01*
X1103456Y1129579D01*
X1103446Y1129653D01*
G03X1103442Y1129675I-199J-25D01*
G01X1103426Y1129737D01*
X1103419Y1129787D01*
Y1132796D01*
G02X1103421Y1132820I200J-5D01*
G01X1103426Y1132864D01*
X1103429Y1132877D01*
Y1132879D01*
G03X1103465Y1133169I-1166J292D01*
G01Y1133234D01*
G03X1103463Y1133257I-199J-6D01*
G01Y1133259D01*
X1103458Y1133302D01*
Y1133303D01*
X1103456Y1133319D01*
X1103446Y1133393D01*
G03X1103442Y1133415I-199J-25D01*
G01X1103426Y1133477D01*
X1103419Y1133527D01*
Y1136536D01*
G02X1103421Y1136560I200J-5D01*
G01X1103426Y1136604D01*
X1103429Y1136617D01*
Y1136619D01*
G03X1103465Y1136909I-1166J292D01*
G01Y1136974D01*
G03X1103463Y1136997I-199J-6D01*
G01Y1136999D01*
X1103458Y1137042D01*
Y1137043D01*
X1103456Y1137059D01*
X1103446Y1137133D01*
G03X1103442Y1137155I-199J-25D01*
G01X1103426Y1137217D01*
X1103419Y1137267D01*
Y1140276D01*
G02X1103421Y1140300I200J-5D01*
G01X1103426Y1140344D01*
X1103429Y1140357D01*
Y1140359D01*
G03X1103465Y1140649I-1166J292D01*
G03X1103431Y1140932I-1202J-1D01*
G01X1103429Y1140941D01*
X1103428Y1140948D01*
X1103425Y1140964D01*
X1103419Y1141006D01*
Y1141024D01*
G02X1103478Y1141166I200J0D01*
G01X1103888Y1141575D01*
G03X1104060Y1141793I-851J848D01*
G01X1104074Y1141816D01*
X1104077Y1141821D01*
G03X1104113Y1141887I-1037J608D01*
G01Y1141888D01*
X1104114Y1141889D01*
G02X1104115Y1141891I179J-88D01*
G03X1104125Y1141911I-1070J547D01*
G01X1104130Y1141923D01*
X1104133Y1141927D01*
X1104149Y1141965D01*
X1104150Y1141968D01*
X1104152Y1141974D01*
G03X1104189Y1142079I-1113J451D01*
G02X1104190Y1142082I190J-62D01*
G03X1104200Y1142114I-1142J374D01*
G01X1104201Y1142118D01*
Y1142120D01*
G03X1104206Y1142137I-1149J347D01*
G01X1104208Y1142149D01*
X1104209Y1142154D01*
G03X1104239Y1142365I-1170J274D01*
G01X1104240Y1142385D01*
Y1142823D01*
G03X1103920Y1143605I-1201J-35D01*
G01X1103913Y1143612D01*
X1103911Y1143614D01*
G03X1103890Y1143636I-880J-819D01*
G01X1103875Y1143651D01*
X1103854Y1143671D01*
X1103813Y1143710D01*
G03X1103788Y1143730I-137J-145D01*
G01X1103787Y1143731D01*
X1103763Y1143748D01*
X1103760Y1143751D01*
X1103757Y1143753D01*
X1103620Y1143848D01*
X1103618D01*
X1103556Y1143892D01*
X1103545Y1143900D01*
X1103466Y1143956D01*
X1103423Y1144067D01*
X1103436Y1144125D01*
Y1144126D01*
X1103440Y1144146D01*
G03X1103465Y1144378I-1177J244D01*
G01Y1144389D01*
Y1144429D01*
Y1144436D01*
G02X1103464Y1144440I190J50D01*
G03X1103463Y1144467I-1202J-31D01*
G01X1103462Y1144468D01*
Y1144472D01*
X1103460Y1144519D01*
G03X1103456Y1144548I-200J-13D01*
G01Y1144549D01*
X1103449Y1144584D01*
Y1144585D01*
Y1144587D01*
G03X1103446Y1144602I-1180J-228D01*
G01X1103444Y1144615D01*
G03X1103436Y1144650I-1175J-250D01*
G01X1103423Y1144709D01*
X1103466Y1144821D01*
X1103562Y1144890D01*
X1103593Y1144912D01*
X1103619Y1144930D01*
X1103643Y1144946D01*
X1103676Y1144970D01*
X1103716Y1144998D01*
X1103738Y1145013D01*
G03X1103822Y1145079I-700J977D01*
G03X1103824Y1145081I-140J142D01*
G03X1103825Y1145082I-847J848D01*
G03X1103860Y1145114I-793J902D01*
G01X1103868Y1145122D01*
X1103883Y1145133D01*
G03X1103903Y1145154I-135J148D01*
G01X1103907Y1145159D01*
X1103916Y1145169D01*
X1103919Y1145172D01*
G03X1103921Y1145175I-998J668D01*
G03X1103954Y1145212I-880J818D01*
G01X1103955Y1145213D01*
G03X1103957Y1145215I-848J850D01*
G03X1103968Y1145229I-152J130D01*
G01X1103971Y1145234D01*
X1103999Y1145268D01*
X1104000Y1145269D01*
G03X1104004Y1145274I-935J752D01*
G01X1104005Y1145276D01*
X1104014Y1145288D01*
G03X1104240Y1145989I-976J701D01*
G01Y1146563D01*
G03X1103920Y1147345I-1201J-35D01*
G01X1103913Y1147352D01*
X1103911Y1147354D01*
G03X1103890Y1147376I-880J-819D01*
G01X1103875Y1147391D01*
X1103854Y1147411D01*
X1103813Y1147450D01*
G03X1103788Y1147470I-137J-145D01*
G01X1103787Y1147471D01*
X1103763Y1147488D01*
X1103760Y1147491D01*
X1103757Y1147493D01*
X1103620Y1147588D01*
X1103618D01*
X1103556Y1147632D01*
X1103545Y1147640D01*
X1103466Y1147696D01*
X1103423Y1147807D01*
X1103436Y1147865D01*
Y1147866D01*
X1103440Y1147886D01*
G03X1103465Y1148118I-1177J244D01*
G01Y1148129D01*
Y1148169D01*
Y1148176D01*
G02X1103464Y1148180I190J50D01*
G03X1103463Y1148207I-1202J-31D01*
G01X1103462Y1148208D01*
Y1148212D01*
X1103460Y1148259D01*
G03X1103456Y1148288I-200J-13D01*
G01Y1148289D01*
X1103449Y1148324D01*
Y1148325D01*
Y1148327D01*
G03X1103446Y1148342I-1180J-228D01*
G01X1103444Y1148355D01*
G03X1103436Y1148390I-1175J-250D01*
G01X1103423Y1148449D01*
X1103466Y1148561D01*
X1103562Y1148630D01*
X1103593Y1148652D01*
X1103619Y1148670D01*
X1103643Y1148686D01*
X1103676Y1148710D01*
X1103716Y1148738D01*
X1103738Y1148753D01*
G03X1103822Y1148819I-700J977D01*
G03X1103824Y1148821I-140J142D01*
G03X1103825Y1148822I-847J848D01*
G03X1103860Y1148854I-793J902D01*
G01X1103868Y1148862D01*
X1103883Y1148873D01*
G03X1103903Y1148894I-135J148D01*
G01X1103907Y1148899D01*
X1103916Y1148909D01*
X1103919Y1148912D01*
G03X1103921Y1148915I-998J668D01*
G03X1103954Y1148952I-880J818D01*
G01X1103955Y1148953D01*
G03X1103957Y1148955I-848J850D01*
G03X1103968Y1148969I-152J130D01*
G01X1103971Y1148974D01*
X1103999Y1149008D01*
X1104000Y1149009D01*
G03X1104004Y1149014I-935J752D01*
G01X1104005Y1149016D01*
X1104014Y1149028D01*
G03X1104240Y1149729I-976J701D01*
G01Y1150304D01*
G03X1103920Y1151086I-1201J-35D01*
G01X1103913Y1151093D01*
X1103911Y1151095D01*
G03X1103890Y1151117I-880J-819D01*
G01X1103875Y1151132D01*
X1103854Y1151152D01*
X1103813Y1151191D01*
G03X1103788Y1151211I-137J-145D01*
G01X1103787Y1151212D01*
X1103763Y1151229D01*
X1103760Y1151232D01*
X1103757Y1151234D01*
X1103620Y1151329D01*
X1103618D01*
X1103556Y1151373D01*
X1103545Y1151381D01*
X1103466Y1151437D01*
X1103423Y1151548D01*
X1103436Y1151606D01*
Y1151607D01*
X1103440Y1151627D01*
G03X1103465Y1151859I-1177J244D01*
G01Y1151870D01*
Y1151910D01*
Y1151917D01*
G02X1103464Y1151921I190J50D01*
G03X1103463Y1151948I-1202J-31D01*
G01X1103462Y1151949D01*
Y1151953D01*
X1103460Y1152000D01*
G03X1103456Y1152029I-200J-13D01*
G01Y1152030D01*
X1103449Y1152065D01*
Y1152066D01*
Y1152068D01*
G03X1103446Y1152083I-1180J-228D01*
G01X1103444Y1152096D01*
G03X1103436Y1152131I-1175J-250D01*
G01X1103423Y1152190D01*
X1103466Y1152302D01*
X1103562Y1152371D01*
X1103593Y1152393D01*
X1103619Y1152411D01*
X1103643Y1152427D01*
X1103676Y1152451D01*
X1103716Y1152479D01*
X1103738Y1152494D01*
G03X1103822Y1152560I-700J977D01*
G01X1103831Y1152569D01*
X1103836Y1152573D01*
X1103892Y1152629D01*
X1103897D01*
X1103901Y1152634D01*
X1103907Y1152640D01*
X1103920Y1152654D01*
X1103925Y1152660D01*
G03X1103954Y1152693I-888J809D01*
G01X1103955Y1152694D01*
G03X1103957Y1152696I-848J850D01*
G03X1103968Y1152710I-152J130D01*
G01X1103971Y1152715D01*
X1103999Y1152749D01*
X1104000Y1152750D01*
G03X1104004Y1152755I-935J752D01*
G01X1104005Y1152757D01*
X1104014Y1152769D01*
G03X1104240Y1153470I-976J701D01*
G01Y1156116D01*
G03X1103939Y1156911I-1202J0D01*
G03X1103936Y1156914I-143J-140D01*
G02X1103934Y1156916I140J142D01*
G03X1103933Y1156917I-849J-848D01*
G02X1103923Y1156928I143J140D01*
G03X1103914Y1156938I-897J-799D01*
G01X1103913Y1156939D01*
G03X1103905Y1156947I-853J-845D01*
G03X1103903Y1156949I-850J-848D01*
G03X1103893Y1156960I-894J-803D01*
G01X1103890Y1156963D01*
X1103889D01*
X1103750Y1157102D01*
X1103477Y1157376D01*
G02X1103419Y1157517I142J141D01*
G01Y1158977D01*
G02X1103421Y1159001I200J-5D01*
G01X1103426Y1159045D01*
X1103429Y1159058D01*
Y1159060D01*
G03X1103465Y1159350I-1166J292D01*
G01Y1159429D01*
G02X1103466Y1159444I200J-6D01*
G02X1103524Y1159571I199J-14D01*
G01X1103767Y1159814D01*
X1103771Y1159817D01*
G03X1103778Y1159824I-846J853D01*
G01X1103781Y1159827D01*
G03X1103793Y1159839I-844J856D01*
G01X1104170Y1160216D01*
G03X1104262Y1160321I-857J843D01*
G01X1104265Y1160324D01*
X1104277Y1160338D01*
G03X1104352Y1160451I-963J720D01*
G03X1104520Y1161055I-1034J613D01*
G01Y1164163D01*
G02X1104632Y1164343I200J0D01*
G01X1104683Y1164368D01*
X1104796Y1164356D01*
X1107533Y1162242D01*
G03X1107795Y1162257I122J158D01*
G01X1107797Y1162259D01*
G03X1107855Y1162384I-141J142D01*
G01X1107858Y1162420D01*
X1107838Y1162490D01*
X1105720Y1165313D01*
G02X1105686Y1165482I160J120D01*
G01X1105704Y1165555D01*
X1105824Y1165639D01*
X1105898Y1165633D01*
G03X1106003Y1165628I110J1197D01*
G01X1106036D01*
G03X1107205Y1166830I-33J1202D01*
G03X1106003Y1168032I-1202J0D01*
G03X1104921Y1167354I0J-1202D01*
G01X1104898Y1167308D01*
X1104815Y1167249D01*
X1104556Y1167218D01*
X1104379Y1167196D01*
X1104285Y1167234D01*
X1104252Y1167274D01*
G03X1104233Y1167297I-936J-754D01*
G01X1104226Y1167305D01*
X1104217Y1167318D01*
X1104197Y1167337D01*
X1104192Y1167342D01*
G03X1104187Y1167348I-926J-766D01*
G01X1104183Y1167352D01*
G03X1104180Y1167355I-851J-848D01*
G02X1104178Y1167357I140J142D01*
G03X1104149Y1167386I-865J-836D01*
G01X1104147Y1167388D01*
X1104146Y1167389D01*
X1104107Y1167428D01*
X1103947Y1167589D01*
X1103468Y1168068D01*
G02X1103419Y1168198I151J131D01*
G01Y1170197D01*
G02X1103421Y1170221I200J-5D01*
G01X1103426Y1170265D01*
X1103429Y1170278D01*
Y1170280D01*
G03X1103465Y1170570I-1166J292D01*
G01Y1170635D01*
G03X1103463Y1170658I-199J-6D01*
G01Y1170660D01*
X1103458Y1170703D01*
Y1170704D01*
X1103456Y1170720D01*
X1103446Y1170794D01*
G03X1103442Y1170816I-199J-25D01*
G01X1103426Y1170878D01*
X1103419Y1170928D01*
Y1170973D01*
G02X1103498Y1171132I200J0D01*
G01X1103569Y1171186D01*
X1103570D01*
X1103653Y1171249D01*
G03X1104130Y1172207I-725J959D01*
G01Y1176414D01*
G03X1103653Y1177372I-1202J-1D01*
G01X1103509Y1177481D01*
G02X1103488Y1177499I119J160D01*
G01X1103478Y1177509D01*
G02X1103419Y1177651I141J142D01*
G01Y1177691D01*
X1103426Y1177746D01*
X1103429Y1177759D01*
Y1177761D01*
G03X1103465Y1178051I-1166J292D01*
G01Y1178116D01*
G03X1103463Y1178139I-199J-6D01*
G01Y1178141D01*
X1103458Y1178184D01*
Y1178185D01*
X1103456Y1178201D01*
X1103446Y1178275D01*
G03X1103442Y1178297I-199J-25D01*
G01X1103426Y1178359D01*
X1103419Y1178409D01*
Y1181418D01*
G02X1103421Y1181442I200J-5D01*
G01X1103426Y1181486D01*
X1103429Y1181499D01*
Y1181501D01*
G03X1103465Y1181791I-1166J292D01*
G01Y1181856D01*
G03X1103463Y1181879I-199J-6D01*
G01Y1181881D01*
X1103458Y1181924D01*
Y1181925D01*
X1103456Y1181941D01*
X1103446Y1182015D01*
G03X1103442Y1182037I-199J-25D01*
G01X1103426Y1182099D01*
X1103419Y1182149D01*
Y1185158D01*
G02X1103421Y1185182I200J-5D01*
G01X1103426Y1185226D01*
X1103429Y1185239D01*
Y1185241D01*
G03X1103465Y1185531I-1166J292D01*
G01Y1185596D01*
G03X1103463Y1185619I-199J-6D01*
G01Y1185621D01*
X1103458Y1185664D01*
Y1185665D01*
X1103456Y1185681D01*
X1103446Y1185755D01*
G03X1103442Y1185777I-199J-25D01*
G01X1103426Y1185839D01*
X1103419Y1185889D01*
Y1192638D01*
G02X1103421Y1192662I200J-5D01*
G01X1103426Y1192706D01*
X1103429Y1192719D01*
Y1192721D01*
G03X1103465Y1193011I-1166J292D01*
G01Y1193076D01*
G03X1103463Y1193099I-199J-6D01*
G01Y1193101D01*
X1103458Y1193144D01*
Y1193145D01*
X1103456Y1193161D01*
X1103446Y1193235D01*
G03X1103442Y1193257I-199J-25D01*
G01X1103426Y1193319D01*
X1103419Y1193369D01*
Y1196378D01*
G02X1103421Y1196402I200J-5D01*
G01X1103426Y1196446D01*
X1103429Y1196459D01*
Y1196461D01*
G03X1103465Y1196751I-1166J292D01*
G01Y1196816D01*
G03X1103463Y1196839I-199J-6D01*
G01Y1196841D01*
X1103458Y1196884D01*
Y1196885D01*
X1103456Y1196901D01*
X1103446Y1196975D01*
G03X1103442Y1196997I-199J-25D01*
G01X1103426Y1197059D01*
X1103419Y1197109D01*
Y1200118D01*
G02X1103421Y1200142I200J-5D01*
G01X1103426Y1200186D01*
X1103429Y1200199D01*
Y1200201D01*
G03X1103465Y1200491I-1166J292D01*
G01Y1200556D01*
G03X1103463Y1200579I-199J-6D01*
G01Y1200581D01*
X1103458Y1200624D01*
Y1200625D01*
X1103456Y1200641D01*
X1103446Y1200715D01*
G03X1103442Y1200737I-199J-25D01*
G01X1103426Y1200799D01*
X1103419Y1200849D01*
Y1203859D01*
G02X1103421Y1203883I200J-5D01*
G01X1103426Y1203927D01*
X1103429Y1203940D01*
Y1203942D01*
G03X1103465Y1204232I-1166J292D01*
G01Y1204297D01*
G03X1103463Y1204320I-199J-6D01*
G01Y1204322D01*
X1103458Y1204365D01*
Y1204366D01*
X1103456Y1204382D01*
X1103446Y1204456D01*
G03X1103442Y1204478I-199J-25D01*
G01X1103426Y1204540D01*
X1103419Y1204590D01*
Y1207599D01*
G02X1103421Y1207623I200J-5D01*
G01X1103426Y1207667D01*
X1103429Y1207680D01*
Y1207682D01*
G03X1103465Y1207972I-1166J292D01*
G01Y1208037D01*
G03X1103463Y1208060I-199J-6D01*
G01Y1208062D01*
X1103458Y1208105D01*
Y1208106D01*
X1103456Y1208122D01*
X1103446Y1208196D01*
G03X1103442Y1208218I-199J-25D01*
G01X1103426Y1208280D01*
X1103419Y1208330D01*
Y1211339D01*
G02X1103421Y1211363I200J-5D01*
G01X1103426Y1211407D01*
X1103429Y1211420D01*
Y1211422D01*
G03X1103465Y1211712I-1166J292D01*
G01Y1211777D01*
G03X1103463Y1211800I-199J-6D01*
G01Y1211802D01*
X1103458Y1211845D01*
Y1211846D01*
X1103456Y1211862D01*
X1103446Y1211936D01*
G03X1103442Y1211958I-199J-25D01*
G01X1103426Y1212020D01*
X1103419Y1212070D01*
Y1215079D01*
G02X1103421Y1215103I200J-5D01*
G01X1103426Y1215147D01*
X1103429Y1215160D01*
Y1215162D01*
G03X1103465Y1215452I-1166J292D01*
G01Y1215517D01*
G03X1103463Y1215540I-199J-6D01*
G01Y1215542D01*
X1103458Y1215585D01*
Y1215586D01*
X1103456Y1215602D01*
X1103446Y1215676D01*
G03X1103442Y1215698I-199J-25D01*
G01X1103426Y1215760D01*
X1103419Y1215810D01*
Y1218738D01*
X1103434Y1218775D01*
G03X1103449Y1218851I-185J76D01*
G01Y1218996D01*
X1103451Y1219011D01*
Y1219012D01*
G03X1103461Y1219099I-1188J181D01*
G01Y1219101D01*
G02X1103519Y1219226I199J-17D01*
G01X1103863Y1219570D01*
G02X1103986Y1219628I142J-141D01*
G01X1103996Y1219629D01*
X1104401D01*
G02X1104544Y1219569I0J-200D01*
G01X1104773Y1219334D01*
X1104802Y1219261D01*
X1104801Y1219220D01*
Y1219192D01*
G03X1107205I1202J0D01*
G01Y1219220D01*
X1107204Y1219261D01*
X1107233Y1219334D01*
X1107390Y1219495D01*
X1107462Y1219569D01*
G02X1107605Y1219629I143J-140D01*
G01X1108141D01*
G02X1108284Y1219569I0J-200D01*
G01X1108513Y1219334D01*
X1108542Y1219261D01*
X1108541Y1219220D01*
Y1219192D01*
G03X1109743Y1217990I1202J0D01*
G03X1109965Y1218011I-2J1202D01*
G01X1110014Y1218020D01*
X1110107Y1217991D01*
X1110412Y1217686D01*
X1110441Y1217593D01*
X1110432Y1217544D01*
G03X1110411Y1217322I1181J-224D01*
G03X1110432Y1217100I1202J2D01*
G01X1110441Y1217051D01*
X1110412Y1216958D01*
X1110107Y1216653D01*
X1110014Y1216624D01*
X1109965Y1216633D01*
G03X1109743Y1216654I-224J-1181D01*
G03X1110945Y1215452I0J-1202D01*
G03X1110924Y1215674I-1202J-2D01*
G01X1110915Y1215723D01*
X1110944Y1215816D01*
X1111249Y1216121D01*
X1111342Y1216150D01*
X1111391Y1216141D01*
G03X1111613Y1216120I224J1181D01*
G03X1112815Y1217322I0J1202D01*
G03X1112794Y1217544I-1202J-2D01*
G01X1112785Y1217593D01*
X1112814Y1217687D01*
X1113118Y1217991D01*
X1113213Y1218020D01*
X1113261Y1218011D01*
G03X1113484Y1217990I224J1181D01*
G03X1113706Y1218011I-2J1202D01*
G01X1113755Y1218020D01*
X1113848Y1217991D01*
X1114153Y1217686D01*
X1114182Y1217593D01*
X1114173Y1217544D01*
G03X1114152Y1217322I1181J-224D01*
G03X1115354Y1216120I1202J0D01*
G03X1115576Y1216141I-2J1202D01*
G01X1115625Y1216150D01*
X1115718Y1216121D01*
X1116023Y1215816D01*
X1116052Y1215723D01*
X1116043Y1215674D01*
G03X1116022Y1215452I1181J-224D01*
G03X1117224Y1216654I1202J0D01*
G03X1117002Y1216633I2J-1202D01*
G01X1116953Y1216624D01*
X1116860Y1216653D01*
X1116555Y1216958D01*
X1116526Y1217051D01*
X1116535Y1217100D01*
G03X1116556Y1217322I-1181J224D01*
G03X1116535Y1217544I-1202J-2D01*
G01X1116526Y1217593D01*
X1116555Y1217686D01*
X1116860Y1217991D01*
X1116953Y1218020D01*
X1117002Y1218011D01*
G03X1117224Y1217990I224J1181D01*
G03X1118426Y1219192I0J1202D01*
G01Y1219220D01*
X1118425Y1219261D01*
X1118454Y1219334D01*
X1118611Y1219495D01*
X1118683Y1219569D01*
G02X1118826Y1219629I143J-140D01*
G01X1119362D01*
G02X1119505Y1219569I0J-200D01*
G01X1119734Y1219334D01*
X1119763Y1219261D01*
X1119762Y1219220D01*
Y1219192D01*
G03X1122166I1202J0D01*
G01Y1219220D01*
X1122165Y1219261D01*
X1122194Y1219334D01*
X1122351Y1219495D01*
X1122423Y1219569D01*
G02X1122566Y1219629I143J-140D01*
G01X1123102D01*
G02X1123245Y1219569I0J-200D01*
G01X1123474Y1219334D01*
X1123503Y1219261D01*
X1123502Y1219220D01*
Y1219192D01*
G03X1125906I1202J0D01*
G01Y1219220D01*
X1125905Y1219261D01*
X1125934Y1219334D01*
X1126091Y1219495D01*
X1126163Y1219569D01*
G02X1126306Y1219629I143J-140D01*
G01X1126842D01*
G02X1126985Y1219569I0J-200D01*
G01X1127214Y1219334D01*
X1127243Y1219261D01*
X1127242Y1219220D01*
Y1219192D01*
G03X1129646I1202J0D01*
G01Y1219220D01*
X1129645Y1219261D01*
X1129674Y1219334D01*
X1129831Y1219495D01*
X1129903Y1219569D01*
G02X1130046Y1219629I143J-140D01*
G01X1130582D01*
G02X1130725Y1219569I0J-200D01*
G01X1130954Y1219334D01*
X1130983Y1219261D01*
X1130982Y1219220D01*
Y1219192D01*
G03X1132184Y1217990I1202J0D01*
G03X1132406Y1218011I-2J1202D01*
G01X1132455Y1218020D01*
X1132548Y1217991D01*
X1132853Y1217686D01*
X1132882Y1217593D01*
X1132873Y1217544D01*
G03X1132852Y1217322I1181J-224D01*
G03X1132873Y1217100I1202J2D01*
G01X1132882Y1217051D01*
X1132853Y1216958D01*
X1132548Y1216653D01*
X1132455Y1216624D01*
X1132406Y1216633D01*
G03X1132184Y1216654I-224J-1181D01*
G03X1133386Y1215452I0J-1202D01*
G03X1133365Y1215674I-1202J-2D01*
G01X1133356Y1215723D01*
X1133385Y1215816D01*
X1133690Y1216121D01*
X1133783Y1216150D01*
X1133832Y1216141D01*
G03X1134054Y1216120I224J1181D01*
G03X1134277Y1216141I-1J1202D01*
G01X1134325Y1216150D01*
X1134420Y1216121D01*
X1134724Y1215817D01*
X1134753Y1215723D01*
X1134744Y1215674D01*
G03X1134723Y1215452I1181J-224D01*
G03X1135925Y1216654I1202J0D01*
G03X1135702Y1216633I1J-1202D01*
G01X1135654Y1216624D01*
X1135559Y1216653D01*
X1135255Y1216957D01*
X1135226Y1217051D01*
X1135235Y1217100D01*
G03X1135256Y1217322I-1181J224D01*
G03X1135235Y1217544I-1202J-2D01*
G01X1135226Y1217593D01*
X1135255Y1217686D01*
X1135560Y1217991D01*
X1135653Y1218020D01*
X1135702Y1218011D01*
G03X1135924Y1217990I224J1181D01*
G03X1137126Y1219192I0J1202D01*
G01Y1219220D01*
X1137125Y1219261D01*
X1137154Y1219334D01*
X1137311Y1219495D01*
X1137383Y1219569D01*
G02X1137526Y1219629I143J-140D01*
G01X1138063D01*
G02X1138206Y1219569I0J-200D01*
G01X1138435Y1219334D01*
X1138464Y1219261D01*
X1138463Y1219220D01*
Y1219192D01*
G03X1140867I1202J0D01*
G01Y1219220D01*
X1140866Y1219261D01*
X1140895Y1219334D01*
X1141052Y1219495D01*
X1141124Y1219569D01*
G02X1141267Y1219629I143J-140D01*
G01X1141479D01*
G02X1141575Y1219605I1J-200D01*
G01X1141576Y1219604D01*
G03X1141867Y1219460I1828J3328D01*
G01X1141869Y1219459D01*
X1141891Y1219449D01*
G03X1141904Y1219443I1598J3445D01*
G01X1141905D01*
X1141935Y1219430D01*
G03X1142018Y1219396I1481J3497D01*
G01X1142046Y1219385D01*
X1142075Y1219362D01*
G02X1142113Y1219321I-126J-155D01*
G01X1142136Y1219288D01*
X1142159Y1219256D01*
X1142177Y1219200D01*
X1142178Y1219169D01*
G03X1143405Y1217965I1227J23D01*
G03X1144632Y1219167I0J1227D01*
G02X1144666Y1219275I200J-4D01*
G01X1144699Y1219323D01*
G02X1144744Y1219370I165J-113D01*
G01X1144767Y1219388D01*
X1144793Y1219398D01*
G03X1145200Y1219586I-1386J3535D01*
G01X1145202Y1219587D01*
X1145218Y1219595D01*
X1145250Y1219608D01*
G02X1145276Y1219616I72J-187D01*
G01X1145303Y1219623D01*
G02X1145352Y1219629I49J-194D01*
G01X1149283D01*
G02X1149426Y1219569I0J-200D01*
G01X1149655Y1219334D01*
X1149684Y1219261D01*
X1149683Y1219220D01*
Y1219192D01*
G03X1150885Y1217990I1202J0D01*
G03X1151107Y1218011I-2J1202D01*
G01X1151156Y1218020D01*
X1151249Y1217991D01*
X1151554Y1217686D01*
X1151583Y1217593D01*
X1151574Y1217544D01*
G03X1151553Y1217322I1181J-224D01*
G03X1151574Y1217100I1202J2D01*
G01X1151583Y1217051D01*
X1151554Y1216958D01*
X1151249Y1216653D01*
X1151156Y1216624D01*
X1151107Y1216633D01*
G03X1150885Y1216654I-224J-1181D01*
G03X1152087Y1215452I0J-1202D01*
G03X1152066Y1215674I-1202J-2D01*
G01X1152057Y1215723D01*
X1152086Y1215816D01*
X1152391Y1216121D01*
X1152484Y1216150D01*
X1152533Y1216141D01*
G03X1152755Y1216120I224J1181D01*
G03X1152977Y1216141I-2J1202D01*
G01X1153026Y1216150D01*
X1153119Y1216121D01*
X1153424Y1215816D01*
X1153453Y1215723D01*
X1153444Y1215674D01*
G03X1153423Y1215452I1181J-224D01*
G03X1155827I1202J0D01*
G03X1155806Y1215674I-1202J-2D01*
G01X1155797Y1215723D01*
X1155826Y1215816D01*
X1156131Y1216121D01*
X1156224Y1216150D01*
X1156273Y1216141D01*
G03X1156495Y1216120I224J1181D01*
G03X1156717Y1216141I-2J1202D01*
G01X1156766Y1216150D01*
X1156859Y1216121D01*
X1157164Y1215816D01*
X1157193Y1215723D01*
X1157184Y1215674D01*
G03X1157163Y1215452I1181J-224D01*
G03X1158365Y1216654I1202J0D01*
G03X1158143Y1216633I2J-1202D01*
G01X1158094Y1216624D01*
X1158001Y1216653D01*
X1157696Y1216958D01*
X1157667Y1217051D01*
X1157676Y1217100D01*
G03X1157697Y1217322I-1181J224D01*
G03X1157676Y1217544I-1202J-2D01*
G01X1157667Y1217593D01*
X1157696Y1217686D01*
X1158001Y1217991D01*
X1158094Y1218020D01*
X1158143Y1218011D01*
G03X1158365Y1217990I224J1181D01*
G03X1159567Y1219192I0J1202D01*
G01Y1219220D01*
X1159566Y1219261D01*
X1159595Y1219334D01*
X1159752Y1219495D01*
X1159824Y1219569D01*
G02X1159967Y1219629I143J-140D01*
G01X1160179D01*
G02X1160228Y1219623I0J-200D01*
G01X1160256Y1219616D01*
X1160279Y1219603D01*
G03X1160719Y1219397I1827J3329D01*
G01X1160747Y1219386D01*
X1160792Y1219350D01*
X1160868Y1219241D01*
G02X1160893Y1219192I-164J-115D01*
G01X1160903Y1219164D01*
X1160904Y1219136D01*
G03X1163306Y1219134I1201J57D01*
G01X1163307Y1219163D01*
X1163316Y1219190D01*
X1163325Y1219218D01*
X1163406Y1219335D01*
X1163427Y1219354D01*
G03X1163429Y1219356I-140J142D01*
G02X1163494Y1219397I137J-145D01*
G03X1163930Y1219602I-1394J3532D01*
G01X1163957Y1219616D01*
X1163980Y1219622D01*
G02X1164032Y1219629I52J-193D01*
G01X1164244D01*
G02X1164387Y1219569I0J-200D01*
G01X1164616Y1219334D01*
X1164645Y1219261D01*
X1164644Y1219220D01*
Y1219192D01*
G03X1167048I1202J0D01*
G01Y1219220D01*
X1167047Y1219261D01*
X1167076Y1219334D01*
X1167233Y1219495D01*
X1167305Y1219569D01*
G02X1167448Y1219629I143J-140D01*
G01X1167661D01*
G02X1167757Y1219605I1J-200D01*
G01X1167758Y1219604D01*
G03X1168093Y1219441I1827J3328D01*
G01X1168109Y1219435D01*
X1168124Y1219428D01*
X1168126Y1219427D01*
G03X1168138Y1219422I1465J3498D01*
G03X1168144Y1219420I66J189D01*
G03X1168151Y1219417I1499J3488D01*
G01X1168155D01*
X1168196Y1219399D01*
G02X1168206Y1219395I-69J-188D01*
G01X1168218Y1219389D01*
G02X1168270Y1219351I-91J-178D01*
G01X1168289Y1219332D01*
X1168344Y1219249D01*
X1168382Y1219192D01*
X1168385Y1219136D01*
G03X1170787I1201J56D01*
G01X1170790Y1219192D01*
X1170873Y1219317D01*
G02X1170898Y1219347I165J-112D01*
G01X1170931Y1219380D01*
X1170969Y1219396D01*
X1170974Y1219398D01*
X1170982Y1219402D01*
G03X1171038Y1219424I-1360J3544D01*
G03X1171415Y1219604I-1445J3511D01*
G01X1171416Y1219605D01*
G02X1171512Y1219629I95J-176D01*
G01X1171724D01*
G02X1171867Y1219569I0J-200D01*
G01X1172096Y1219334D01*
X1172125Y1219261D01*
X1172124Y1219220D01*
Y1219192D01*
G03X1174528I1202J0D01*
G01Y1219220D01*
X1174527Y1219261D01*
X1174556Y1219334D01*
X1174713Y1219495D01*
X1174785Y1219569D01*
G02X1174928Y1219629I143J-140D01*
G01X1175141D01*
G02X1175237Y1219605I1J-200D01*
G01X1175238Y1219604D01*
G03X1175573Y1219441I1827J3328D01*
G01X1175589Y1219435D01*
X1175604Y1219428D01*
X1175606Y1219427D01*
G03X1175618Y1219422I1465J3498D01*
G03X1175624Y1219420I66J189D01*
G03X1175631Y1219417I1499J3488D01*
G01X1175635D01*
X1175676Y1219399D01*
G02X1175686Y1219395I-69J-188D01*
G01X1175698Y1219389D01*
G02X1175750Y1219351I-91J-178D01*
G01X1175769Y1219332D01*
X1175824Y1219249D01*
X1175862Y1219192D01*
X1175865Y1219136D01*
G03X1178267I1201J56D01*
G01X1178270Y1219192D01*
X1178353Y1219317D01*
G02X1178378Y1219347I165J-112D01*
G01X1178411Y1219380D01*
X1178449Y1219396D01*
X1178454Y1219398D01*
X1178462Y1219402D01*
G03X1178518Y1219424I-1360J3544D01*
G03X1178895Y1219604I-1445J3511D01*
G01X1178896Y1219605D01*
G02X1178992Y1219629I95J-176D01*
G01X1179204D01*
G02X1179347Y1219569I0J-200D01*
G01X1179576Y1219334D01*
X1179605Y1219261D01*
X1179604Y1219220D01*
Y1219192D01*
G03X1182008I1202J0D01*
G01Y1219220D01*
X1182007Y1219261D01*
X1182036Y1219334D01*
X1182193Y1219495D01*
X1182265Y1219569D01*
G02X1182408Y1219629I143J-140D01*
G01X1182621D01*
G02X1182717Y1219605I1J-200D01*
G01X1182718Y1219604D01*
G03X1183009Y1219460I1828J3328D01*
G01X1183011Y1219459D01*
X1183033Y1219449D01*
G03X1183046Y1219443I1598J3445D01*
G01X1183047D01*
X1183077Y1219430D01*
G03X1183160Y1219396I1481J3497D01*
G01X1183188Y1219385D01*
X1183217Y1219362D01*
G02X1183255Y1219321I-126J-155D01*
G01X1183278Y1219288D01*
X1183301Y1219256D01*
X1183319Y1219200D01*
X1183320Y1219169D01*
G03X1184547Y1217965I1227J23D01*
G03X1185774Y1219166I0J1227D01*
G01X1185775Y1219196D01*
X1185792Y1219251D01*
X1185860Y1219350D01*
X1185907Y1219387D01*
X1185935Y1219398D01*
G03X1186063Y1219451I-1389J3534D01*
G03X1186378Y1219605I-1509J3485D01*
G01X1186401Y1219617D01*
X1186448Y1219629D01*
X1186685D01*
G02X1186828Y1219569I0J-200D01*
G01X1187057Y1219334D01*
X1187086Y1219261D01*
X1187085Y1219220D01*
Y1219192D01*
G03X1189489I1202J0D01*
G01Y1219220D01*
X1189488Y1219261D01*
X1189517Y1219334D01*
X1189674Y1219495D01*
X1189746Y1219569D01*
G02X1189889Y1219629I143J-140D01*
G01X1190102D01*
G02X1190198Y1219605I1J-200D01*
G01X1190199Y1219604D01*
G03X1190534Y1219441I1827J3328D01*
G01X1190550Y1219435D01*
X1190565Y1219428D01*
X1190567Y1219427D01*
G03X1190579Y1219422I1465J3498D01*
G03X1190585Y1219420I66J189D01*
G03X1190592Y1219417I1499J3488D01*
G01X1190596D01*
X1190637Y1219399D01*
G02X1190647Y1219395I-69J-188D01*
G01X1190659Y1219389D01*
G02X1190711Y1219351I-91J-178D01*
G01X1190730Y1219332D01*
X1190785Y1219249D01*
X1190823Y1219192D01*
X1190826Y1219136D01*
G03X1193228I1201J56D01*
G01X1193231Y1219192D01*
X1193314Y1219317D01*
G02X1193339Y1219347I165J-112D01*
G01X1193372Y1219380D01*
X1193410Y1219396D01*
X1193415Y1219398D01*
X1193423Y1219402D01*
G03X1193479Y1219424I-1360J3544D01*
G03X1193856Y1219604I-1445J3511D01*
G01X1193857Y1219605D01*
G02X1193953Y1219629I95J-176D01*
G01X1194165D01*
G02X1194308Y1219569I0J-200D01*
G01X1194537Y1219334D01*
X1194566Y1219261D01*
X1194565Y1219220D01*
Y1219192D01*
G03X1196969I1202J0D01*
G01Y1219220D01*
X1196968Y1219261D01*
X1196997Y1219334D01*
X1197154Y1219495D01*
X1197226Y1219569D01*
G02X1197369Y1219629I143J-140D01*
G01X1197582D01*
G02X1197678Y1219605I1J-200D01*
G01X1197679Y1219604D01*
G03X1198014Y1219441I1827J3328D01*
G01X1198030Y1219435D01*
X1198045Y1219428D01*
X1198047Y1219427D01*
G03X1198059Y1219422I1465J3498D01*
G03X1198065Y1219420I66J189D01*
G03X1198072Y1219417I1499J3488D01*
G01X1198076D01*
X1198117Y1219399D01*
G02X1198127Y1219395I-69J-188D01*
G01X1198139Y1219389D01*
G02X1198191Y1219351I-91J-178D01*
G01X1198210Y1219332D01*
X1198265Y1219249D01*
X1198303Y1219192D01*
X1198306Y1219136D01*
G03X1200708I1201J56D01*
G01X1200711Y1219192D01*
X1200794Y1219317D01*
G02X1200819Y1219347I165J-112D01*
G01X1200852Y1219380D01*
X1200890Y1219396D01*
X1200895Y1219398D01*
X1200903Y1219402D01*
G03X1200959Y1219424I-1360J3544D01*
G03X1201335Y1219604I-1449J3509D01*
G01X1201381Y1219629D01*
X1201435D01*
X1201471Y1219644D01*
G03X1201536Y1219687I-76J185D01*
G01X1201620Y1219771D01*
G02X1201635Y1219784I138J-144D01*
G01X1201647Y1219794D01*
G02X1201715Y1219831I128J-154D01*
G01X1201737Y1219838D01*
G02X1201932Y1219794I59J-191D01*
G01X1201971Y1219758D01*
X1202003Y1219657D01*
X1201987Y1219585D01*
X1201985Y1219578D01*
G03X1201927Y1219192I1262J-387D01*
G03X1203247Y1217872I1320J0D01*
G03X1203460Y1217889I2J1320D01*
G01X1203506Y1217897D01*
X1203595Y1217869D01*
X1203895Y1217586D01*
X1203927Y1217498D01*
X1203922Y1217451D01*
G03X1203915Y1217322I1195J-130D01*
G03X1205117Y1218524I1202J0D01*
G03X1204988Y1218517I1J-1202D01*
G01X1204941Y1218512D01*
X1204853Y1218544D01*
X1204570Y1218844D01*
X1204542Y1218933D01*
X1204550Y1218979D01*
G03X1204567Y1219192I-1303J211D01*
G03X1204550Y1219405I-1320J2D01*
G01X1204542Y1219451D01*
X1204570Y1219540D01*
X1204853Y1219840D01*
X1204941Y1219872D01*
X1204988Y1219867D01*
G03X1205117Y1219860I130J1195D01*
G03X1206319Y1221062I0J1202D01*
G03X1206310Y1221206I-1202J-3D01*
G01X1206305Y1221253D01*
X1206336Y1221341D01*
X1206637Y1221628D01*
X1206726Y1221656D01*
X1206773Y1221648D01*
G03X1206988Y1221630I216J1284D01*
G03X1207202Y1221648I-2J1302D01*
G01X1207249Y1221656D01*
X1207338Y1221628D01*
X1207639Y1221341D01*
X1207670Y1221253D01*
X1207665Y1221205D01*
G03X1207656Y1221062I1193J-147D01*
G03X1208858Y1222264I1202J0D01*
G03X1208715Y1222255I4J-1202D01*
G01X1208667Y1222250D01*
X1208579Y1222281D01*
X1208292Y1222582D01*
X1208264Y1222671D01*
X1208272Y1222718D01*
G03X1208290Y1222932I-1284J216D01*
G01Y1223210D01*
G02X1208356Y1223359I200J0D01*
G01X1208609Y1223586D01*
X1208689Y1223612D01*
X1208732Y1223608D01*
G03X1208858Y1223601I130J1195D01*
G03Y1226005I0J1202D01*
G03X1208732Y1225998I4J-1202D01*
G01X1208689Y1225994D01*
X1208609Y1226020D01*
X1208356Y1226247D01*
G02X1208290Y1226396I134J149D01*
G01Y1226672D01*
G03X1208272Y1226887I-1302J-1D01*
G01X1208264Y1226934D01*
X1208292Y1227023D01*
X1208579Y1227324D01*
X1208667Y1227355D01*
X1208714Y1227350D01*
G03X1208858Y1227341I147J1193D01*
G03Y1229745I0J1202D01*
G03X1208635Y1229724I1J-1202D01*
G01X1208587Y1229715D01*
X1208492Y1229744D01*
X1208188Y1230048D01*
X1208159Y1230142D01*
X1208168Y1230191D01*
G03X1208189Y1230413I-1181J224D01*
G03X1208168Y1230635I-1202J-2D01*
G01X1208159Y1230684D01*
X1208188Y1230778D01*
X1208492Y1231082D01*
X1208587Y1231111D01*
X1208635Y1231102D01*
G03X1208858Y1231081I224J1181D01*
G03Y1233485I0J1202D01*
G03X1208635Y1233464I1J-1202D01*
G01X1208587Y1233455D01*
X1208492Y1233484D01*
X1208188Y1233788D01*
X1208159Y1233882D01*
X1208168Y1233931D01*
G03X1208189Y1234153I-1181J224D01*
G03X1208168Y1234375I-1203J-2D01*
G01X1208159Y1234424D01*
X1208188Y1234518D01*
X1208492Y1234822D01*
X1208587Y1234851D01*
X1208635Y1234842D01*
G03X1208858Y1234821I224J1181D01*
G03Y1237225I0J1202D01*
G03X1208635Y1237204I1J-1202D01*
G01X1208587Y1237195D01*
X1208492Y1237224D01*
X1208188Y1237528D01*
X1208159Y1237622D01*
X1208168Y1237671D01*
G03X1208189Y1237893I-1180J224D01*
G01Y1237901D01*
G03X1208175Y1238076I-1202J-8D01*
G01Y1238077D01*
X1208174Y1238084D01*
X1208170Y1238105D01*
X1208169Y1238117D01*
X1208160Y1238164D01*
X1208189Y1238257D01*
X1208494Y1238562D01*
X1208587Y1238591D01*
X1208636Y1238582D01*
G03X1208858Y1238561I224J1181D01*
G03Y1240965I0J1202D01*
G03X1208643Y1240946I-2J-1202D01*
G01X1208594Y1240937D01*
X1208501Y1240966D01*
X1208198Y1241270D01*
X1208169Y1241363D01*
X1208178Y1241412D01*
G03X1208196Y1241559I-1182J219D01*
G03X1208177Y1241853I-1200J70D01*
G01X1208168Y1241903D01*
X1208197Y1241996D01*
X1208500Y1242300D01*
X1208593Y1242330D01*
X1208642Y1242321D01*
G03X1208858Y1242301I218J1182D01*
G03Y1244705I0J1202D01*
G03X1208715Y1244696I4J-1202D01*
G01X1208667Y1244691D01*
X1208579Y1244722D01*
X1208292Y1245023D01*
X1208265Y1245112D01*
X1208272Y1245159D01*
G03X1208290Y1245371I-1284J216D01*
G01Y1245650D01*
G02X1208356Y1245799I200J0D01*
G01X1208609Y1246026D01*
X1208689Y1246052D01*
X1208732Y1246048D01*
G03X1208858Y1246041I130J1195D01*
G03Y1248445I0J1202D01*
G03X1208733Y1248438I5J-1202D01*
G01X1208690Y1248434D01*
X1208610Y1248460D01*
X1208357Y1248688D01*
G02X1208291Y1248836I134J148D01*
G01Y1249113D01*
G03X1208273Y1249328I-1303J-1D01*
G01X1208265Y1249375D01*
X1208293Y1249464D01*
X1208580Y1249765D01*
X1208668Y1249796D01*
X1208715Y1249791D01*
G03X1208858Y1249782I147J1193D01*
G03X1210060Y1250984I0J1202D01*
G03X1210051Y1251127I-1202J-4D01*
G01X1210046Y1251175D01*
X1210077Y1251263D01*
X1210378Y1251550D01*
X1210467Y1251578D01*
X1210514Y1251570D01*
G03X1210728Y1251552I216J1284D01*
G03X1210942Y1251570I-2J1302D01*
G01X1210989Y1251578D01*
X1211078Y1251550D01*
X1211379Y1251263D01*
X1211410Y1251175D01*
X1211405Y1251127D01*
G03X1211396Y1250984I1193J-147D01*
G03X1213800I1202J0D01*
G03X1213779Y1251206I-1202J-2D01*
G01X1213770Y1251255D01*
X1213799Y1251348D01*
X1214104Y1251653D01*
X1214197Y1251682D01*
X1214246Y1251673D01*
G03X1214690I222J1181D01*
G01X1214739Y1251682D01*
X1214832Y1251653D01*
X1215137Y1251348D01*
X1215166Y1251255D01*
X1215157Y1251206D01*
G03X1215136Y1250984I1181J-224D01*
G03X1217540I1202J0D01*
G03X1217531Y1251127I-1202J-4D01*
G01X1217526Y1251175D01*
X1217557Y1251263D01*
X1217858Y1251550D01*
X1217947Y1251578D01*
X1217994Y1251570D01*
G03X1218208Y1251552I216J1284D01*
G03X1218422Y1251570I-2J1302D01*
G01X1218469Y1251578D01*
X1218558Y1251550D01*
X1218859Y1251263D01*
X1218890Y1251175D01*
X1218885Y1251127D01*
G03X1218876Y1250984I1193J-147D01*
G03X1221280I1202J0D01*
G03X1221259Y1251206I-1202J-2D01*
G01X1221250Y1251255D01*
X1221279Y1251348D01*
X1221584Y1251653D01*
X1221677Y1251682D01*
X1221726Y1251673D01*
G03X1222170I222J1181D01*
G01X1222219Y1251682D01*
X1222312Y1251653D01*
X1222617Y1251348D01*
X1222646Y1251255D01*
X1222637Y1251206D01*
G03X1222616Y1250984I1181J-224D01*
G03X1225020I1202J0D01*
G03X1225011Y1251127I-1202J-4D01*
G01X1225006Y1251175D01*
X1225037Y1251263D01*
X1225338Y1251550D01*
X1225427Y1251578D01*
X1225474Y1251570D01*
G03X1225688Y1251552I216J1284D01*
G03X1225902Y1251570I-2J1302D01*
G01X1225949Y1251578D01*
X1226038Y1251550D01*
X1226339Y1251263D01*
X1226370Y1251175D01*
X1226365Y1251127D01*
G03X1226356Y1250984I1193J-147D01*
G03X1228760I1202J0D01*
G03X1228739Y1251206I-1202J-2D01*
G01X1228730Y1251255D01*
X1228759Y1251348D01*
X1229064Y1251653D01*
X1229157Y1251682D01*
X1229206Y1251673D01*
G03X1229650I222J1181D01*
G01X1229699Y1251682D01*
X1229792Y1251653D01*
X1230097Y1251348D01*
X1230126Y1251255D01*
X1230117Y1251206D01*
G03X1230096Y1250984I1181J-224D01*
G03X1232500I1202J0D01*
G03X1232491Y1251127I-1202J-4D01*
G01X1232486Y1251175D01*
X1232517Y1251263D01*
X1232818Y1251550D01*
X1232907Y1251578D01*
X1232954Y1251570D01*
G03X1233168Y1251552I216J1284D01*
G03X1233383Y1251570I-1J1302D01*
G01X1233430Y1251578D01*
X1233519Y1251550D01*
X1233820Y1251263D01*
X1233851Y1251175D01*
X1233846Y1251128D01*
G03X1233837Y1250984I1193J-147D01*
G03X1236241I1202J0D01*
G03X1236220Y1251206I-1202J-2D01*
G01X1236211Y1251255D01*
X1236240Y1251348D01*
X1236545Y1251653D01*
X1236638Y1251682D01*
X1236687Y1251673D01*
G03X1237131I222J1181D01*
G01X1237180Y1251682D01*
X1237273Y1251653D01*
X1237578Y1251348D01*
X1237607Y1251255D01*
X1237598Y1251206D01*
G03X1237577Y1250984I1181J-224D01*
G03X1239981I1202J0D01*
G03X1239972Y1251128I-1202J-3D01*
G01X1239967Y1251175D01*
X1239998Y1251263D01*
X1240299Y1251550D01*
X1240388Y1251578D01*
X1240435Y1251570D01*
G03X1241951Y1252794I215J1284D01*
G01Y1252795D01*
G02X1242012Y1252929I200J-10D01*
G01X1242191Y1253101D01*
G02X1242193Y1253103I142J-140D01*
G01X1242214Y1253122D01*
G02X1242350Y1253176I137J-146D01*
G37*
G36*
G01X1120775Y1642431D02*
X1232376D01*
G02X1232574Y1642255I0J-199D01*
G01Y1449385D01*
G02X1232515Y1449243I-200J0D01*
G01X1226559Y1443287D01*
X1226531Y1443258D01*
X1226457Y1443228D01*
X1209455D01*
G02X1209313Y1443287I0J200D01*
G01X1207096Y1445504D01*
G02X1207037Y1445646I141J142D01*
G01Y1577654D01*
G03X1206978Y1577796I-200J0D01*
G01X1203098Y1581676D01*
G02X1203066Y1581717I140J143D01*
G01X1203025Y1581787D01*
X1203019Y1581821D01*
G03X1201486Y1583338I-1878J-364D01*
G01X1201455Y1583344D01*
X1201403Y1583371D01*
X1198313Y1586461D01*
G03X1198171Y1586520I-142J-141D01*
G01X1198040D01*
X1198023Y1586523D01*
X1197964Y1586533D01*
X1197934Y1586549D01*
X1197910Y1586562D01*
X1197889Y1586582D01*
X1197888Y1586583D01*
G03X1196077Y1587596I-2754J-2799D01*
G01X1196036Y1587606D01*
X1195908Y1587704D01*
X1195887Y1587739D01*
G03X1192480Y1589715I-3407J-1949D01*
G01X1192479D01*
X1192425Y1589714D01*
G03X1191330Y1589542I56J-3926D01*
G03X1190920Y1589393I1134J-3760D01*
G01X1190902Y1589385D01*
X1190860Y1589376D01*
G02X1190785Y1589375I-40J196D01*
G01X1190760Y1589379D01*
X1190745Y1589384D01*
G03X1190278Y1589462I-478J-1424D01*
G01X1190259D01*
G03X1188765Y1587960I8J-1502D01*
G01Y1587958D01*
G03X1188851Y1587459I1502J2D01*
G01X1188862Y1587427D01*
Y1587335D01*
X1188854Y1587296D01*
X1188841Y1587261D01*
X1188840Y1587257D01*
G03X1188655Y1586675I3638J-1477D01*
G01X1188639Y1586607D01*
X1188530Y1586520D01*
X1180749D01*
G02X1180671Y1586536I0J200D01*
G01X1180569Y1586579D01*
X1180542Y1586605D01*
G03X1178754Y1587596I-2732J-2821D01*
G01X1178713Y1587606D01*
X1178585Y1587704D01*
X1178564Y1587739D01*
G03X1175157Y1589715I-3407J-1949D01*
G01X1175156D01*
X1175102Y1589714D01*
G03X1174007Y1589542I56J-3926D01*
G03X1173597Y1589393I1134J-3760D01*
G01X1173579Y1589385D01*
X1173537Y1589376D01*
G02X1173462Y1589375I-40J196D01*
G01X1173437Y1589379D01*
X1173422Y1589384D01*
G03X1172955Y1589462I-478J-1424D01*
G01X1172936D01*
G03X1171442Y1587960I8J-1502D01*
G01Y1587958D01*
G03X1171528Y1587459I1502J2D01*
G01X1171539Y1587427D01*
Y1587335D01*
X1171531Y1587296D01*
X1171518Y1587261D01*
X1171517Y1587257D01*
G03X1171332Y1586675I3638J-1477D01*
G01X1171316Y1586607D01*
X1171207Y1586520D01*
X1163426D01*
G02X1163348Y1586536I0J200D01*
G01X1163246Y1586579D01*
X1163219Y1586605D01*
G03X1161431Y1587596I-2732J-2821D01*
G01X1161390Y1587606D01*
X1161262Y1587704D01*
X1161241Y1587739D01*
G03X1157834Y1589715I-3407J-1949D01*
G01X1157833D01*
X1157779Y1589714D01*
G03X1156684Y1589542I56J-3926D01*
G03X1156274Y1589393I1134J-3760D01*
G01X1156256Y1589385D01*
X1156214Y1589376D01*
G02X1156139Y1589375I-40J196D01*
G01X1156114Y1589379D01*
X1156099Y1589384D01*
G03X1155632Y1589462I-478J-1424D01*
G01X1155613D01*
G03X1154119Y1587960I8J-1502D01*
G01Y1587958D01*
G03X1154205Y1587459I1502J2D01*
G01X1154216Y1587427D01*
Y1587335D01*
X1154208Y1587296D01*
X1154195Y1587261D01*
X1154194Y1587257D01*
G03X1154009Y1586675I3638J-1477D01*
G01X1153993Y1586607D01*
X1153884Y1586520D01*
X1146103D01*
G02X1146025Y1586536I0J200D01*
G01X1145923Y1586579D01*
X1145896Y1586605D01*
G03X1144108Y1587596I-2732J-2821D01*
G01X1144067Y1587606D01*
X1143939Y1587704D01*
X1143918Y1587739D01*
G03X1140511Y1589715I-3407J-1949D01*
G01X1140510D01*
X1140456Y1589714D01*
G03X1139361Y1589542I56J-3926D01*
G03X1138951Y1589393I1134J-3760D01*
G01X1138933Y1589385D01*
X1138891Y1589376D01*
G02X1138816Y1589375I-40J196D01*
G01X1138791Y1589379D01*
X1138776Y1589384D01*
G03X1138309Y1589462I-478J-1424D01*
G01X1138290D01*
G03X1136796Y1587960I8J-1502D01*
G01Y1587958D01*
G03X1136882Y1587459I1502J2D01*
G01X1136893Y1587427D01*
Y1587335D01*
X1136885Y1587296D01*
X1136872Y1587261D01*
X1136871Y1587257D01*
G03X1136686Y1586675I3638J-1477D01*
G01X1136670Y1586607D01*
X1136561Y1586520D01*
X1123097D01*
X1123023Y1586550D01*
X1122995Y1586579D01*
X1115431Y1594143D01*
X1115402Y1594171D01*
X1115372Y1594245D01*
Y1637028D01*
G02X1115429Y1637168I200J0D01*
G01X1115430Y1637169D01*
X1120633Y1642372D01*
G02X1120635Y1642374I142J-140D01*
G02X1120775Y1642431I140J-143D01*
G37*
G36*
G01X1288127Y1021667D02*
X1284426Y1017965D01*
G02X1284284Y1017906I-142J141D01*
G01X1247798D01*
G03X1246876Y1017524I1J-1306D01*
G01X1246831Y1017479D01*
G02X1246689Y1017420I-142J141D01*
G01X1246297D01*
G03X1245401Y1017049I0J-1267D01*
G01X1244966Y1016613D01*
G02X1244924Y1016581I-141J142D01*
G01X1244902Y1016568D01*
X1244875Y1016561D01*
G03X1243749Y1015107I376J-1454D01*
G03X1245028Y1013621I1503J0D01*
G02X1245116Y1013585I-29J-197D01*
G03X1246000Y1013298I883J1215D01*
G03X1247082Y1013758I0J1503D01*
G01X1247119Y1013797D01*
X1247222Y1013827D01*
X1247611Y1013729D01*
G02X1247755Y1013590I-48J-194D01*
G03X1249200Y1012498I1445J410D01*
G03X1249333Y1012504I-1J1502D01*
G02X1249469Y1012465I16J-199D01*
G03X1250815Y1012022I1346J1823D01*
G01X1252069D01*
X1252087Y1012019D01*
G03X1252497Y1011982I411J2269D01*
G01X1286089D01*
G03X1287719Y1012657I0J2306D01*
G01X1287788Y1012726D01*
G02X1288005Y1012769I141J-142D01*
G01X1288115Y1012724D01*
X1288129Y1012703D01*
Y990334D01*
G02X1288107Y990243I-200J0D01*
G02X1288071Y990193I-178J90D01*
G01X1264752Y966874D01*
G03X1264693Y966732I141J-142D01*
G01Y887914D01*
G02X1264691Y887886I-200J0D01*
G01X1260366Y883561D01*
G03X1259984Y882639I924J-923D01*
G01Y751691D01*
G03X1260038Y751320I1306J1D01*
G01X1260046Y751292D01*
Y751271D01*
X1260076Y751198D01*
X1260083Y751191D01*
X1260098Y751158D01*
G03X1260366Y750768I1193J533D01*
G01X1275737Y735397D01*
G02X1275796Y735255I-141J-142D01*
G01Y698783D01*
G02X1275737Y698641I-200J0D01*
G01X1267361Y690265D01*
G03X1266978Y689341I923J-924D01*
G01Y543619D01*
G02X1266919Y543477I-200J0D01*
G01X1249641Y526199D01*
G03X1249258Y525275I923J-924D01*
G01Y473522D01*
G02X1249199Y473380I-200J0D01*
G01X1248230Y472411D01*
G03X1247848Y471489I924J-923D01*
G01Y432431D01*
G02X1247789Y432289I-200J0D01*
G01X1246630Y431130D01*
G02X1246488Y431071I-142J141D01*
G01X1238774D01*
G02X1238578Y431232I0J200D01*
G01X1232936Y459669D01*
G02X1232932Y459705I196J40D01*
G01X1232872Y464871D01*
G02X1233025Y465068I200J3D01*
G03X1233935Y465718I-355J1460D01*
G02X1233952Y465741I169J-107D01*
G02X1234210Y465779I151J-131D01*
G03X1235166Y465504I957J1527D01*
G03X1236968Y467306I0J1802D01*
G01Y470706D01*
G03X1235166Y472508I-1802J0D01*
G03X1234210Y472233I1J-1802D01*
G02X1233957Y472266I-107J169D01*
G02X1233935Y472294I146J137D01*
G03X1232940Y472961I-1264J-811D01*
G02X1232776Y473156I36J197D01*
G01X1232709Y479013D01*
G02X1232881Y479213I200J2D01*
G03X1233935Y479891I-212J1487D01*
G02X1233952Y479914I169J-107D01*
G02X1234210Y479952I151J-131D01*
G03X1235166Y479677I957J1527D01*
G03X1236968Y481479I0J1802D01*
G01Y484879D01*
G03X1233364I-1802J0D01*
G01Y482330D01*
G02X1233363Y482308I-200J-2D01*
G02X1233120Y482134I-199J21D01*
G02X1233106Y482138I48J194D01*
G03X1232846Y482193I-440J-1436D01*
G02X1232670Y482389I24J198D01*
G01X1232034Y537451D01*
G02X1232108Y537608I200J2D01*
G01X1232350Y537805D01*
G02X1232518Y537846I127J-155D01*
G03X1232828Y537813I313J1469D01*
G01X1232857D01*
G03X1234335Y539315I-24J1502D01*
G03X1232833Y540817I-1502J0D01*
G01X1232832D01*
G03X1232484Y540776I1J-1502D01*
G01X1232483D01*
G02X1232315Y540813I-45J195D01*
G01X1232068Y541005D01*
G02X1231991Y541160I123J158D01*
G01X1231909Y548237D01*
G02X1231961Y548374I200J2D01*
G01X1232169Y548604D01*
X1232238Y548637D01*
X1232276Y548640D01*
G03X1233255Y549121I-128J1497D01*
G02X1233354Y549176I143J-140D01*
G02X1233398Y549181I44J-195D01*
G01X1233693D01*
X1233694D01*
X1233695D01*
G02X1233840Y549117I-2J-200D01*
G03X1234941Y548635I1102J1019D01*
G03Y551639I0J1502D01*
G03X1233840Y551157I1J-1501D01*
G02X1233695Y551093I-147J136D01*
G01X1233397D01*
X1233395D01*
G02X1233376Y551094I1J200D01*
G02X1233250Y551158I22J199D01*
G03X1233187Y551222I-1101J-1021D01*
G03X1232223Y551637I-1038J-1084D01*
G01X1232219D01*
X1232202Y551638D01*
X1232134Y551670D01*
X1231920Y551895D01*
G02X1231865Y552031I145J138D01*
G01X1231690Y567202D01*
G03X1231658Y567659I-3926J-45D01*
G01X1226189Y610114D01*
G03X1226163Y610286I-3894J-501D01*
G01X1185683Y842724D01*
X1185700Y842748D01*
X1185857Y842785D01*
G03X1187018Y844248I-341J1463D01*
G03X1185516Y845750I-1502J0D01*
G03X1185348Y845741I-4J-1502D01*
G01X1185185Y845723D01*
X1185157Y845743D01*
X1184504Y849496D01*
X1184521Y849571D01*
X1184522Y849573D01*
X1184676Y849608D01*
G03X1185842Y851072I-336J1464D01*
G03X1184340Y852574I-1502J0D01*
G01X1184339D01*
G03X1184128Y852559I1J-1502D01*
G01X1184124D01*
X1184047Y852550D01*
X1183976Y852567D01*
X1183968Y852573D01*
X1183523Y855125D01*
X1183529Y855135D01*
X1183626Y855183D01*
G02X1183632Y855185I66J-189D01*
G03X1184514Y856553I-620J1368D01*
G03X1183164Y858047I-1502J0D01*
G01X1183162D01*
X1183024Y858062D01*
X1183010Y858074D01*
X1181386Y867403D01*
X1181405Y867483D01*
X1181431Y867516D01*
G03X1181741Y868430I-1192J914D01*
G03X1181728Y868630I-1502J3D01*
G03X1181184Y869598I-1489J-200D01*
G03X1181045Y869697I-940J-1172D01*
G02X1181043Y869699I140J142D01*
G01X1181016Y869716D01*
X1180970Y869785D01*
X1178894Y881707D01*
G02X1178939Y881764I177J-93D01*
G01X1179200Y881989D01*
G02X1179290Y882034I132J-151D01*
G01X1179314Y882039D01*
X1179366Y882035D01*
X1179391Y882027D01*
G03X1179855Y881953I466J1428D01*
G01X1179858D01*
G03X1181360Y883455I0J1502D01*
G03X1180844Y884588I-1502J0D01*
G01X1180814Y884614D01*
X1180797Y884649D01*
G02X1180776Y884729I179J90D01*
G01X1180763Y885018D01*
G02X1180775Y885096I200J9D01*
G01X1180789Y885134D01*
X1180817Y885164D01*
G03X1181229Y886197I-1089J1033D01*
G03X1179727Y887699I-1502J0D01*
G03X1178575Y887161I0J-1502D01*
G01X1178574Y887160D01*
G02X1178482Y887099I-152J130D01*
G01X1178456Y887090D01*
X1178398Y887089D01*
X1178020Y887191D01*
G02X1177930Y887243I52J193D01*
G01X1173499Y912686D01*
G02X1173557Y912806I199J-22D01*
G01X1173826Y913041D01*
G02X1173914Y913086I132J-150D01*
G01X1173963Y913097D01*
X1173987Y913090D01*
X1174014Y913081D01*
G03X1174461Y913013I447J1435D01*
G03Y916017I0J1502D01*
G03X1173559Y915716I0J-1502D01*
G01X1173557Y915715D01*
G02X1173465Y915677I-120J160D01*
G01X1173414Y915670D01*
X1173048Y915815D01*
G02X1172934Y915931I73J186D01*
G01X1172436Y918786D01*
X1153597Y1027694D01*
X1152495Y1034065D01*
X1149872Y1049226D01*
G02X1149927Y1049401I197J34D01*
G01X1149934Y1049408D01*
Y1062722D01*
G02X1149938Y1062760I200J-2D01*
G02X1149991Y1062862I196J-37D01*
G01X1151321Y1064192D01*
G02X1151423Y1064245I139J-143D01*
G02X1151461Y1064249I40J-196D01*
G01X1241271D01*
G02X1241309Y1064245I-2J-200D01*
G02X1241411Y1064192I-37J-196D01*
G01X1258912Y1046691D01*
G03X1259054Y1046632I142J141D01*
G01X1274835D01*
G02X1274879Y1046627I0J-200D01*
G02X1274975Y1046575I-44J-195D01*
G01X1288075Y1033476D01*
G02X1288128Y1033361I-146J-137D01*
G02X1288129Y1033339I-199J-20D01*
G01Y1021695D01*
G02X1288127Y1021667I-200J0D01*
G37*
G36*
G01X1256555Y54588D02*
X1285191D01*
X1285226D01*
X1285275Y54539D01*
Y52675D01*
X1285191Y52591D01*
X1256555D01*
G03X1250618Y46654I0J-5937D01*
G01Y7874D01*
G02X1244744Y2000I-5874J0D01*
G01X1197500D01*
G02X1191626Y7874I0J5874D01*
G01Y46654D01*
G03X1190170Y50549I-5938J0D01*
G01Y50728D01*
X1190174Y50732D01*
X1192419D01*
X1192602Y50549D01*
G02X1193624Y46654I-6911J-3895D01*
G01Y7874D01*
G03X1197500Y3998I3876J0D01*
G01X1244744D01*
G03X1248620Y7874I0J3876D01*
G01Y46654D01*
G02X1256555Y54588I7935J-1D01*
G37*
G36*
G01X1284289Y1039099D02*
X1304020D01*
G02X1304162Y1039040I0J-200D01*
G01X1305212Y1037990D01*
G02X1305270Y1037854I-142J-141D01*
G01X1305273Y1037735D01*
G02X1305227Y1037603I-200J-4D01*
G03X1304883Y1036646I1159J-957D01*
G03X1306385Y1035144I1502J0D01*
G03X1307397Y1035536I0J1502D01*
G01X1307456Y1035590D01*
X1307615Y1035587D01*
X1312753Y1030449D01*
G03X1312895Y1030390I142J141D01*
G01X1344558D01*
G02X1344700Y1030331I0J-200D01*
G01X1345449Y1029582D01*
G02X1345508Y1029440I-141J-142D01*
G01Y1022075D01*
G02X1345449Y1021933I-200J0D01*
G01X1344146Y1020631D01*
G02X1344004Y1020572I-142J141D01*
G01X1311570D01*
G02X1311370Y1020772I0J200D01*
G01Y1021487D01*
G03X1310987Y1022411I-1306J0D01*
G01X1304474Y1028924D01*
G03X1303550Y1029306I-923J-924D01*
G01X1301309D01*
G02X1301168Y1029365I1J200D01*
G01X1299568Y1030965D01*
G03X1299426Y1031024I-142J-141D01*
G01X1289330D01*
G02X1289130Y1031224I0J200D01*
G01Y1033340D01*
G03X1288778Y1034190I-1201J0D01*
G01X1284209Y1038758D01*
G02X1284166Y1038976I142J141D01*
G01X1284189Y1039032D01*
X1284289Y1039099D01*
G37*
G36*
G01X1406555Y54588D02*
X1435515D01*
X1435890Y54213D01*
Y52966D01*
X1435515Y52591D01*
X1406555D01*
G03X1400618Y46654I0J-5937D01*
G01Y7874D01*
G02X1394744Y2000I-5874J0D01*
G01X1299862D01*
G02X1293988Y7874I0J5874D01*
G01Y46654D01*
G03X1292425Y50669I-5938J0D01*
G01Y50696D01*
X1292470Y50741D01*
X1294823D01*
X1294895Y50669D01*
G02X1295986Y46654I-6842J-4015D01*
G01Y7874D01*
G03X1299862Y3998I3876J0D01*
G01X1394744D01*
G03X1398620Y7874I0J3876D01*
G01Y46654D01*
G02X1406555Y54588I7935J-1D01*
G37*
G36*
G01X1306584Y798223D02*
X1300589D01*
G02X1300435Y798295I0J200D01*
G01X1300210Y798567D01*
X1300188Y798652D01*
X1300196Y798697D01*
G03X1300222Y798975I-1476J278D01*
G03X1298720Y800477I-1502J0D01*
G03X1297669Y800048I0J-1502D01*
G01X1296358D01*
X1295366Y801040D01*
Y810752D01*
X1296138Y811524D01*
X1301043D01*
G02X1301172Y811477I0J-200D01*
G03X1302140Y811123I968J1148D01*
G03X1303108Y811477I0J1502D01*
G02X1303237Y811524I129J-153D01*
G01X1303814D01*
X1304005Y811715D01*
Y812679D01*
X1304514Y813188D01*
X1306986D01*
X1308563Y811611D01*
Y810746D01*
Y800119D01*
X1306725Y798281D01*
G02X1306584Y798223I-141J142D01*
G37*
G36*
G01X1448457Y1337209D02*
X1464463D01*
G02X1464605Y1337150I0J-200D01*
G01X1529912Y1271843D01*
G03X1530054Y1271784I142J141D01*
G01X1550472D01*
G02X1550598Y1271739I0J-200D01*
G01X1562769Y1261862D01*
G02X1562784Y1261848I-129J-153D01*
G01X1566311Y1258321D01*
G02X1566370Y1258180I-141J-142D01*
G01Y1253790D01*
G02X1566311Y1253649I-200J1D01*
G01X1564977Y1252315D01*
X1564912Y1252286D01*
X1564875Y1252283D01*
G03X1564300Y1252107I83J-1300D01*
G02X1564199Y1252079I-102J172D01*
G01X1561717D01*
X1561681Y1252094D01*
G03X1560759I-461J-1109D01*
G01X1560723Y1252079D01*
X1558241D01*
G02X1558140Y1252107I1J200D01*
G03X1557480Y1252286I-659J-1123D01*
G03X1556820Y1252107I-1J-1302D01*
G02X1556719Y1252079I-102J172D01*
G01X1554237D01*
X1554201Y1252094D01*
G03X1553279I-461J-1109D01*
G01X1553243Y1252079D01*
X1550761D01*
G02X1550660Y1252107I1J200D01*
G03X1550000Y1252286I-659J-1123D01*
G03X1549340Y1252107I-1J-1302D01*
G02X1549239Y1252079I-102J172D01*
G01X1546756D01*
X1546720Y1252094D01*
G03X1545798I-461J-1109D01*
G01X1545762Y1252079D01*
X1543280D01*
G02X1543179Y1252107I1J200D01*
G03X1542519Y1252286I-659J-1123D01*
G03X1541859Y1252107I-1J-1302D01*
G02X1541758Y1252079I-102J172D01*
G01X1539276D01*
X1539240Y1252094D01*
G03X1538318I-461J-1109D01*
G01X1538282Y1252079D01*
X1535800D01*
G02X1535699Y1252107I1J200D01*
G03X1535039Y1252286I-659J-1123D01*
G03X1534379Y1252107I-1J-1302D01*
G02X1534278Y1252079I-102J172D01*
G01X1531796D01*
X1531760Y1252094D01*
G03X1530838I-461J-1109D01*
G01X1530802Y1252079D01*
X1528320D01*
G02X1528219Y1252107I1J200D01*
G03X1527559Y1252286I-659J-1123D01*
G03X1526899Y1252107I-1J-1302D01*
G02X1526798Y1252079I-102J172D01*
G01X1524316D01*
X1524280Y1252094D01*
G03X1523358I-461J-1109D01*
G01X1523322Y1252079D01*
X1520839D01*
G02X1520738Y1252107I1J200D01*
G03X1520078Y1252286I-659J-1123D01*
G03X1519418Y1252107I-1J-1302D01*
G02X1519317Y1252079I-102J172D01*
G01X1517099D01*
G02X1516998Y1252107I1J200D01*
G03X1516338Y1252286I-659J-1123D01*
G03X1515678Y1252107I-1J-1302D01*
G02X1515577Y1252079I-102J172D01*
G01X1513671D01*
G02X1513529Y1252138I0J200D01*
G01X1511742Y1253925D01*
G03X1511600Y1253984I-142J-141D01*
G01X1504839D01*
G02X1504668Y1254081I0J200D01*
G01X1504464Y1254421D01*
X1504461Y1254525D01*
X1504487Y1254572D01*
G03X1506694Y1263386I-16497J8814D01*
G03X1469288I-18703J0D01*
G03X1471495Y1254572I18704J0D01*
G01X1471521Y1254525D01*
X1471518Y1254421D01*
X1471314Y1254081D01*
G02X1471143Y1253984I-171J103D01*
G01X1466297D01*
G03X1466155Y1253925I0J-200D01*
G01X1466054Y1253824D01*
G02X1465912Y1253765I-142J141D01*
G01X1305063D01*
G02X1304921Y1253824I0J200D01*
G01X1300792Y1257953D01*
G02X1300733Y1258095I141J142D01*
G01Y1281015D01*
G02X1300792Y1281157I200J0D01*
G01X1341794Y1322159D01*
G02X1341936Y1322218I142J-141D01*
G01X1365792D01*
G03X1365934Y1322277I0J200D01*
G01X1380806Y1337149D01*
G02X1380948Y1337208I142J-141D01*
G01X1405662D01*
Y1337209D01*
X1441018D01*
X1441030Y1337208D01*
G03X1441200Y1337198I173J1492D01*
G03X1441370Y1337208I-3J1502D01*
G01X1441382Y1337209D01*
X1445177D01*
G02X1445350Y1337108I-1J-200D01*
G01X1445550Y1336760D01*
X1445549Y1336653D01*
X1445522Y1336607D01*
G03X1445315Y1335846I1295J-761D01*
G03X1448319I1502J0D01*
G03X1448112Y1336607I-1502J0D01*
G01X1448085Y1336653D01*
X1448084Y1336760D01*
X1448284Y1337108D01*
G02X1448457Y1337209I174J-99D01*
G37*
G36*
G01X1372507Y1114632D02*
G03X1371162Y1114075I0J-1902D01*
G01X1370127Y1113039D01*
G02X1369985Y1112980I-142J141D01*
G01X1363830D01*
G03X1362488Y1112424I2J-1902D01*
G01X1356790Y1106725D01*
G02X1356648Y1106666I-142J141D01*
G01X1354856D01*
G02X1354683Y1106765I0J200D01*
G01X1354509Y1107063D01*
G02X1354507Y1107262I172J101D01*
G03X1354699Y1107997I-1311J735D01*
G03X1354331Y1108982I-1502J0D01*
G01X1354306Y1109011D01*
X1354281Y1109081D01*
X1354294Y1109432D01*
X1354325Y1109502D01*
X1354352Y1109528D01*
G03X1354799Y1110597I-1055J1069D01*
G03X1354422Y1111592I-1502J0D01*
G01X1354389Y1111629D01*
X1354366Y1111725D01*
X1354461Y1112095D01*
G02X1354587Y1112234I194J-49D01*
G03X1355584Y1113648I-504J1414D01*
G03X1355511Y1114110I-1502J-1D01*
G01X1355498Y1114151D01*
X1355507Y1114236D01*
X1355705Y1114569D01*
X1355773Y1114618D01*
X1355816Y1114626D01*
G03X1357035Y1116101I-283J1475D01*
G03X1356591Y1117167I-1502J0D01*
G02X1356532Y1117309I141J142D01*
G01Y1117593D01*
G02X1356591Y1117735I200J0D01*
G03X1357035Y1118801I-1058J1066D01*
G03X1354031I-1502J0D01*
G03X1354475Y1117735I1502J0D01*
G02X1354534Y1117593I-141J-142D01*
G01Y1117309D01*
G02X1354475Y1117167I-200J0D01*
G03X1354031Y1116101I1058J-1066D01*
G03X1354104Y1115639I1502J1D01*
G01X1354117Y1115598D01*
X1354108Y1115513D01*
X1353910Y1115180D01*
X1353842Y1115131D01*
X1353799Y1115123D01*
G03X1352607Y1113929I283J-1475D01*
G01X1352597Y1113880D01*
X1352537Y1113804D01*
X1352139Y1113632D01*
X1352042Y1113639D01*
X1352000Y1113666D01*
G03X1351197Y1113899I-803J-1269D01*
G03X1350915Y1113872I2J-1502D01*
G01X1350877Y1113865D01*
X1350802Y1113879D01*
X1350507Y1114068D01*
X1350462Y1114130D01*
X1350453Y1114167D01*
G03X1348997Y1115299I-1456J-370D01*
G03X1347495Y1113797I0J-1502D01*
G03X1348025Y1112652I1502J0D01*
G02X1348096Y1112500I-129J-153D01*
G01Y1112194D01*
G02X1348025Y1112042I-200J1D01*
G03X1347857Y1111875I972J-1145D01*
G02X1347712Y1111805I-152J130D01*
G01X1347419Y1111793D01*
G02X1347270Y1111852I-7J200D01*
G01X1345410Y1113712D01*
G02X1345366Y1113928I142J141D01*
G01X1345503Y1114268D01*
G02X1345684Y1114394I186J-74D01*
G03X1347152Y1115883I-34J1502D01*
G01Y1115897D01*
G03X1346864Y1116781I-1502J0D01*
G01X1346854Y1116795D01*
G02X1346825Y1116903I171J104D01*
G01X1346840Y1117110D01*
G03X1346886Y1117156I-1215J1261D01*
G02X1346888Y1117158I142J-140D01*
G01X1348628Y1118898D01*
G03X1349142Y1120136I-1237J1239D01*
G01Y1124443D01*
X1349148Y1124467D01*
G03X1349202Y1124916I-1848J450D01*
G01Y1128332D01*
G03X1349148Y1128781I-1902J-1D01*
G01X1349142Y1128805D01*
Y1147734D01*
G03X1349155Y1147765I-1748J751D01*
G01X1349633Y1148243D01*
G02X1349735Y1148296I139J-143D01*
G02X1349773Y1148300I40J-196D01*
G01X1410306D01*
G02X1410448Y1148242I1J-200D01*
G01X1410511Y1148179D01*
G02X1410570Y1148037I-141J-142D01*
G01Y1131416D01*
G02X1410486Y1131253I-200J0D01*
G01X1410181Y1131035D01*
X1410086Y1131021D01*
X1410040Y1131037D01*
G03X1409425Y1131140I-617J-1799D01*
G03X1407524Y1129240I0J-1901D01*
G01Y1124331D01*
G02X1407465Y1124189I-200J0D01*
G01X1406044Y1122769D01*
G03X1405488Y1121427I1346J-1344D01*
G01Y1115231D01*
G02X1405429Y1115089I-200J0D01*
G01X1403357Y1113017D01*
G02X1403215Y1112958I-142J141D01*
G01X1396221D01*
G02X1396069Y1113028I0J200D01*
G01X1395871Y1113258D01*
G02X1395825Y1113419I152J130D01*
G03X1395843Y1113648I-1484J232D01*
G03X1394341Y1115150I-1502J0D01*
G03X1393354Y1114780I0J-1501D01*
G01X1393353D01*
Y1114779D01*
G02X1393223Y1114731I-130J152D01*
G01X1392959D01*
G02X1392829Y1114779I0J200D01*
G01X1392828Y1114780D01*
G03X1391841Y1115150I-987J-1131D01*
G03X1390339Y1113648I0J-1502D01*
G03X1391840Y1112146I1502J0D01*
G01X1391842D01*
G03X1391927Y1112149I-10J1502D01*
G01X1391929D01*
X1391991Y1112153D01*
X1392097Y1112089D01*
X1392276Y1111690D01*
G02X1392235Y1111467I-183J-82D01*
G01X1388812Y1108044D01*
G02X1388610Y1107995I-141J141D01*
G01X1388272Y1108101D01*
G02X1388135Y1108258I60J191D01*
G03X1387790Y1108982I-1479J-261D01*
G01X1387765Y1109011D01*
X1387740Y1109081D01*
X1387753Y1109432D01*
X1387784Y1109502D01*
X1387811Y1109528D01*
G03X1388258Y1110597I-1055J1069D01*
G03X1387881Y1111592I-1502J0D01*
G01X1387848Y1111629D01*
X1387825Y1111725D01*
X1387920Y1112095D01*
G02X1388046Y1112234I194J-49D01*
G03X1389043Y1113648I-504J1414D01*
G03X1388970Y1114110I-1502J-1D01*
G01X1388957Y1114151D01*
X1388966Y1114236D01*
X1389164Y1114569D01*
X1389232Y1114618D01*
X1389275Y1114626D01*
G03X1390494Y1116101I-283J1475D01*
G03X1390050Y1117167I-1502J0D01*
G02X1389991Y1117309I141J142D01*
G01Y1117593D01*
G02X1390050Y1117735I200J0D01*
G03X1390494Y1118801I-1058J1066D01*
G03X1387490I-1502J0D01*
G03X1387934Y1117735I1502J0D01*
G02X1387993Y1117593I-141J-142D01*
G01Y1117309D01*
G02X1387934Y1117167I-200J0D01*
G03X1387490Y1116101I1058J-1066D01*
G03X1387563Y1115639I1502J1D01*
G01X1387576Y1115598D01*
X1387567Y1115513D01*
X1387369Y1115180D01*
X1387301Y1115131D01*
X1387258Y1115123D01*
G03X1386066Y1113929I283J-1475D01*
G01X1386056Y1113880D01*
X1385996Y1113804D01*
X1385598Y1113632D01*
X1385501Y1113639D01*
X1385459Y1113666D01*
G03X1384656Y1113899I-803J-1269D01*
G03X1384374Y1113872I2J-1502D01*
G01X1384336Y1113865D01*
X1384261Y1113879D01*
X1383966Y1114068D01*
X1383921Y1114130D01*
X1383912Y1114167D01*
G03X1382456Y1115299I-1456J-370D01*
G03X1380954Y1113797I0J-1502D01*
G03X1381484Y1112652I1502J0D01*
G02X1381555Y1112500I-129J-153D01*
G01Y1112194D01*
G02X1381484Y1112042I-200J1D01*
G03X1380964Y1111073I972J-1145D01*
G01X1380958Y1111016D01*
X1380886Y1110926D01*
X1380491Y1110789D01*
G02X1380284Y1110837I-65J189D01*
G01X1377047Y1114075D01*
G03X1376912Y1114197I-1341J-1348D01*
G02X1376858Y1114265I126J155D01*
G01X1376802Y1114381D01*
G02X1377002Y1114581I200J0D01*
G01X1377071Y1114564D01*
G02X1377112Y1114549I-48J-194D01*
G03X1377777Y1114394I665J1347D01*
G01X1377778D01*
G03X1379280Y1115896I0J1502D01*
G03X1378910Y1116883I-1501J0D01*
G01Y1116884D01*
X1378909D01*
G02X1378861Y1117014I152J130D01*
G01Y1117278D01*
G02X1378909Y1117408I200J0D01*
G01X1378910Y1117409D01*
G03X1379280Y1118396I-1131J987D01*
G03X1376276I-1502J0D01*
G03X1376646Y1117409I1501J0D01*
G01Y1117408D01*
X1376647D01*
G02X1376695Y1117278I-152J-130D01*
G01Y1117014D01*
G02X1376647Y1116884I-200J0D01*
G01X1376646Y1116883D01*
G03X1376593Y1116819I1130J-990D01*
G01X1376576Y1116798D01*
G03X1376276Y1115923I1202J-901D01*
G01Y1115896D01*
G03X1376455Y1115186I1502J1D01*
G01Y1115185D01*
G02X1376441Y1114974I-176J-94D01*
G01X1376195Y1114635D01*
X1376090Y1114593D01*
X1376033Y1114603D01*
G03X1375702Y1114632I-331J-1873D01*
G01X1372507D01*
G37*
G36*
G01X1566997Y1216896D02*
X1566911Y1216811D01*
G02X1566849Y1216769I-141J142D01*
G01X1566816Y1216755D01*
X1566778Y1216753D01*
X1566777D01*
G03X1566744Y1214153I54J-1301D01*
G01X1566778Y1214151D01*
X1566874Y1214109D01*
G02X1566936Y1214068I-77J-184D01*
G01X1566996Y1214009D01*
G02X1567056Y1213866I-140J-143D01*
G01Y1213298D01*
G02X1567013Y1213175I-200J1D01*
G02X1566997Y1213156I-160J119D01*
G01X1566911Y1213071D01*
G02X1566849Y1213029I-141J142D01*
G01X1566816Y1213015D01*
X1566778Y1213013D01*
X1566777D01*
G03X1566744Y1210413I54J-1301D01*
G01X1566778Y1210411D01*
X1566874Y1210369D01*
G02X1566936Y1210328I-77J-184D01*
G01X1566996Y1210269D01*
G02X1567056Y1210126I-140J-143D01*
G01Y1209558D01*
G02X1567013Y1209435I-200J1D01*
G02X1566997Y1209416I-160J119D01*
G01X1566911Y1209331D01*
G02X1566849Y1209289I-141J142D01*
G01X1566816Y1209275D01*
X1566778Y1209273D01*
X1566777D01*
G03X1566744Y1206673I54J-1301D01*
G01X1566778Y1206671D01*
X1566874Y1206629D01*
G02X1566936Y1206588I-77J-184D01*
G01X1566996Y1206529D01*
G02X1567056Y1206386I-140J-143D01*
G01Y1205818D01*
G02X1567013Y1205695I-200J1D01*
G02X1566997Y1205676I-160J119D01*
G01X1566911Y1205591D01*
G02X1566849Y1205549I-141J142D01*
G01X1566816Y1205535D01*
X1566778Y1205533D01*
X1566777D01*
G03X1566744Y1202933I54J-1301D01*
G01X1566778Y1202931D01*
X1566874Y1202889D01*
G02X1566936Y1202848I-77J-184D01*
G01X1566996Y1202789D01*
G02X1567056Y1202646I-140J-143D01*
G01Y1202077D01*
G02X1567013Y1201954I-200J1D01*
G02X1566997Y1201935I-160J119D01*
G01X1566911Y1201850D01*
G02X1566849Y1201808I-141J142D01*
G01X1566816Y1201794D01*
X1566778Y1201792D01*
X1566777D01*
G03X1565528Y1200491I53J-1301D01*
G03X1566830Y1199189I1302J0D01*
G01X1566831D01*
G03X1567640Y1199471I0J1303D01*
G01X1567665Y1199491D01*
X1567755Y1199524D01*
G02X1567760Y1199526I77J-184D01*
G01X1567762D01*
G02X1567800Y1199535I65J-189D01*
G02X1567833Y1199536I23J-199D01*
G01X1567892Y1199533D01*
X1568082Y1199524D01*
G02X1568203Y1199467I-20J-199D01*
G01X1569499Y1198171D01*
G03X1569585Y1198120I142J141D01*
G01X1569611Y1198112D01*
X1569632Y1198099D01*
G02X1569673Y1198065I-106J-169D01*
G01X1569730Y1198005D01*
X1569750Y1197984D01*
X1569778Y1197910D01*
X1569777Y1197870D01*
G02X1569713Y1197730I-200J7D01*
G01X1569701Y1197718D01*
X1569697Y1197715D01*
G03X1569269Y1196751I872J-964D01*
G03X1571873I1302J0D01*
G01Y1196752D01*
G03X1571645Y1197487I-1302J-1D01*
G02X1571622Y1197666I166J112D01*
G01X1571630Y1197686D01*
X1571806Y1198017D01*
G02X1571873Y1198084I171J-104D01*
G01X1571899Y1198100D01*
X1571924Y1198106D01*
X1572954D01*
G02X1573078Y1198014I-48J-194D01*
G02X1573083Y1198005I-172J-101D01*
G01X1573088Y1197996D01*
G02X1573090Y1197991I-185J-77D01*
G01X1573248Y1197693D01*
G02X1573268Y1197562I-176J-94D01*
G01X1573261Y1197524D01*
X1573236Y1197487D01*
G03X1573009Y1196752I1075J-735D01*
G01Y1196751D01*
G03X1575613I1302J0D01*
G01Y1196752D01*
G03X1575385Y1197487I-1302J-1D01*
G02X1575362Y1197666I166J112D01*
G01X1575370Y1197686D01*
X1575546Y1198017D01*
G02X1575613Y1198084I171J-104D01*
G01X1575639Y1198100D01*
X1575664Y1198106D01*
X1576694D01*
G02X1576818Y1198014I-48J-194D01*
G02X1576823Y1198005I-172J-101D01*
G01X1576828Y1197996D01*
G02X1576830Y1197991I-185J-77D01*
G01X1576988Y1197693D01*
G02X1577008Y1197562I-176J-94D01*
G01X1577001Y1197524D01*
X1576976Y1197487D01*
G03X1576749Y1196752I1075J-735D01*
G01Y1196751D01*
G03X1579353I1302J0D01*
G01Y1196752D01*
G03X1579125Y1197487I-1302J-1D01*
G02X1579102Y1197666I166J112D01*
G01X1579110Y1197686D01*
X1579286Y1198017D01*
G02X1579353Y1198084I171J-104D01*
G01X1579379Y1198100D01*
X1579404Y1198106D01*
X1580434D01*
G02X1580558Y1198014I-48J-194D01*
G02X1580563Y1198005I-172J-101D01*
G01X1580568Y1197996D01*
G02X1580570Y1197991I-185J-77D01*
G01X1580728Y1197693D01*
G02X1580748Y1197562I-176J-94D01*
G01X1580741Y1197524D01*
X1580716Y1197487D01*
G03X1580489Y1196752I1075J-735D01*
G01Y1196751D01*
G03X1583093I1302J0D01*
G01Y1196752D01*
G03X1582865Y1197487I-1302J-1D01*
G02X1582842Y1197666I166J112D01*
G01X1582850Y1197686D01*
X1583026Y1198017D01*
G02X1583093Y1198084I171J-104D01*
G01X1583119Y1198100D01*
X1583144Y1198106D01*
X1584174D01*
G02X1584298Y1198014I-48J-194D01*
G02X1584303Y1198005I-172J-101D01*
G01X1584308Y1197996D01*
G02X1584310Y1197991I-185J-77D01*
G01X1584468Y1197693D01*
G02X1584488Y1197562I-176J-94D01*
G01X1584481Y1197524D01*
X1584456Y1197487D01*
G03X1584229Y1196752I1075J-735D01*
G01Y1196751D01*
G03X1586833I1302J0D01*
G01Y1196752D01*
G03X1586605Y1197487I-1302J-1D01*
G02X1586582Y1197666I166J112D01*
G01X1586590Y1197686D01*
X1586766Y1198017D01*
G02X1586833Y1198084I171J-104D01*
G01X1586859Y1198100D01*
X1586884Y1198106D01*
X1587914D01*
G02X1588038Y1198014I-48J-194D01*
G02X1588043Y1198005I-172J-101D01*
G01X1588048Y1197996D01*
G02X1588050Y1197991I-185J-77D01*
G01X1588208Y1197693D01*
G02X1588228Y1197562I-176J-94D01*
G01X1588221Y1197524D01*
X1588196Y1197487D01*
G03X1587969Y1196752I1075J-735D01*
G01Y1196751D01*
G03X1590573I1302J0D01*
G01Y1196752D01*
G03X1590345Y1197487I-1302J-1D01*
G02X1590322Y1197666I166J112D01*
G01X1590330Y1197686D01*
X1590506Y1198017D01*
G02X1590573Y1198084I171J-104D01*
G01X1590599Y1198100D01*
X1590624Y1198106D01*
X1591654D01*
G02X1591778Y1198014I-48J-194D01*
G02X1591783Y1198005I-172J-101D01*
G01X1591788Y1197996D01*
G02X1591790Y1197991I-185J-77D01*
G01X1591948Y1197693D01*
G02X1591968Y1197562I-176J-94D01*
G01X1591961Y1197524D01*
X1591936Y1197487D01*
G03X1591709Y1196752I1075J-735D01*
G01Y1196751D01*
G03X1594313I1302J0D01*
G01Y1196752D01*
G03X1594085Y1197487I-1302J-1D01*
G02X1594062Y1197666I166J112D01*
G01X1594070Y1197686D01*
X1594246Y1198017D01*
G02X1594313Y1198084I171J-104D01*
G01X1594339Y1198100D01*
X1594364Y1198106D01*
X1595395D01*
G02X1595519Y1198014I-48J-194D01*
G02X1595524Y1198005I-172J-101D01*
G01X1595529Y1197996D01*
G02X1595531Y1197991I-185J-77D01*
G01X1595689Y1197693D01*
G02X1595709Y1197562I-176J-94D01*
G01X1595702Y1197524D01*
X1595677Y1197487D01*
G03X1595450Y1196752I1075J-735D01*
G01Y1196751D01*
G03X1598054I1302J0D01*
G01Y1196752D01*
G03X1597826Y1197487I-1302J-1D01*
G02X1597803Y1197666I166J112D01*
G01X1597811Y1197686D01*
X1597987Y1198017D01*
G02X1598054Y1198084I171J-104D01*
G01X1598080Y1198100D01*
X1598105Y1198106D01*
X1599135D01*
G02X1599259Y1198014I-48J-194D01*
G02X1599264Y1198005I-172J-101D01*
G01X1599269Y1197996D01*
G02X1599271Y1197991I-185J-77D01*
G01X1599429Y1197693D01*
G02X1599449Y1197562I-176J-94D01*
G01X1599442Y1197524D01*
X1599417Y1197487D01*
G03X1599190Y1196752I1075J-735D01*
G01Y1196751D01*
G03X1601794I1302J0D01*
G01Y1196752D01*
G03X1601566Y1197487I-1302J-1D01*
G02X1601543Y1197666I166J112D01*
G01X1601551Y1197686D01*
X1601727Y1198017D01*
G02X1601794Y1198084I171J-104D01*
G01X1601820Y1198100D01*
X1601845Y1198106D01*
X1606615D01*
G02X1606739Y1198014I-48J-194D01*
G02X1606744Y1198005I-172J-101D01*
G01X1606749Y1197996D01*
G02X1606751Y1197991I-185J-77D01*
G01X1606909Y1197693D01*
G02X1606929Y1197562I-176J-94D01*
G01X1606922Y1197524D01*
X1606897Y1197487D01*
G03X1606670Y1196752I1075J-735D01*
G01Y1196751D01*
G03X1609274I1302J0D01*
G01Y1196752D01*
G03X1609046Y1197487I-1302J-1D01*
G02X1609023Y1197666I166J112D01*
G01X1609031Y1197686D01*
X1609207Y1198017D01*
G02X1609274Y1198084I171J-104D01*
G01X1609300Y1198100D01*
X1609325Y1198106D01*
X1610355D01*
G02X1610479Y1198014I-48J-194D01*
G02X1610484Y1198005I-172J-101D01*
G01X1610489Y1197996D01*
G02X1610491Y1197991I-185J-77D01*
G01X1610649Y1197693D01*
G02X1610669Y1197562I-176J-94D01*
G01X1610662Y1197524D01*
X1610637Y1197487D01*
G03X1610410Y1196752I1075J-735D01*
G01Y1196751D01*
G03X1613014I1302J0D01*
G01Y1196752D01*
G03X1612786Y1197487I-1302J-1D01*
G02X1612763Y1197666I166J112D01*
G01X1612771Y1197686D01*
X1612947Y1198017D01*
G02X1613014Y1198084I171J-104D01*
G01X1613040Y1198100D01*
X1613065Y1198106D01*
X1614095D01*
G02X1614219Y1198014I-48J-194D01*
G02X1614224Y1198005I-172J-101D01*
G01X1614229Y1197996D01*
G02X1614231Y1197991I-185J-77D01*
G01X1614389Y1197693D01*
G02X1614409Y1197562I-176J-94D01*
G01X1614402Y1197524D01*
X1614377Y1197487D01*
G03X1614150Y1196752I1075J-735D01*
G01Y1196751D01*
G03X1616754I1302J0D01*
G01Y1196752D01*
G03X1616526Y1197487I-1302J-1D01*
G02X1616503Y1197666I166J112D01*
G01X1616511Y1197686D01*
X1616687Y1198017D01*
G02X1616754Y1198084I171J-104D01*
G01X1616780Y1198100D01*
X1616805Y1198106D01*
X1617836D01*
G02X1617960Y1198014I-48J-194D01*
G02X1617965Y1198005I-172J-101D01*
G01X1617970Y1197996D01*
G02X1617972Y1197991I-185J-77D01*
G01X1618130Y1197693D01*
G02X1618150Y1197562I-176J-94D01*
G01X1618143Y1197524D01*
X1618118Y1197487D01*
G03X1617891Y1196752I1075J-735D01*
G01Y1196751D01*
G03X1620495I1302J0D01*
G01Y1196752D01*
G03X1620267Y1197487I-1302J-1D01*
G02X1620244Y1197666I166J112D01*
G01X1620252Y1197686D01*
X1620428Y1198017D01*
G02X1620495Y1198084I171J-104D01*
G01X1620521Y1198100D01*
X1620546Y1198106D01*
X1621576D01*
G02X1621700Y1198014I-48J-194D01*
G02X1621705Y1198005I-172J-101D01*
G01X1621710Y1197996D01*
G02X1621712Y1197991I-185J-77D01*
G01X1621870Y1197693D01*
G02X1621890Y1197562I-176J-94D01*
G01X1621883Y1197524D01*
X1621858Y1197487D01*
G03X1621631Y1196752I1075J-735D01*
G01Y1196751D01*
G03X1624235I1302J0D01*
G01Y1196752D01*
G03X1624007Y1197487I-1302J-1D01*
G02X1623984Y1197666I166J112D01*
G01X1623992Y1197686D01*
X1624168Y1198017D01*
G02X1624235Y1198084I171J-104D01*
G01X1624261Y1198100D01*
X1624286Y1198106D01*
X1625316D01*
G02X1625440Y1198014I-48J-194D01*
G02X1625445Y1198005I-172J-101D01*
G01X1625450Y1197996D01*
G02X1625452Y1197991I-185J-77D01*
G01X1625610Y1197693D01*
G02X1625630Y1197562I-176J-94D01*
G01X1625623Y1197524D01*
X1625598Y1197487D01*
G03X1625371Y1196752I1075J-735D01*
G01Y1196751D01*
G03X1627975I1302J0D01*
G01Y1196752D01*
G03X1627747Y1197487I-1302J-1D01*
G02X1627724Y1197666I166J112D01*
G01X1627732Y1197686D01*
X1627908Y1198017D01*
G02X1627975Y1198084I171J-104D01*
G01X1628001Y1198100D01*
X1628026Y1198106D01*
X1629056D01*
G02X1629180Y1198014I-48J-194D01*
G02X1629185Y1198005I-172J-101D01*
G01X1629190Y1197996D01*
G02X1629192Y1197991I-185J-77D01*
G01X1629350Y1197693D01*
G02X1629370Y1197562I-176J-94D01*
G01X1629363Y1197524D01*
X1629338Y1197487D01*
G03X1629111Y1196752I1075J-735D01*
G01Y1196751D01*
G03X1631715I1302J0D01*
G01Y1196752D01*
G03X1631487Y1197487I-1302J-1D01*
G02X1631464Y1197666I166J112D01*
G01X1631472Y1197686D01*
X1631648Y1198017D01*
G02X1631715Y1198084I171J-104D01*
G01X1631741Y1198100D01*
X1631766Y1198106D01*
X1632796D01*
G02X1632920Y1198014I-48J-194D01*
G02X1632925Y1198005I-172J-101D01*
G01X1632930Y1197996D01*
G02X1632932Y1197991I-185J-77D01*
G01X1633090Y1197693D01*
G02X1633110Y1197562I-176J-94D01*
G01X1633103Y1197524D01*
X1633078Y1197487D01*
G03X1632851Y1196752I1075J-735D01*
G01Y1196751D01*
G03X1635455I1302J0D01*
G01Y1196752D01*
G03X1635227Y1197487I-1302J-1D01*
G02X1635204Y1197666I166J112D01*
G01X1635212Y1197686D01*
X1635388Y1198017D01*
G02X1635455Y1198084I171J-104D01*
G01X1635481Y1198100D01*
X1635506Y1198106D01*
X1636536D01*
G02X1636660Y1198014I-48J-194D01*
G02X1636665Y1198005I-172J-101D01*
G01X1636670Y1197996D01*
G02X1636672Y1197991I-185J-77D01*
G01X1636830Y1197693D01*
G02X1636850Y1197562I-176J-94D01*
G01X1636843Y1197524D01*
X1636818Y1197487D01*
G03X1636591Y1196752I1075J-735D01*
G01Y1196751D01*
G03X1639195I1302J0D01*
G01Y1196752D01*
G03X1638967Y1197487I-1302J-1D01*
G02X1638944Y1197666I166J112D01*
G01X1638952Y1197686D01*
X1639128Y1198017D01*
G02X1639195Y1198084I171J-104D01*
G01X1639221Y1198100D01*
X1639246Y1198106D01*
X1640017D01*
G02X1640110Y1198055I-46J-194D01*
G01X1640512Y1197653D01*
G02X1640541Y1197616I-142J-141D01*
G01Y1197409D01*
X1640522Y1197374D01*
G03X1640351Y1196732I1130J-645D01*
G03X1641652Y1195430I1302J0D01*
G01X1641654D01*
G03X1641755Y1195433I12J1302D01*
G01X1641797Y1195436D01*
X1641835Y1195423D01*
G02X1641904Y1195381I-67J-188D01*
G01X1642067Y1195231D01*
X1642120Y1195182D01*
G02X1642184Y1195036I-136J-147D01*
G01Y1194706D01*
G02X1642127Y1194567I-200J1D01*
G01X1641901Y1194359D01*
G02X1641831Y1194317I-136J147D01*
G01X1641792Y1194304D01*
X1641749Y1194308D01*
G03X1641633Y1194313I-114J-1297D01*
G03Y1191709I0J-1302D01*
G03X1641749Y1191714I2J1302D01*
G01X1641792Y1191718D01*
X1641831Y1191705D01*
G02X1641901Y1191663I-66J-189D01*
G01X1642119Y1191463D01*
G02X1642184Y1191316I-135J-148D01*
G01Y1190966D01*
G02X1642127Y1190827I-200J1D01*
G01X1641901Y1190619D01*
G02X1641831Y1190577I-136J147D01*
G01X1641792Y1190564D01*
X1641749Y1190568D01*
G03X1641633Y1190573I-114J-1297D01*
G03Y1187969I0J-1302D01*
G03X1641749Y1187974I2J1302D01*
G01X1641792Y1187978D01*
X1641831Y1187965D01*
G02X1641901Y1187923I-66J-189D01*
G01X1642119Y1187723D01*
G02X1642184Y1187576I-135J-148D01*
G01Y1187226D01*
G02X1642127Y1187087I-200J1D01*
G01X1641901Y1186879D01*
G02X1641831Y1186837I-136J147D01*
G01X1641792Y1186824D01*
X1641749Y1186828D01*
G03X1641633Y1186833I-114J-1297D01*
G03Y1184229I0J-1302D01*
G03X1641749Y1184234I2J1302D01*
G01X1641792Y1184238D01*
X1641831Y1184225D01*
G02X1641901Y1184183I-66J-189D01*
G01X1642119Y1183983D01*
G02X1642184Y1183836I-135J-148D01*
G01Y1183486D01*
G02X1642127Y1183347I-200J1D01*
G01X1641901Y1183139D01*
G02X1641831Y1183097I-136J147D01*
G01X1641792Y1183084D01*
X1641749Y1183088D01*
G03X1641633Y1183093I-114J-1297D01*
G03Y1180489I0J-1302D01*
G03X1641749Y1180494I2J1302D01*
G01X1641792Y1180498D01*
X1641831Y1180485D01*
G02X1641901Y1180443I-66J-189D01*
G01X1642119Y1180243D01*
G02X1642184Y1180096I-135J-148D01*
G01Y1179746D01*
G02X1642127Y1179607I-200J1D01*
G01X1641901Y1179399D01*
G02X1641831Y1179357I-136J147D01*
G01X1641792Y1179344D01*
X1641749Y1179348D01*
G03X1641633Y1179353I-114J-1297D01*
G03Y1176749I0J-1302D01*
G03X1641749Y1176754I2J1302D01*
G01X1641792Y1176758D01*
X1641831Y1176745D01*
G02X1641901Y1176703I-66J-189D01*
G01X1642119Y1176503D01*
G02X1642184Y1176356I-135J-148D01*
G01Y1176005D01*
G02X1642127Y1175866I-200J1D01*
G01X1641901Y1175658D01*
G02X1641831Y1175616I-136J147D01*
G01X1641792Y1175603D01*
X1641749Y1175607D01*
G03X1641633Y1175612I-114J-1297D01*
G03Y1173008I0J-1302D01*
G03X1641749Y1173013I2J1302D01*
G01X1641792Y1173017D01*
X1641831Y1173004D01*
G02X1641901Y1172962I-66J-189D01*
G01X1642119Y1172762D01*
G02X1642184Y1172615I-135J-148D01*
G01Y1172265D01*
G02X1642127Y1172126I-200J1D01*
G01X1641901Y1171918D01*
G02X1641831Y1171876I-136J147D01*
G01X1641792Y1171863D01*
X1641749Y1171867D01*
G03X1641633Y1171872I-114J-1297D01*
G03Y1169268I0J-1302D01*
G03X1641749Y1169273I2J1302D01*
G01X1641792Y1169277D01*
X1641831Y1169264D01*
G02X1641901Y1169222I-66J-189D01*
G01X1642119Y1169022D01*
G02X1642184Y1168875I-135J-148D01*
G01Y1168525D01*
G02X1642127Y1168386I-200J1D01*
G01X1641901Y1168178D01*
G02X1641831Y1168136I-136J147D01*
G01X1641792Y1168123D01*
X1641749Y1168127D01*
G03X1641633Y1168132I-114J-1297D01*
G03Y1165528I0J-1302D01*
G03X1641749Y1165533I2J1302D01*
G01X1641792Y1165537D01*
X1641831Y1165524D01*
G02X1641901Y1165482I-66J-189D01*
G01X1642119Y1165282D01*
G02X1642184Y1165135I-135J-148D01*
G01Y1161045D01*
G02X1642127Y1160906I-200J1D01*
G01X1641901Y1160698D01*
G02X1641831Y1160656I-136J147D01*
G01X1641792Y1160643D01*
X1641749Y1160647D01*
G03X1641633Y1160652I-114J-1297D01*
G03Y1158048I0J-1302D01*
G03X1641749Y1158053I2J1302D01*
G01X1641792Y1158057D01*
X1641831Y1158044D01*
G02X1641901Y1158002I-66J-189D01*
G01X1642119Y1157802D01*
G02X1642184Y1157655I-135J-148D01*
G01Y1157305D01*
G02X1642127Y1157166I-200J1D01*
G01X1641901Y1156958D01*
G02X1641831Y1156916I-136J147D01*
G01X1641792Y1156903D01*
X1641749Y1156907D01*
G03X1641633Y1156912I-114J-1297D01*
G03Y1154308I0J-1302D01*
G03X1641749Y1154313I2J1302D01*
G01X1641792Y1154317D01*
X1641831Y1154304D01*
G02X1641901Y1154262I-66J-189D01*
G01X1642119Y1154062D01*
G02X1642184Y1153915I-135J-148D01*
G01Y1153564D01*
G02X1642127Y1153425I-200J1D01*
G01X1641901Y1153217D01*
G02X1641831Y1153175I-136J147D01*
G01X1641792Y1153162D01*
X1641749Y1153166D01*
G03X1641633Y1153171I-114J-1297D01*
G03Y1150567I0J-1302D01*
G03X1641749Y1150572I2J1302D01*
G01X1641792Y1150576D01*
X1641831Y1150563D01*
G02X1641901Y1150521I-66J-189D01*
G01X1642119Y1150321D01*
G02X1642184Y1150174I-135J-148D01*
G01Y1149824D01*
G02X1642127Y1149685I-200J1D01*
G01X1641901Y1149477D01*
G02X1641831Y1149435I-136J147D01*
G01X1641792Y1149422D01*
X1641749Y1149426D01*
G03X1641633Y1149431I-114J-1297D01*
G03Y1146827I0J-1302D01*
G03X1641749Y1146832I2J1302D01*
G01X1641792Y1146836D01*
X1641831Y1146823D01*
G02X1641901Y1146781I-66J-189D01*
G01X1642119Y1146581D01*
G02X1642184Y1146434I-135J-148D01*
G01Y1146084D01*
G02X1642127Y1145945I-200J1D01*
G01X1641901Y1145737D01*
G02X1641831Y1145695I-136J147D01*
G01X1641792Y1145682D01*
X1641749Y1145686D01*
G03X1641633Y1145691I-114J-1297D01*
G03Y1143087I0J-1302D01*
G03X1641749Y1143092I2J1302D01*
G01X1641792Y1143096D01*
X1641831Y1143083D01*
G02X1641901Y1143041I-66J-189D01*
G01X1642119Y1142841D01*
G02X1642184Y1142694I-135J-148D01*
G01Y1142344D01*
G02X1642127Y1142205I-200J1D01*
G01X1641901Y1141997D01*
G02X1641831Y1141955I-136J147D01*
G01X1641792Y1141942D01*
X1641749Y1141946D01*
G03X1641633Y1141951I-114J-1297D01*
G03Y1139347I0J-1302D01*
G03X1641749Y1139352I2J1302D01*
G01X1641792Y1139356D01*
X1641831Y1139343D01*
G02X1641901Y1139301I-66J-189D01*
G01X1642119Y1139101D01*
G02X1642184Y1138954I-135J-148D01*
G01Y1138604D01*
G02X1642127Y1138465I-200J1D01*
G01X1641901Y1138257D01*
G02X1641831Y1138215I-136J147D01*
G01X1641792Y1138202D01*
X1641749Y1138206D01*
G03X1641633Y1138211I-114J-1297D01*
G03Y1135607I0J-1302D01*
G03X1641749Y1135612I2J1302D01*
G01X1641792Y1135616D01*
X1641831Y1135603D01*
G02X1641901Y1135561I-66J-189D01*
G01X1642119Y1135361D01*
G02X1642184Y1135214I-135J-148D01*
G01Y1134864D01*
G02X1642127Y1134725I-200J1D01*
G01X1641901Y1134517D01*
G02X1641831Y1134475I-136J147D01*
G01X1641792Y1134462D01*
X1641749Y1134466D01*
G03X1641633Y1134471I-114J-1297D01*
G03X1640331Y1133169I0J-1302D01*
G03X1641035Y1132012I1303J0D01*
G01X1641063Y1131998D01*
X1641090Y1131971D01*
G02X1641085Y1131693I-146J-136D01*
G01X1641021Y1131629D01*
G02X1640971Y1131593I-140J142D01*
G02X1640880Y1131571I-91J178D01*
G01X1640210D01*
G03X1640188Y1131573I-120J-1201D01*
G01X1640182D01*
G03X1640091Y1131578I-112J-1202D01*
G01X1639313D01*
G03X1639208Y1131573I5J-1208D01*
G02X1639189Y1131572I-20J199D01*
G01X1639101D01*
G02X1638917Y1131695I1J200D01*
G01X1638775Y1132035D01*
G02X1638810Y1132245I185J77D01*
G03X1639195Y1133169I-916J924D01*
G03X1636591I-1302J0D01*
G03X1636976Y1132245I1301J0D01*
G02X1637011Y1132035I-150J-133D01*
G01X1636869Y1131695D01*
G02X1636685Y1131572I-185J77D01*
G01X1636597D01*
G02X1636578Y1131573I1J200D01*
G03X1636473Y1131578I-110J-1203D01*
G01X1635573D01*
G03X1635468Y1131573I5J-1208D01*
G02X1635449Y1131572I-20J199D01*
G01X1635361D01*
G02X1635177Y1131695I1J200D01*
G01X1635035Y1132035D01*
G02X1635070Y1132245I185J77D01*
G03X1635455Y1133169I-916J924D01*
G03X1632851I-1302J0D01*
G03X1633236Y1132245I1301J0D01*
G02X1633271Y1132035I-150J-133D01*
G01X1633129Y1131695D01*
G02X1632945Y1131572I-185J77D01*
G01X1632857D01*
G02X1632838Y1131573I1J200D01*
G03X1632733Y1131578I-110J-1203D01*
G01X1631833D01*
G03X1631728Y1131573I5J-1208D01*
G02X1631709Y1131572I-20J199D01*
G01X1631621D01*
G02X1631437Y1131695I1J200D01*
G01X1631295Y1132035D01*
G02X1631330Y1132245I185J77D01*
G03X1631715Y1133169I-916J924D01*
G03X1629111I-1302J0D01*
G03X1629496Y1132245I1301J0D01*
G02X1629531Y1132035I-150J-133D01*
G01X1629389Y1131695D01*
G02X1629205Y1131572I-185J77D01*
G01X1629117D01*
G02X1629098Y1131573I1J200D01*
G03X1628993Y1131578I-110J-1203D01*
G01X1628093D01*
G03X1627988Y1131573I5J-1208D01*
G02X1627969Y1131572I-20J199D01*
G01X1627881D01*
G02X1627697Y1131695I1J200D01*
G01X1627555Y1132035D01*
G02X1627590Y1132245I185J77D01*
G03X1627975Y1133169I-916J924D01*
G03X1625371I-1302J0D01*
G03X1625756Y1132245I1301J0D01*
G02X1625791Y1132035I-150J-133D01*
G01X1625649Y1131695D01*
G02X1625465Y1131572I-185J77D01*
G01X1625377D01*
G02X1625358Y1131573I1J200D01*
G03X1625253Y1131578I-110J-1203D01*
G01X1624353D01*
G03X1624248Y1131573I5J-1208D01*
G02X1624229Y1131572I-20J199D01*
G01X1624141D01*
G02X1623957Y1131695I1J200D01*
G01X1623815Y1132035D01*
G02X1623850Y1132245I185J77D01*
G03X1624235Y1133169I-916J924D01*
G03X1621631I-1302J0D01*
G03X1622016Y1132245I1301J0D01*
G02X1622051Y1132035I-150J-133D01*
G01X1621909Y1131695D01*
G02X1621725Y1131572I-185J77D01*
G01X1621637D01*
G02X1621618Y1131573I1J200D01*
G03X1621513Y1131578I-110J-1203D01*
G01X1620613D01*
G03X1620508Y1131573I5J-1208D01*
G02X1620489Y1131572I-20J199D01*
G01X1620401D01*
G02X1620217Y1131695I1J200D01*
G01X1620075Y1132035D01*
G02X1620110Y1132245I185J77D01*
G03X1620495Y1133169I-916J924D01*
G03X1617891I-1302J0D01*
G03X1618276Y1132245I1301J0D01*
G02X1618311Y1132035I-150J-133D01*
G01X1618169Y1131695D01*
G02X1617985Y1131572I-185J77D01*
G01X1617897D01*
G02X1617878Y1131573I1J200D01*
G03X1617773Y1131578I-110J-1203D01*
G01X1616872D01*
G03X1616767Y1131573I5J-1208D01*
G02X1616748Y1131572I-20J199D01*
G01X1616660D01*
G02X1616476Y1131695I1J200D01*
G01X1616334Y1132035D01*
G02X1616369Y1132245I185J77D01*
G03X1616754Y1133169I-916J924D01*
G03X1614150I-1302J0D01*
G03X1614535Y1132245I1301J0D01*
G02X1614570Y1132035I-150J-133D01*
G01X1614428Y1131695D01*
G02X1614244Y1131572I-185J77D01*
G01X1614156D01*
G02X1614137Y1131573I1J200D01*
G03X1614032Y1131578I-110J-1203D01*
G01X1613132D01*
G03X1613027Y1131573I5J-1208D01*
G02X1613008Y1131572I-20J199D01*
G01X1612920D01*
G02X1612736Y1131695I1J200D01*
G01X1612594Y1132035D01*
G02X1612629Y1132245I185J77D01*
G03X1613014Y1133169I-916J924D01*
G03X1610410I-1302J0D01*
G03X1610795Y1132245I1301J0D01*
G02X1610830Y1132035I-150J-133D01*
G01X1610688Y1131695D01*
G02X1610504Y1131572I-185J77D01*
G01X1610416D01*
G02X1610397Y1131573I1J200D01*
G03X1610292Y1131578I-110J-1203D01*
G01X1609392D01*
G03X1609287Y1131573I5J-1208D01*
G02X1609268Y1131572I-20J199D01*
G01X1606676D01*
G02X1606657Y1131573I1J200D01*
G03X1606552Y1131578I-110J-1203D01*
G01X1602090D01*
G02X1601974Y1131658I48J194D01*
G01X1601876Y1131812D01*
X1601807Y1131920D01*
G02X1601775Y1132027I168J108D01*
G01Y1132136D01*
X1601791Y1132174D01*
G03X1601892Y1132676I-1201J503D01*
G01Y1132677D01*
G03X1599288I-1302J0D01*
G01Y1132676D01*
G03X1599405Y1132139I1302J2D01*
G01Y1132137D01*
X1599406D01*
G02X1599422Y1132041I-183J-80D01*
G01X1599419Y1131992D01*
X1599205Y1131657D01*
G02X1599090Y1131578I-164J115D01*
G01X1598172D01*
G03X1598067Y1131573I5J-1208D01*
G02X1598048Y1131572I-20J199D01*
G01X1597960D01*
G02X1597776Y1131695I1J200D01*
G01X1597634Y1132035D01*
G02X1597669Y1132245I185J77D01*
G03X1598054Y1133169I-916J924D01*
G03X1595450I-1302J0D01*
G03X1595835Y1132245I1301J0D01*
G02X1595870Y1132035I-150J-133D01*
G01X1595728Y1131695D01*
G02X1595544Y1131572I-185J77D01*
G01X1595456D01*
G02X1595437Y1131573I1J200D01*
G03X1595332Y1131578I-110J-1203D01*
G01X1594431D01*
G03X1594326Y1131573I5J-1208D01*
G02X1594307Y1131572I-20J199D01*
G01X1594219D01*
G02X1594035Y1131695I1J200D01*
G01X1593893Y1132035D01*
G02X1593928Y1132245I185J77D01*
G03X1594313Y1133169I-916J924D01*
G03X1591709I-1302J0D01*
G03X1592094Y1132245I1301J0D01*
G02X1592129Y1132035I-150J-133D01*
G01X1591987Y1131695D01*
G02X1591803Y1131572I-185J77D01*
G01X1591715D01*
G02X1591696Y1131573I1J200D01*
G03X1591591Y1131578I-110J-1203D01*
G01X1590691D01*
G03X1590586Y1131573I5J-1208D01*
G02X1590567Y1131572I-20J199D01*
G01X1590479D01*
G02X1590295Y1131695I1J200D01*
G01X1590153Y1132035D01*
G02X1590188Y1132245I185J77D01*
G03X1590573Y1133169I-916J924D01*
G03X1587969I-1302J0D01*
G03X1588354Y1132245I1301J0D01*
G02X1588389Y1132035I-150J-133D01*
G01X1588247Y1131695D01*
G02X1588063Y1131572I-185J77D01*
G01X1587975D01*
G02X1587956Y1131573I1J200D01*
G03X1587851Y1131578I-110J-1203D01*
G01X1586951D01*
G03X1586846Y1131573I5J-1208D01*
G02X1586827Y1131572I-20J199D01*
G01X1586739D01*
G02X1586555Y1131695I1J200D01*
G01X1586413Y1132035D01*
G02X1586448Y1132245I185J77D01*
G03X1586833Y1133169I-916J924D01*
G03X1584229I-1302J0D01*
G03X1584614Y1132245I1301J0D01*
G02X1584649Y1132035I-150J-133D01*
G01X1584507Y1131695D01*
G02X1584323Y1131572I-185J77D01*
G01X1584235D01*
G02X1584216Y1131573I1J200D01*
G03X1584111Y1131578I-110J-1203D01*
G01X1583211D01*
G03X1583106Y1131573I5J-1208D01*
G02X1583087Y1131572I-20J199D01*
G01X1582999D01*
G02X1582815Y1131695I1J200D01*
G01X1582673Y1132035D01*
G02X1582708Y1132245I185J77D01*
G03X1583093Y1133169I-916J924D01*
G03X1580489I-1302J0D01*
G03X1580874Y1132245I1301J0D01*
G02X1580909Y1132035I-150J-133D01*
G01X1580767Y1131695D01*
G02X1580583Y1131572I-185J77D01*
G01X1580495D01*
G02X1580476Y1131573I1J200D01*
G03X1580371Y1131578I-110J-1203D01*
G01X1579471D01*
G03X1579366Y1131573I5J-1208D01*
G02X1579347Y1131572I-20J199D01*
G01X1579259D01*
G02X1579075Y1131695I1J200D01*
G01X1578933Y1132035D01*
G02X1578968Y1132245I185J77D01*
G03X1579353Y1133169I-916J924D01*
G03X1576749I-1302J0D01*
G03X1577134Y1132245I1301J0D01*
G02X1577169Y1132035I-150J-133D01*
G01X1577027Y1131695D01*
G02X1576843Y1131572I-185J77D01*
G01X1576755D01*
G02X1576736Y1131573I1J200D01*
G03X1576631Y1131578I-110J-1203D01*
G01X1575731D01*
G03X1575626Y1131573I5J-1208D01*
G02X1575607Y1131572I-20J199D01*
G01X1575519D01*
G02X1575335Y1131695I1J200D01*
G01X1575193Y1132035D01*
G02X1575228Y1132245I185J77D01*
G03X1575613Y1133169I-916J924D01*
G03X1573009I-1302J0D01*
G03X1573394Y1132245I1301J0D01*
G02X1573429Y1132035I-150J-133D01*
G01X1573287Y1131695D01*
G02X1573103Y1131572I-185J77D01*
G01X1573015D01*
G02X1572996Y1131573I1J200D01*
G03X1572891Y1131578I-110J-1203D01*
G01X1571991D01*
G03X1571886Y1131573I5J-1208D01*
G02X1571867Y1131572I-20J199D01*
G01X1571779D01*
G02X1571595Y1131695I1J200D01*
G01X1571453Y1132035D01*
G02X1571488Y1132245I185J77D01*
G03X1571873Y1133169I-916J924D01*
G03X1569269I-1302J0D01*
G03X1569654Y1132245I1301J0D01*
G02X1569689Y1132035I-150J-133D01*
G01X1569547Y1131695D01*
G02X1569363Y1131572I-185J77D01*
G01X1569275D01*
G02X1569256Y1131573I1J200D01*
G03X1569151Y1131578I-110J-1203D01*
G01X1568323D01*
G03X1568301Y1131577I-2J-200D01*
G01X1568251Y1131571D01*
X1568038D01*
G02X1567927Y1131605I1J200D01*
G02X1567854Y1131694I112J166D01*
G01X1567752Y1131939D01*
X1567712Y1132034D01*
G02X1567752Y1132250I184J78D01*
G02X1567755Y1132253I143J-140D01*
G03X1568132Y1133169I-924J916D01*
G03X1565528I-1302J0D01*
G03X1565905Y1132253I1301J0D01*
G02X1565908Y1132250I-140J-143D01*
G02X1565948Y1132034I-144J-138D01*
G01X1565908Y1131939D01*
X1565806Y1131694D01*
G02X1565733Y1131605I-185J77D01*
G02X1565622Y1131571I-112J166D01*
G01X1565407D01*
G03X1565385Y1131573I-120J-1201D01*
G01X1565379D01*
G03X1565288Y1131578I-112J-1202D01*
G01X1564583D01*
G03X1564561Y1131577I-2J-200D01*
G01X1564511Y1131571D01*
X1564298D01*
G02X1564187Y1131605I1J200D01*
G02X1564114Y1131694I112J166D01*
G01X1564012Y1131939D01*
X1563972Y1132034D01*
G02X1564012Y1132250I184J78D01*
G02X1564015Y1132253I143J-140D01*
G03X1564392Y1133169I-924J916D01*
G03X1561788I-1302J0D01*
G03X1562165Y1132253I1301J0D01*
G02X1562168Y1132250I-140J-143D01*
G02X1562208Y1132034I-144J-138D01*
G01X1562168Y1131939D01*
X1562066Y1131694D01*
G02X1561993Y1131605I-185J77D01*
G02X1561882Y1131571I-112J166D01*
G01X1561667D01*
G03X1561659Y1131572I-154J-1197D01*
G01X1561605Y1131577D01*
G03X1561586Y1131578I-20J-199D01*
G01X1561451D01*
X1561440Y1131576D01*
X1561250D01*
X1561237Y1131571D01*
X1560558D01*
G02X1560447Y1131605I1J200D01*
G02X1560374Y1131694I112J166D01*
G01X1560272Y1131939D01*
X1560232Y1132034D01*
G02X1560272Y1132250I184J78D01*
G02X1560275Y1132253I143J-140D01*
G03X1560652Y1133169I-924J916D01*
G03X1558048I-1302J0D01*
G03X1558425Y1132253I1301J0D01*
G02X1558428Y1132250I-140J-143D01*
G02X1558468Y1132034I-144J-138D01*
G01X1558428Y1131939D01*
X1558326Y1131694D01*
G02X1558253Y1131605I-185J77D01*
G02X1558142Y1131571I-112J166D01*
G01X1556818D01*
G02X1556707Y1131605I1J200D01*
G02X1556634Y1131694I112J166D01*
G01X1556532Y1131939D01*
X1556492Y1132034D01*
G02X1556532Y1132250I184J78D01*
G02X1556535Y1132253I143J-140D01*
G03X1556912Y1133169I-924J916D01*
G03X1554308I-1302J0D01*
G03X1554685Y1132253I1301J0D01*
G02X1554688Y1132250I-140J-143D01*
G02X1554728Y1132034I-144J-138D01*
G01X1554688Y1131939D01*
X1554586Y1131694D01*
G02X1554513Y1131605I-185J77D01*
G02X1554402Y1131571I-112J166D01*
G01X1553078D01*
G02X1552894Y1131694I1J200D01*
G01X1552823Y1131865D01*
X1552752Y1132035D01*
G02X1552779Y1132235I184J77D01*
G02X1552785Y1132243I163J-116D01*
G01X1552793Y1132251D01*
G03X1553172Y1133169I-922J918D01*
G03X1550568I-1302J0D01*
G03X1550945Y1132253I1301J0D01*
G02X1550948Y1132250I-140J-143D01*
G02X1550988Y1132034I-144J-138D01*
G01X1550948Y1131939D01*
X1550846Y1131694D01*
G02X1550773Y1131605I-185J77D01*
G02X1550662Y1131571I-112J166D01*
G01X1549338D01*
G02X1549154Y1131694I1J200D01*
G01X1549083Y1131865D01*
X1549012Y1132035D01*
G02X1549039Y1132235I184J77D01*
G02X1549045Y1132243I163J-116D01*
G01X1549053Y1132251D01*
G03X1549432Y1133169I-922J918D01*
G03X1546828I-1302J0D01*
G03X1547205Y1132253I1301J0D01*
G02X1547208Y1132250I-140J-143D01*
G02X1547248Y1132034I-144J-138D01*
G01X1547208Y1131939D01*
X1547106Y1131694D01*
G02X1547033Y1131605I-185J77D01*
G02X1546922Y1131571I-112J166D01*
G01X1534377D01*
G02X1534193Y1131694I1J200D01*
G01X1534122Y1131865D01*
X1534051Y1132035D01*
G02X1534078Y1132235I184J77D01*
G02X1534084Y1132243I163J-116D01*
G01X1534092Y1132251D01*
G03X1534471Y1133169I-922J918D01*
G03X1531867I-1302J0D01*
G03X1532244Y1132253I1301J0D01*
G02X1532247Y1132250I-140J-143D01*
G02X1532287Y1132034I-144J-138D01*
G01X1532247Y1131939D01*
X1532145Y1131694D01*
G02X1532072Y1131605I-185J77D01*
G02X1531961Y1131571I-112J166D01*
G01X1523157D01*
G02X1522973Y1131694I1J200D01*
G01X1522902Y1131865D01*
X1522831Y1132035D01*
G02X1522858Y1132235I184J77D01*
G02X1522864Y1132243I163J-116D01*
G01X1522872Y1132251D01*
G03X1523251Y1133169I-922J918D01*
G03X1520647I-1302J0D01*
G03X1521024Y1132253I1301J0D01*
G02X1521027Y1132250I-140J-143D01*
G02X1521067Y1132034I-144J-138D01*
G01X1521027Y1131939D01*
X1520925Y1131694D01*
G02X1520852Y1131605I-185J77D01*
G02X1520741Y1131571I-112J166D01*
G01X1519416D01*
G02X1519232Y1131694I1J200D01*
G01X1519161Y1131865D01*
X1519090Y1132035D01*
G02X1519117Y1132235I184J77D01*
G02X1519123Y1132243I163J-116D01*
G01X1519131Y1132251D01*
G03X1519510Y1133169I-922J918D01*
G03X1516906I-1302J0D01*
G03X1517283Y1132253I1301J0D01*
G02X1517286Y1132250I-140J-143D01*
G02X1517326Y1132034I-144J-138D01*
G01X1517286Y1131939D01*
X1517184Y1131694D01*
G02X1517111Y1131605I-185J77D01*
G02X1517000Y1131571I-112J166D01*
G01X1515676D01*
G02X1515492Y1131694I1J200D01*
G01X1515421Y1131865D01*
X1515350Y1132035D01*
G02X1515377Y1132235I184J77D01*
G02X1515383Y1132243I163J-116D01*
G01X1515391Y1132251D01*
G03X1515770Y1133169I-922J918D01*
G03X1513166I-1302J0D01*
G03X1513543Y1132253I1301J0D01*
G02X1513546Y1132250I-140J-143D01*
G02X1513586Y1132034I-144J-138D01*
G01X1513546Y1131939D01*
X1513444Y1131694D01*
G02X1513371Y1131605I-185J77D01*
G02X1513260Y1131571I-112J166D01*
G01X1505998D01*
G02X1505947Y1131578I1J200D01*
G01X1505873Y1131597D01*
X1505851Y1131609D01*
G03X1505131Y1131793I-720J-1318D01*
G01X1505093D01*
G03X1504410Y1131609I38J-1502D01*
G01X1504387Y1131597D01*
X1504313Y1131578D01*
G02X1504262Y1131571I-52J193D01*
G01X1502508D01*
G02X1502457Y1131578I1J200D01*
G01X1502383Y1131597D01*
X1502361Y1131609D01*
G03X1501641Y1131793I-720J-1318D01*
G01X1501603D01*
G03X1500920Y1131609I38J-1502D01*
G01X1500897Y1131597D01*
X1500823Y1131578D01*
G02X1500772Y1131571I-52J193D01*
G01X1497008D01*
G02X1496957Y1131578I1J200D01*
G01X1496883Y1131597D01*
X1496861Y1131609D01*
G03X1496141Y1131793I-720J-1318D01*
G01X1496103D01*
G03X1495420Y1131609I38J-1502D01*
G01X1495397Y1131597D01*
X1495323Y1131578D01*
G02X1495272Y1131571I-52J193D01*
G01X1453180D01*
G02X1453054Y1131616I0J200D01*
G02X1453039Y1131629I123J157D01*
G01X1451043Y1133625D01*
G02X1451007Y1133675I142J140D01*
G02X1450985Y1133766I178J91D01*
G01Y1153322D01*
G03X1450926Y1153464I-200J0D01*
G01X1446423Y1157967D01*
G03X1446281Y1158026I-142J-141D01*
G01X1384604D01*
G02X1384529Y1158040I-1J200D01*
G01X1384493Y1158055D01*
X1382337Y1160211D01*
G03X1382273Y1160254I-141J-141D01*
G03X1382265Y1160257I-74J-186D01*
G01X1382261Y1160259D01*
X1382199Y1160285D01*
G02X1382139Y1160326I81J183D01*
G01X1382078Y1160387D01*
G02X1382042Y1160437I142J140D01*
G02X1382020Y1160528I178J91D01*
G01Y1239546D01*
Y1239552D01*
G02X1382035Y1239622I200J-6D01*
G01X1382059Y1239680D01*
G03X1382074Y1239756I-185J76D01*
G01Y1248457D01*
G02X1382078Y1248495I200J-2D01*
G02X1382131Y1248597I196J-37D01*
G01X1384941Y1251407D01*
G02X1385043Y1251460I139J-143D01*
G02X1385081Y1251464I40J-196D01*
G01X1472117D01*
G02X1472149Y1251461I-3J-200D01*
G01X1472151D01*
G02X1472257Y1251407I-34J-197D01*
G01X1479818Y1243846D01*
G03X1479960Y1243787I142J141D01*
G01X1495803D01*
G03X1495945Y1243846I0J200D01*
G01X1503506Y1251407D01*
G02X1503608Y1251460I139J-143D01*
G02X1503646Y1251464I40J-196D01*
G01X1512703D01*
G02X1512771Y1251452I0J-200D01*
G02X1512844Y1251406I-68J-188D01*
G01X1513024Y1251226D01*
X1513025D01*
X1513114Y1251137D01*
G03X1513256Y1251078I142J141D01*
G01X1514861D01*
G02X1514998Y1251024I0J-200D01*
G01X1515084Y1250944D01*
G02X1515146Y1250824I-136J-146D01*
G03X1517530I1192J160D01*
G02X1517592Y1250944I198J-26D01*
G01X1517678Y1251024D01*
G02X1517815Y1251078I137J-146D01*
G01X1518601D01*
G02X1518738Y1251024I0J-200D01*
G01X1518824Y1250944D01*
G02X1518886Y1250824I-136J-146D01*
G03X1521270I1192J160D01*
G02X1521332Y1250944I198J-26D01*
G01X1521418Y1251024D01*
G02X1521555Y1251078I137J-146D01*
G01X1522342D01*
G02X1522479Y1251024I0J-200D01*
G01X1522565Y1250944D01*
G02X1522627Y1250824I-136J-146D01*
G03X1525011I1192J160D01*
G02X1525073Y1250944I198J-26D01*
G01X1525159Y1251024D01*
G02X1525296Y1251078I137J-146D01*
G01X1526082D01*
G02X1526219Y1251024I0J-200D01*
G01X1526305Y1250944D01*
G02X1526367Y1250824I-136J-146D01*
G03X1528751I1192J160D01*
G02X1528813Y1250944I198J-26D01*
G01X1528899Y1251024D01*
G02X1529036Y1251078I137J-146D01*
G01X1529822D01*
G02X1529959Y1251024I0J-200D01*
G01X1530045Y1250944D01*
G02X1530107Y1250824I-136J-146D01*
G03X1532491I1192J160D01*
G02X1532553Y1250944I198J-26D01*
G01X1532639Y1251024D01*
G02X1532776Y1251078I137J-146D01*
G01X1533562D01*
G02X1533699Y1251024I0J-200D01*
G01X1533785Y1250944D01*
G02X1533847Y1250824I-136J-146D01*
G03X1536231I1192J160D01*
G02X1536293Y1250944I198J-26D01*
G01X1536379Y1251024D01*
G02X1536516Y1251078I137J-146D01*
G01X1537302D01*
G02X1537439Y1251024I0J-200D01*
G01X1537525Y1250944D01*
G02X1537587Y1250824I-136J-146D01*
G03X1539971I1192J160D01*
G02X1540033Y1250944I198J-26D01*
G01X1540119Y1251024D01*
G02X1540256Y1251078I137J-146D01*
G01X1541042D01*
G02X1541179Y1251024I0J-200D01*
G01X1541265Y1250944D01*
G02X1541327Y1250824I-136J-146D01*
G03X1543711I1192J160D01*
G02X1543773Y1250944I198J-26D01*
G01X1543859Y1251024D01*
G02X1543996Y1251078I137J-146D01*
G01X1544782D01*
G02X1544919Y1251024I0J-200D01*
G01X1545005Y1250944D01*
G02X1545067Y1250824I-136J-146D01*
G03X1547451I1192J160D01*
G02X1547513Y1250944I198J-26D01*
G01X1547599Y1251024D01*
G02X1547736Y1251078I137J-146D01*
G01X1548523D01*
G02X1548660Y1251024I0J-200D01*
G01X1548746Y1250944D01*
G02X1548808Y1250824I-136J-146D01*
G03X1551192I1192J160D01*
G02X1551254Y1250944I198J-26D01*
G01X1551340Y1251024D01*
G02X1551477Y1251078I137J-146D01*
G01X1552263D01*
G02X1552400Y1251024I0J-200D01*
G01X1552486Y1250944D01*
G02X1552548Y1250824I-136J-146D01*
G03X1554932I1192J160D01*
G02X1554994Y1250944I198J-26D01*
G01X1555080Y1251024D01*
G02X1555217Y1251078I137J-146D01*
G01X1556003D01*
G02X1556140Y1251024I0J-200D01*
G01X1556226Y1250944D01*
G02X1556288Y1250824I-136J-146D01*
G03X1557280Y1249798I1192J160D01*
G01Y1249799D01*
G03X1557480Y1249782I201J1185D01*
G03X1557701Y1249803I-3J1202D01*
G01X1557751Y1249812D01*
X1557797Y1249798D01*
G02X1557879Y1249748I-60J-191D01*
G01X1557996Y1249630D01*
X1558113Y1249513D01*
G02X1558163Y1249431I-141J-142D01*
G01X1558177Y1249385D01*
X1558168Y1249335D01*
G03X1558147Y1249113I1181J-224D01*
G03X1558168Y1248891I1202J2D01*
G01X1558177Y1248842D01*
X1558163Y1248796D01*
G02X1558113Y1248714I-191J60D01*
G01X1557994Y1248595D01*
X1557879Y1248479D01*
G02X1557796Y1248429I-142J141D01*
G01X1557753Y1248416D01*
X1557703Y1248425D01*
X1557701D01*
G03X1557480Y1248445I-218J-1182D01*
G03X1558682Y1247243I0J-1202D01*
G03X1558661Y1247465I-1202J-2D01*
G01X1558652Y1247514D01*
X1558666Y1247560D01*
G02X1558716Y1247642I191J-60D01*
G01X1558835Y1247761D01*
X1558950Y1247877D01*
G02X1559033Y1247927I142J-141D01*
G01X1559076Y1247940D01*
X1559126Y1247931D01*
X1559128D01*
G03X1559349Y1247911I218J1182D01*
G03X1559572Y1247932I-1J1202D01*
G01X1559620Y1247941D01*
X1559667Y1247927D01*
G02X1559750Y1247877I-59J-191D01*
G01X1559984Y1247643D01*
G02X1560034Y1247561I-141J-142D01*
G01X1560048Y1247514D01*
X1560039Y1247465D01*
G03X1560018Y1247243I1181J-224D01*
G03X1561220Y1246041I1202J0D01*
G03X1561345Y1246047I5J1202D01*
G01X1561389Y1246051D01*
X1561426Y1246039D01*
G02X1561498Y1245997I-63J-190D01*
G01X1561719Y1245798D01*
G02X1561785Y1245650I-134J-148D01*
G01Y1245373D01*
G03X1561803Y1245159I1303J2D01*
G01X1561810Y1245112D01*
X1561797Y1245069D01*
G02X1561750Y1244988I-192J57D01*
G01X1561528Y1244756D01*
G02X1561453Y1244707I-144J139D01*
G01X1561409Y1244691D01*
X1561361Y1244697D01*
G03X1561220Y1244705I-138J-1194D01*
G03Y1242301I0J-1202D01*
G03X1561442Y1242322I-2J1202D01*
G01X1561491Y1242331D01*
X1561537Y1242317D01*
G02X1561619Y1242267I-60J-191D01*
G01X1561854Y1242032D01*
G02X1561904Y1241950I-141J-142D01*
G01X1561918Y1241904D01*
X1561909Y1241855D01*
G03X1561888Y1241633I1181J-224D01*
G03X1561909Y1241411I1202J2D01*
G01X1561918Y1241362D01*
X1561904Y1241316D01*
G02X1561854Y1241234I-191J60D01*
G01X1561619Y1240999D01*
G02X1561537Y1240949I-142J141D01*
G01X1561491Y1240935D01*
X1561442Y1240944D01*
G03X1561220Y1240965I-224J-1181D01*
G03Y1238561I0J-1202D01*
G03X1561364Y1238570I-3J1202D01*
G01X1561370Y1238571D01*
X1561411Y1238575D01*
X1561454Y1238560D01*
G02X1561532Y1238509I-67J-188D01*
G01X1561642Y1238394D01*
X1561754Y1238276D01*
G02X1561800Y1238199I-144J-138D01*
G01X1561814Y1238155D01*
X1561809Y1238126D01*
X1561806Y1238107D01*
G03X1561788Y1237893I1284J-216D01*
G03X1561806Y1237679I1302J2D01*
G01X1561809Y1237660D01*
X1561814Y1237631D01*
X1561800Y1237587D01*
G02X1561754Y1237510I-190J61D01*
G01X1561643Y1237393D01*
X1561532Y1237277D01*
G02X1561454Y1237226I-145J137D01*
G01X1561411Y1237211D01*
X1561370Y1237215D01*
X1561364Y1237216D01*
G03X1561220Y1237225I-147J-1193D01*
G03Y1234821I0J-1202D01*
G03X1561364Y1234830I-3J1202D01*
G01X1561370Y1234831D01*
X1561411Y1234835D01*
X1561454Y1234820D01*
G02X1561532Y1234769I-67J-188D01*
G01X1561642Y1234654D01*
X1561754Y1234536D01*
G02X1561800Y1234459I-144J-138D01*
G01X1561814Y1234415D01*
X1561809Y1234386D01*
X1561806Y1234367D01*
G03X1561788Y1234153I1284J-216D01*
G03X1561806Y1233939I1302J2D01*
G01X1561809Y1233920D01*
X1561814Y1233891D01*
X1561800Y1233847D01*
G02X1561754Y1233770I-190J61D01*
G01X1561643Y1233653D01*
X1561532Y1233537D01*
G02X1561454Y1233486I-145J137D01*
G01X1561411Y1233471D01*
X1561370Y1233475D01*
X1561364Y1233476D01*
G03X1561220Y1233485I-147J-1193D01*
G03Y1231081I0J-1202D01*
G03X1561364Y1231090I-3J1202D01*
G01X1561370Y1231091D01*
X1561411Y1231095D01*
X1561454Y1231080D01*
G02X1561532Y1231029I-67J-188D01*
G01X1561642Y1230914D01*
X1561754Y1230796D01*
G02X1561800Y1230719I-144J-138D01*
G01X1561814Y1230675D01*
X1561809Y1230646D01*
X1561806Y1230627D01*
G03X1561788Y1230413I1284J-216D01*
G03X1561806Y1230199I1302J2D01*
G01X1561809Y1230180D01*
X1561814Y1230151D01*
X1561800Y1230107D01*
G02X1561754Y1230030I-190J61D01*
G01X1561643Y1229913D01*
X1561532Y1229797D01*
G02X1561454Y1229746I-145J137D01*
G01X1561411Y1229731D01*
X1561370Y1229735D01*
X1561364Y1229736D01*
G03X1561220Y1229745I-147J-1193D01*
G03Y1227341I0J-1202D01*
G03X1561362Y1227349I3J1202D01*
G01X1561410Y1227355D01*
X1561452Y1227340D01*
G02X1561528Y1227290I-69J-188D01*
G01X1561752Y1227057D01*
G02X1561798Y1226978I-145J-138D01*
G01X1561812Y1226934D01*
X1561804Y1226886D01*
G03X1561786Y1226672I1284J-216D01*
G01Y1226396D01*
G02X1561720Y1226248I-200J0D01*
G01X1561499Y1226049D01*
G02X1561426Y1226007I-134J148D01*
G01X1561389Y1225995D01*
X1561346Y1225999D01*
G03X1561220Y1226005I-120J-1196D01*
G03Y1223601I0J-1202D01*
G03X1561346Y1223607I6J1202D01*
G01X1561389Y1223611D01*
X1561426Y1223599D01*
G02X1561499Y1223557I-61J-190D01*
G01X1561720Y1223358D01*
G02X1561786Y1223210I-134J-148D01*
G01Y1222932D01*
G03X1561804Y1222718I1302J2D01*
G01X1561807Y1222699D01*
X1561812Y1222670D01*
X1561798Y1222626D01*
G02X1561752Y1222549I-190J61D01*
G01X1561657Y1222449D01*
X1561530Y1222315D01*
G02X1561452Y1222265I-144J139D01*
G01X1561410Y1222250D01*
X1561363Y1222256D01*
G03X1561220Y1222264I-139J-1194D01*
G03Y1219860I0J-1202D01*
G03X1561442Y1219881I-2J1202D01*
G01X1561491Y1219890D01*
X1561537Y1219876D01*
G02X1561619Y1219826I-60J-191D01*
G01X1561854Y1219591D01*
G02X1561904Y1219509I-141J-142D01*
G01X1561918Y1219463D01*
X1561909Y1219414D01*
G03X1561888Y1219192I1181J-224D01*
G03X1564292I1202J0D01*
G03X1564271Y1219414I-1202J-2D01*
G01X1564262Y1219463D01*
X1564276Y1219509D01*
G02X1564326Y1219591I191J-60D01*
G01X1564561Y1219826D01*
G02X1564643Y1219876I142J-141D01*
G01X1564689Y1219890D01*
X1564738Y1219881D01*
G03X1564960Y1219860I224J1181D01*
G03X1565104Y1219869I-3J1202D01*
G01X1565110Y1219870D01*
X1565151Y1219874D01*
X1565193Y1219859D01*
G02X1565272Y1219808I-66J-189D01*
G01X1565382Y1219692D01*
X1565494Y1219576D01*
G02X1565540Y1219498I-145J-138D01*
G01X1565554Y1219454D01*
X1565549Y1219425D01*
X1565546Y1219406D01*
G03X1566744Y1217893I1284J-214D01*
G01X1566778Y1217891D01*
X1566874Y1217849D01*
G02X1566936Y1217808I-77J-184D01*
G01X1566996Y1217749D01*
G02X1567056Y1217606I-140J-143D01*
G01Y1217038D01*
G02X1567013Y1216915I-200J1D01*
G02X1566997Y1216896I-160J119D01*
G37*
G36*
G01X1508917Y54588D02*
X1537184D01*
X1537398Y54374D01*
Y52805D01*
X1537184Y52591D01*
X1508917D01*
G03X1502980Y46654I0J-5937D01*
G01Y7874D01*
G02X1497106Y2000I-5874J0D01*
G01X1449862D01*
G02X1443988Y7874I0J5874D01*
G01Y46654D01*
G03X1442424Y50670I-5938J0D01*
G01Y50786D01*
X1442657Y51019D01*
X1444546D01*
X1444895Y50670D01*
G02X1445986Y46656I-6843J-4015D01*
G01Y7874D01*
G03X1449862Y3998I3876J0D01*
G01X1497106D01*
G03X1500982Y7874I0J3876D01*
G01Y46654D01*
G02X1508917Y54588I7935J-1D01*
G37*
G36*
G01X1315590Y1155944D02*
X1444775D01*
G02X1444807Y1155941I-3J-200D01*
G01X1444809D01*
G02X1444915Y1155887I-34J-197D01*
G01X1447933Y1152869D01*
G02X1447987Y1152763I-143J-140D01*
G01Y1152761D01*
G02X1447990Y1152729I-197J-35D01*
G01Y1132793D01*
G03X1448049Y1132651I200J0D01*
G01X1450363Y1130337D01*
G03X1450505Y1130278I142J141D01*
G01X1460571D01*
G02X1460589Y1130279I20J-199D01*
G01X1494453D01*
G02X1494467Y1130278I-7J-200D01*
G02X1494585Y1130229I-14J-199D01*
G01X1494612Y1130205D01*
X1494645Y1130142D01*
X1494650Y1130104D01*
G03X1495223Y1129101I1490J186D01*
G01X1495234Y1129093D01*
X1495260Y1129067D01*
X1495276Y1129046D01*
G02X1495315Y1128938I-161J-119D01*
G01X1495316Y1128836D01*
G02X1495258Y1128697I-200J2D01*
G01X1495241Y1128680D01*
X1495220Y1128664D01*
X1495213Y1128659D01*
X1495210Y1128656D01*
X1495202Y1128650D01*
X1495195Y1128645D01*
G03X1494506Y1127291I986J-1354D01*
G03X1497864I1679J0D01*
G03X1497099Y1128699I-1678J0D01*
G01X1497087Y1128707D01*
G02X1497061Y1128731I122J158D01*
G02X1497031Y1128772I145J138D01*
G01X1497020Y1128793D01*
X1497009Y1128838D01*
X1497007Y1128958D01*
Y1129020D01*
X1497044Y1129079D01*
G02X1497077Y1129116I165J-114D01*
G01X1497088Y1129125D01*
X1497091Y1129128D01*
G03X1497630Y1130103I-951J1162D01*
G01Y1130104D01*
X1497631Y1130111D01*
G02X1497739Y1130258I197J-32D01*
G02X1497810Y1130278I89J-179D01*
G01X1497812D01*
G02X1497828Y1130279I20J-199D01*
G01X1499953D01*
G02X1499967Y1130278I-7J-200D01*
G02X1500085Y1130229I-14J-199D01*
G01X1500112Y1130205D01*
X1500145Y1130142D01*
X1500150Y1130104D01*
G03X1503130Y1130103I1490J186D01*
G01Y1130104D01*
X1503131Y1130111D01*
G02X1503239Y1130258I197J-32D01*
G02X1503310Y1130278I89J-179D01*
G01X1503312D01*
G02X1503328Y1130279I20J-199D01*
G01X1503443D01*
G02X1503457Y1130278I-7J-200D01*
G02X1503575Y1130229I-14J-199D01*
G01X1503602Y1130205D01*
X1503635Y1130142D01*
X1503640Y1130104D01*
G03X1506620Y1130103I1490J186D01*
G01Y1130104D01*
X1506621Y1130111D01*
G02X1506729Y1130258I197J-32D01*
G02X1506800Y1130278I89J-179D01*
G01X1506802D01*
G02X1506818Y1130279I20J-199D01*
G01X1512929D01*
G02X1512961Y1130276I-3J-200D01*
G01X1512963D01*
G02X1513069Y1130222I-34J-197D01*
G01X1513088Y1130203D01*
X1513289Y1129938D01*
X1513297Y1129921D01*
X1513301Y1129913D01*
G02X1513322Y1129824I-179J-89D01*
G01Y1129793D01*
X1513314Y1129766D01*
G03X1513266Y1129430I1154J-336D01*
G01Y1129402D01*
G03X1514468Y1128227I1202J27D01*
G03X1515670Y1129429I0J1202D01*
G03X1515629Y1129743I-1202J3D01*
G01X1515622Y1129768D01*
X1515609Y1129813D01*
X1515617Y1129858D01*
X1515625Y1129907D01*
X1515844Y1130199D01*
G02X1516004Y1130279I160J-120D01*
G01X1516669D01*
G02X1516701Y1130276I-3J-200D01*
G01X1516703D01*
G02X1516809Y1130222I-34J-197D01*
G01X1516828Y1130203D01*
X1517029Y1129938D01*
X1517037Y1129921D01*
X1517041Y1129913D01*
G02X1517062Y1129824I-179J-89D01*
G01Y1129793D01*
X1517054Y1129766D01*
G03X1517006Y1129430I1154J-336D01*
G01Y1129402D01*
G03X1518208Y1128227I1202J27D01*
G03X1519410Y1129429I0J1202D01*
G03X1519369Y1129743I-1202J3D01*
G01X1519362Y1129768D01*
X1519349Y1129813D01*
X1519357Y1129858D01*
X1519365Y1129907D01*
X1519584Y1130199D01*
G02X1519744Y1130279I160J-120D01*
G01X1559136D01*
G02X1559173Y1130275I-3J-200D01*
G01X1559175D01*
G02X1559276Y1130222I-39J-196D01*
G01X1559606Y1129892D01*
G02X1559660Y1129786I-143J-140D01*
G01Y1129784D01*
G02X1559663Y1129752I-197J-35D01*
G01Y1116068D01*
G02X1559615Y1115938I-200J0D01*
G01X1559553Y1115873D01*
X1559406Y1115719D01*
G02X1559354Y1115685I-134J148D01*
G01X1559323Y1115671D01*
X1559283Y1115668D01*
G03Y1113268I67J-1200D01*
G01X1559323Y1113265D01*
X1559354Y1113251D01*
G02X1559409Y1113214I-83J-182D01*
G01X1559587Y1113028D01*
X1559612Y1113002D01*
G02X1559661Y1112897I-149J-133D01*
G02X1559663Y1112869I-198J-28D01*
G01Y1097465D01*
G02X1559660Y1097429I-200J-1D01*
G02X1559651Y1097397I-197J38D01*
G01X1559639Y1097366D01*
X1559616Y1097339D01*
X1559608Y1097328D01*
X1559410Y1097122D01*
G02X1559284Y1097067I-138J145D01*
G01X1559250Y1097066D01*
X1559248D01*
G03X1558044Y1095767I99J-1299D01*
G01Y1092027D01*
G03X1558051Y1091892I1303J0D01*
G02X1557994Y1091730I-199J-21D01*
G01X1557741Y1091477D01*
X1557656Y1091448D01*
X1557636Y1091450D01*
G03X1557480Y1091459I-153J-1293D01*
G03X1556178Y1090193I0J-1303D01*
G01X1556177Y1090151D01*
X1556086Y1090018D01*
G02X1555998Y1089946I-165J112D01*
G03X1555317Y1089574I1485J-3527D01*
G01X1555303Y1089565D01*
X1555249Y1089540D01*
X1555236Y1089535D01*
G03X1555059Y1089468I372J-1249D01*
G03X1554362Y1088663I551J-1181D01*
G01X1554358Y1088649D01*
X1554332Y1088594D01*
X1554323Y1088580D01*
G03X1554266Y1088494I3161J-2157D01*
G03X1554107Y1088223I3218J-2070D01*
G02X1554086Y1088195I-170J106D01*
G02X1554055Y1088168I-146J137D01*
G03X1554043Y1088160I2116J-3187D01*
G01X1554042D01*
G03X1553942Y1088094I2058J-3226D01*
G01X1553907Y1088071D01*
X1553866Y1088064D01*
G02X1553783Y1088066I-37J196D01*
G01X1553495Y1088137D01*
G02X1553420Y1088173I47J194D01*
G01X1553387Y1088199D01*
X1553367Y1088236D01*
G03X1551482Y1089946I-3368J-1818D01*
G02X1551394Y1090018I77J184D01*
G01X1551303Y1090151D01*
X1551302Y1090193D01*
G03X1548698I-1302J-37D01*
G01X1548697Y1090151D01*
X1548607Y1090018D01*
G02X1548519Y1089946I-165J112D01*
G03X1548419Y1089902I1491J-3524D01*
G03X1548314Y1089852I1592J-3479D01*
G03X1547809Y1089554I1686J-3435D01*
G02X1547787Y1089544I-94J177D01*
G03X1547266Y1089262I343J-1256D01*
G03X1546880Y1088660I861J-977D01*
G01X1546876Y1088646D01*
X1546850Y1088591D01*
X1546841Y1088577D01*
G03X1546830Y1088562I3079J-2269D01*
G01Y1088560D01*
G03X1546633Y1088235I3170J-2143D01*
G02X1546610Y1088200I-178J92D01*
G02X1546562Y1088160I-150J132D01*
G03X1546548Y1088150I2213J-3113D01*
G01X1546546D01*
G03X1546092Y1087810I2061J-3224D01*
G03X1545993Y1087721I2508J-2890D01*
G01X1545988Y1087716D01*
X1545915Y1087673D01*
X1545891Y1087666D01*
G03X1545552Y1087510I369J-1248D01*
G03X1545006Y1086770I707J-1093D01*
G01X1545004Y1086764D01*
X1544960Y1086689D01*
X1544945Y1086672D01*
G03X1544364Y1085849I2808J-2599D01*
G01X1544361D01*
G03X1543088Y1084599I28J-1302D01*
G01X1543087Y1084563D01*
X1543056Y1084491D01*
X1543050Y1084475D01*
X1543016Y1084419D01*
X1543005Y1084406D01*
G03X1542382Y1083376I2879J-2445D01*
G01X1542367Y1083337D01*
X1541073Y1082043D01*
G02X1541006Y1081999I-141J142D01*
G01X1540972Y1081985D01*
X1540889D01*
X1540870Y1081988D01*
G03X1540649Y1082009I-224J-1181D01*
G03X1539447Y1080807I0J-1202D01*
G03X1539471Y1080568I1202J0D01*
G01Y1080567D01*
G02X1539417Y1080387I-196J-39D01*
G01X1539291Y1080261D01*
G03X1539232Y1080119I141J-142D01*
G01Y1076990D01*
G02X1539223Y1076934I-200J3D01*
G01X1539199Y1076865D01*
G02X1539168Y1076807I-190J64D01*
G03X1538367Y1074484I2976J-2326D01*
G01Y1074365D01*
X1538368D01*
Y1073959D01*
G02X1538027Y1073817I-200J0D01*
G01X1537990Y1073854D01*
X1537976Y1073881D01*
G03X1536909Y1074528I-1067J-556D01*
G03X1535707Y1073326I0J-1202D01*
G01Y1073324D01*
G03X1535721Y1073142I1202J1D01*
G01X1535724Y1073126D01*
X1535723D01*
G03X1536764Y1072132I1186J200D01*
G01X1536813Y1072127D01*
X1536850Y1072104D01*
G02X1536868Y1072092I-102J-172D01*
G02X1536912Y1072043I-125J-157D01*
G01X1537079Y1071785D01*
G02X1537110Y1071650I-167J-109D01*
G01X1537106Y1071621D01*
X1537101Y1071605D01*
G03X1536930Y1070482I3606J-1124D01*
G01Y1069002D01*
G02X1536928Y1068977I-200J3D01*
G01X1536920Y1068937D01*
X1536911Y1068905D01*
X1536908Y1068897D01*
X1536906Y1068891D01*
G03X1536650Y1067504I3635J-1388D01*
G01Y1046257D01*
G02X1536609Y1046136I-200J0D01*
G01X1536598Y1046124D01*
G03X1536596Y1046122I139J-141D01*
G01X1536590Y1046114D01*
X1536573Y1046097D01*
G03X1536530Y1045880I142J-141D01*
G01X1536561Y1045805D01*
X1536569Y1045785D01*
G03X1536571Y1045781I180J87D01*
G01X1536580Y1045764D01*
G03X1536601Y1045735I172J103D01*
G01X1536625Y1045707D01*
X1536637Y1045675D01*
G02X1536650Y1045604I-187J-71D01*
G01Y1043046D01*
G02X1536649Y1043022I-200J-4D01*
G01X1536575Y1042415D01*
X1536075Y1038245D01*
G03X1536048Y1037778I3899J-460D01*
G01Y1032740D01*
X1536277Y1009311D01*
X1536304Y1006557D01*
G02X1536303Y1006540I-200J3D01*
G01X1535957Y1002767D01*
X1533257Y973996D01*
X1531480Y955062D01*
X1530888Y948758D01*
G02X1530177Y948547I-398J38D01*
G03X1529000Y949115I-1177J-935D01*
G03X1528779Y949099I-2J-1503D01*
G01X1528750Y949097D01*
X1528721Y949099D01*
G03X1528500Y949115I-219J-1487D01*
G03Y946109I0J-1503D01*
G03X1528721Y946125I2J1503D01*
G01X1528750Y946127D01*
X1528779Y946125D01*
G03X1529000Y946109I219J1487D01*
G03X1529982Y946474I0J1503D01*
G02X1530642Y946134I262J-302D01*
G01X1529937Y938626D01*
X1529894Y938168D01*
X1529892Y938157D01*
X1529209Y934551D01*
X1529072Y933831D01*
G02X1528929Y933686I-194J49D01*
G01X1528903Y933679D01*
X1528588Y933591D01*
G02X1528388Y933646I-55J193D01*
G03X1528382Y933653I-1143J-974D01*
G01X1528379Y933657D01*
X1528367Y933672D01*
G03X1527267Y934150I-1099J-1025D01*
G01X1527230Y934149D01*
X1527228D01*
G03X1527193Y934148I25J-1502D01*
G01X1527167Y934146D01*
X1527166D01*
G03X1525765Y932647I101J-1499D01*
G03X1527267Y931145I1502J0D01*
G01X1527270D01*
G03X1527924Y931295I0J1502D01*
G01X1527943Y931304D01*
X1527989Y931315D01*
G02X1528037Y931321I49J-194D01*
G01X1528038D01*
G02X1528158Y931280I-1J-200D01*
G01X1528159D01*
X1528436Y931070D01*
G02X1528513Y930879I-121J-160D01*
G01X1527126Y923552D01*
X1526459Y920030D01*
X1524812Y911338D01*
G02X1524766Y911246I-196J40D01*
G01X1524730Y911210D01*
Y911208D01*
X1524683Y911160D01*
G02X1524646Y911132I-138J144D01*
G01X1524626Y911120D01*
X1524599Y911112D01*
G03X1523412Y909558I424J-1554D01*
G03X1524104Y908235I1611J0D01*
G01X1524113Y908229D01*
G02X1524175Y908147I-123J-158D01*
G01X1524187Y908120D01*
X1524190Y908091D01*
G02X1524187Y908036I-199J-17D01*
G01X1523174Y902687D01*
G02X1522978Y902534I-194J47D01*
G01X1522967D01*
G03X1522881Y902537I-95J-1500D01*
G01X1522880D01*
G03X1521378Y901034I1J-1503D01*
G03X1522029Y899796I1503J0D01*
G02X1522045Y899148I-226J-330D01*
G03X1521451Y897951I909J-1197D01*
G03X1521963Y896820I1505J0D01*
G01X1521982Y896801D01*
G02X1522022Y896732I-149J-133D01*
G01X1522030Y896710D01*
X1522033Y896661D01*
X1521670Y894741D01*
X1518979Y880535D01*
G02X1518787Y880381I-194J46D01*
G01X1518756Y880382D01*
G03X1518518Y880401I-238J-1484D01*
G01X1518517D01*
G03X1517014Y878898I0J-1503D01*
G03X1517666Y877659I1503J0D01*
G02X1517781Y877122I-227J-329D01*
G03X1517561Y876339I1283J-783D01*
G01Y876338D01*
G03X1517710Y875687I1501J1D01*
G01X1517711Y875684D01*
X1517713Y875680D01*
G02X1517714Y875678I-176J-89D01*
G01X1517741Y875618D01*
G02X1517638Y875043I-320J-239D01*
G03X1516949Y873780I813J-1263D01*
G03X1517404Y872703I1502J0D01*
G01X1517407Y872700D01*
G02X1517456Y872620I-141J-142D01*
G02X1517462Y872521I-190J-61D01*
G01X1516984Y869997D01*
X1514154Y855055D01*
X1511338Y840184D01*
X1510732Y836985D01*
X1510379Y835120D01*
G02X1510328Y835027I-195J46D01*
G01X1510307Y835005D01*
X1510255Y834977D01*
X1510225Y834971D01*
G03X1509035Y833676I302J-1471D01*
G01X1509029Y833620D01*
G03X1509024Y833500I1498J-123D01*
G03X1509705Y832243I1501J0D01*
G01X1509738Y832221D01*
X1509762Y832187D01*
G02X1509799Y832067I-163J-116D01*
G02X1509795Y832034I-200J8D01*
G01X1509288Y829358D01*
X1509129Y828522D01*
G02X1508955Y828370I-194J47D01*
G02X1508935Y828369I-20J199D01*
G01X1499429D01*
G02X1499373Y828377I0J200D01*
G02X1499355Y828383I54J193D01*
G01X1499319Y828398D01*
X1497842Y829875D01*
X1497833Y829888D01*
G03X1497719Y830025I-1210J-891D01*
G01X1497715Y830029D01*
G03X1497705Y830039I-1066J-1056D01*
G03X1497700Y830045I-156J-125D01*
G03X1497699Y830046I-1063J-1062D01*
G02X1497697Y830048I140J142D01*
G03X1497600Y830140I-1081J-1043D01*
G01X1497599Y830141D01*
G03X1497509Y830212I-975J-1143D01*
G01X1497496Y830221D01*
X1494513Y833204D01*
G02X1494469Y833271I142J141D01*
G01X1494455Y833305D01*
Y833399D01*
X1494465Y833429D01*
G03X1494540Y833892I-1427J469D01*
G01Y833904D01*
G03X1493038Y835400I-1502J-6D01*
G01X1493036D01*
G03X1492561Y835323I0J-1502D01*
G02X1492556Y835321I-77J184D01*
G01X1492513Y835308D01*
X1492489Y835301D01*
X1492437Y835316D01*
G02X1492361Y835356I53J193D01*
G02X1492342Y835374I128J154D01*
G01X1492340Y835376D01*
X1492325Y835393D01*
X1492315Y835409D01*
X1492306Y835425D01*
X1492258Y835563D01*
Y835565D01*
X1492245Y835599D01*
X1492248Y835678D01*
X1492265Y835714D01*
G02X1492360Y835811I182J-83D01*
G01X1492422Y835835D01*
X1492446Y835832D01*
G03X1492622Y835822I173J1492D01*
G01X1492625D01*
G03X1494127Y837324I0J1502D01*
G03X1492801Y838816I-1502J0D01*
G01X1492741Y838823D01*
G03X1492625Y838827I-110J-1499D01*
G03X1491364Y838145I0J-1507D01*
G01X1491357Y838134D01*
X1491355Y838130D01*
X1491351Y838125D01*
X1491336Y838110D01*
G02X1491302Y838084I-138J145D01*
G01X1491244Y838048D01*
G03X1491232Y838040I105J-170D01*
G01X1491220Y838032D01*
X1491194Y838022D01*
G02X1491151Y838012I-67J189D01*
G01X1490961Y837990D01*
X1490925Y837986D01*
X1490885Y837981D01*
X1490837D01*
G02X1490804Y837989I31J198D01*
G01X1490775Y837999D01*
X1490735Y838024D01*
X1490720Y838040D01*
G03X1489651Y838487I-1069J-1055D01*
G01X1489614D01*
G03X1489443Y838473I37J-1503D01*
G03X1489386Y838464I206J-1488D01*
G01X1489377Y838462D01*
X1489341Y838459D01*
G02X1489200Y838517I0J200D01*
G01X1473205Y854512D01*
G03X1473063Y854571I-142J-141D01*
G01X1472613D01*
G02X1472492Y854612I0J200D01*
G01X1472480Y854623D01*
G03X1472478Y854625I-143J-141D01*
G01X1472470Y854631D01*
X1466789Y860312D01*
G02X1466730Y860454I141J142D01*
G01Y906478D01*
G03X1466348Y907400I-1306J-1D01*
G01X1448573Y925175D01*
G03X1447649Y925558I-924J-923D01*
G01X1447613D01*
G02X1447441Y925656I0J200D01*
G01X1447392Y925746D01*
X1447269Y925974D01*
G02X1447245Y926077I176J95D01*
G01X1447247Y926130D01*
X1447269Y926163D01*
G03X1447524Y927000I-1248J837D01*
G03X1446022Y928502I-1502J0D01*
G03X1444520Y927017I0J-1502D01*
G01Y926999D01*
G03X1444787Y926146I1502J2D01*
G01Y926145D01*
G02X1444823Y926043I-164J-115D01*
G01X1444826Y925988D01*
X1444627Y925612D01*
G02X1444578Y925558I-170J105D01*
G01X1403160D01*
G02X1403112Y925564I1J200D01*
G02X1403040Y925598I48J195D01*
G02X1403035Y925602I123J158D01*
G01X1402472Y926165D01*
G02X1402454Y926190I153J129D01*
G01X1402442Y926211D01*
X1402440Y926218D01*
G03X1401000Y927291I-1440J-430D01*
G03X1399498Y925789I0J-1502D01*
G03X1400554Y924354I1503J0D01*
G01X1400556D01*
G02X1400636Y924305I-62J-190D01*
G01X1401614Y923327D01*
G03X1402538Y922944I924J923D01*
G01X1446967D01*
G02X1446987Y922927I-119J-161D01*
G01X1455573Y914342D01*
X1462461Y907454D01*
G02X1462515Y907270I-141J-141D01*
G01X1462512Y907255D01*
X1462404Y906913D01*
G02X1462247Y906776I-191J60D01*
G03X1460998Y905295I254J-1481D01*
G03X1462500Y903793I1502J0D01*
G01X1462501D01*
G03X1463468Y904146I0J1502D01*
G01X1463494Y904168D01*
X1463540Y904186D01*
X1463546Y904188D01*
G03X1463559Y904193I-65J189D01*
G01X1463562Y904195D01*
X1463600Y904211D01*
X1463639D01*
G02X1463721Y904193I-1J-200D01*
G01X1463944Y904093D01*
X1464042Y904049D01*
G02X1464118Y903988I-83J-182D01*
G01Y863092D01*
G02X1463958Y863012I-160J120D01*
G01X1450352D01*
G02X1450011Y863620I1J400D01*
G03X1450229Y864400I-1286J780D01*
G03X1447223I-1503J0D01*
G03X1447441Y863620I1504J0D01*
G02X1447100Y863012I-342J-208D01*
G01X1436492D01*
G02X1436371Y863053I0J200D01*
G01X1436359Y863064D01*
G03X1436357Y863066I-143J-141D01*
G01X1436349Y863072D01*
X1418896Y880525D01*
X1418892Y880530D01*
G03X1418879Y880544I-1108J-1015D01*
G01X1418878Y880545D01*
G03X1418874Y880549I-1064J-1060D01*
G02X1418872Y880551I140J142D01*
G03X1418811Y880611I-1084J-1041D01*
G01X1418807Y880614D01*
X1414915Y884506D01*
X1414898Y884548D01*
X1414897Y884550D01*
G03X1414045Y885399I-1397J-550D01*
G01X1414006Y885415D01*
X1413582Y885839D01*
G02X1413538Y885906I142J141D01*
G01X1413524Y885940D01*
Y886013D01*
G02X1413527Y886045I200J-3D01*
G01X1413534Y886088D01*
X1413629Y886396D01*
X1413631Y886401D01*
X1413639Y886419D01*
G02X1413683Y886476I177J-92D01*
G01Y886477D01*
G02X1413765Y886521I133J-150D01*
G01X1413780Y886524D01*
G03X1415002Y888000I-280J1476D01*
G03X1413500Y889502I-1502J0D01*
G01X1413499D01*
G03X1412565Y889176I0J-1502D01*
G01X1412547Y889162D01*
X1412534Y889151D01*
G03X1412023Y888280I965J-1152D01*
G01X1412022Y888270D01*
X1412018Y888253D01*
X1411995Y888205D01*
X1411972Y888180D01*
G02X1411887Y888126I-146J136D01*
G01X1411538Y888019D01*
G02X1411349Y888072I-47J194D01*
G01X1405582Y893839D01*
G02X1405538Y893906I142J141D01*
G01X1405524Y893940D01*
Y894013D01*
G02X1405527Y894045I200J-3D01*
G01X1405534Y894088D01*
X1405629Y894396D01*
X1405631Y894401D01*
X1405639Y894419D01*
G02X1405683Y894476I177J-92D01*
G01Y894477D01*
G02X1405765Y894521I133J-150D01*
G01X1405780Y894524D01*
G03X1407002Y896000I-280J1476D01*
G03X1405500Y897502I-1502J0D01*
G01X1405499D01*
G03X1404565Y897176I0J-1502D01*
G01X1404547Y897162D01*
X1404534Y897151D01*
G03X1404023Y896280I965J-1152D01*
G01X1404022Y896270D01*
X1404018Y896253D01*
X1403995Y896205D01*
X1403972Y896180D01*
G02X1403887Y896126I-146J136D01*
G01X1403538Y896019D01*
G02X1403349Y896072I-47J194D01*
G01X1401747Y897674D01*
G02X1401691Y897844I142J141D01*
G01X1402365Y898517D01*
G02X1402445Y898566I142J-141D01*
G01X1402446D01*
G03X1403502Y900000I-446J1434D01*
G01Y900013D01*
G03X1403369Y900618I-1502J-13D01*
G01Y900619D01*
G02X1403410Y900842I182J82D01*
G01X1403791Y901223D01*
Y901224D01*
X1404244Y901677D01*
G02X1404264Y901694I139J-144D01*
G01X1405500D01*
G03Y906306I0J2306D01*
G01X1401999D01*
G03X1400369Y905631I0J-2306D01*
G01X1397221Y902482D01*
G02X1397148Y902436I-141J142D01*
G02X1397008Y902437I-69J188D01*
G02X1396940Y902481I72J187D01*
G01X1396272Y903149D01*
G02X1396228Y903216I142J141D01*
G01X1396214Y903250D01*
Y914018D01*
G02X1396224Y914079I200J-1D01*
G01X1396234Y914109D01*
X1396240Y914121D01*
G03X1396393Y914761I-1349J661D01*
G01Y914786D01*
G03X1396235Y915455I-1502J-2D01*
G01X1396224Y915477D01*
X1396214Y915520D01*
Y915756D01*
G02X1396294Y915916I200J0D01*
G01X1402100D01*
G02X1402220Y915876I0J-200D01*
G02X1402241Y915858I-119J-160D01*
G01X1403288Y914810D01*
G02X1403306Y914785I-153J-129D01*
G01X1403318Y914764D01*
X1403320Y914757D01*
G03X1404760Y913684I1440J430D01*
G03X1406262Y915186I0J1502D01*
G03X1405184Y916627I-1502J0D01*
G01X1405159Y916635D01*
X1403648Y918146D01*
G03X1403571Y918217I-923J-924D01*
G03X1403409Y918334I-844J-997D01*
G02X1403406Y918336I109J167D01*
G02X1403374Y918362I109J167D01*
G01X1403307Y918429D01*
G03X1403165Y918488I-142J-141D01*
G01X1403048D01*
X1403025Y918493D01*
G03X1402725Y918528I-300J-1271D01*
G01X1396294D01*
G02X1396214Y918688I120J160D01*
G01Y944652D01*
G02X1396217Y944684I200J-3D01*
G01Y944686D01*
G02X1396271Y944792I197J-34D01*
G01X1432114Y980635D01*
G02X1432215Y980688I140J-143D01*
G01X1432217D01*
G02X1432254Y980692I40J-196D01*
G01X1432529D01*
X1432559Y980689D01*
X1432605Y980684D01*
X1432712Y980621D01*
G02X1432749Y980592I-104J-171D01*
G01X1432764Y980578D01*
X1432777Y980558D01*
X1432804Y980522D01*
G03X1432905Y980404I1191J917D01*
G01X1432929Y980378D01*
X1432965Y980297D01*
G02X1432925Y980086I-186J-74D01*
G01X1418757Y965918D01*
G03X1418698Y965776I141J-142D01*
G01Y957706D01*
G03X1418757Y957564I200J0D01*
G01X1419257Y957064D01*
G02X1419259Y957062I-140J-142D01*
G03X1419309Y957012I1440J1390D01*
G02X1419311Y957010I-140J-142D01*
G01X1419811Y956510D01*
G03X1419953Y956451I142J141D01*
G01X1420656D01*
G03X1420696Y956450I70J2000D01*
G03X1420702I3J200D01*
G03X1420742Y956451I-30J2001D01*
G01X1421445D01*
G03X1421587Y956510I0J200D01*
G01X1422087Y957010D01*
G02X1422089Y957012I142J-140D01*
G03X1422139Y957062I-1390J1440D01*
G02X1422141Y957064I142J-140D01*
G01X1422641Y957564D01*
G03X1422700Y957706I-141J142D01*
G01Y962910D01*
G02X1422703Y962942I200J-3D01*
G01Y962944D01*
G02X1422757Y963050I197J-34D01*
G01X1438519Y978812D01*
X1438522Y978814D01*
G03X1438623Y978915I-1365J1466D01*
G01X1438625Y978918D01*
X1439099Y979392D01*
G03X1439158Y979534I-141J142D01*
G01Y980211D01*
G03X1439160Y980271I-2000J97D01*
G02X1439162Y980295I200J-5D01*
G02X1439798Y980562I396J-53D01*
G03X1440700Y980261I902J1201D01*
G03Y983265I0J1502D01*
G03X1439528Y982702I0J-1501D01*
G01X1439524Y982696D01*
X1439514Y982685D01*
G02X1439329Y982625I-146J136D01*
G01X1439243Y982668D01*
G02X1439218Y982684I95J176D01*
G01X1439197Y982701D01*
X1439178Y982741D01*
G02X1439160Y982800I180J87D01*
G01Y982968D01*
G02X1439161Y982974I198J-30D01*
G01Y982976D01*
G02X1439215Y983082I197J-34D01*
G01X1454822Y998689D01*
G03X1454849Y998716I-1401J1429D01*
G01X1455167Y999034D01*
G02X1455218Y999071I141J-141D01*
G02X1455345Y999089I90J-179D01*
G01X1455365Y999084D01*
G02X1455438Y999045I-56J-192D01*
G01X1455450Y999033D01*
G02X1455495Y998962I-142J-140D01*
G01X1455508Y998922D01*
X1455509Y998873D01*
X1455503Y998847D01*
G03X1455464Y998507I1463J-340D01*
G03X1456884Y997007I1502J0D01*
G01X1456916Y997005D01*
X1456968Y996986D01*
X1456991Y996970D01*
G02X1457052Y996896I-119J-160D01*
G03X1457054Y996894I135J133D01*
G02X1457059Y996882I-182J-83D01*
G01X1457197Y996521D01*
G02X1457157Y996337I-193J-54D01*
G01X1456563Y995743D01*
X1455950Y995129D01*
X1451137Y990317D01*
G03X1450580Y988972I1345J-1345D01*
G01Y972003D01*
G02X1450572Y971947I-200J0D01*
G02X1450566Y971929I-193J54D01*
G01X1450551Y971893D01*
X1437686Y959028D01*
G03X1437320Y958514I1345J-1345D01*
G03X1437218Y958259I1710J-832D01*
G01Y958257D01*
G03X1437188Y958151I1814J-571D01*
G01Y958149D01*
G03X1437130Y957685I1843J-466D01*
G01Y957683D01*
G03X1439031Y955782I1901J0D01*
G03X1439687Y955898I2J1901D01*
G03X1440376Y956338I-655J1785D01*
G01X1453827Y969789D01*
G03X1454384Y971134I-1345J1345D01*
G01Y988101D01*
G02X1454388Y988138I200J-3D01*
G01Y988140D01*
G02X1454441Y988241I196J-39D01*
G01X1470214Y1004014D01*
G03X1470580Y1004528I-1345J1345D01*
G03X1470682Y1004783I-1710J832D01*
G01Y1004785D01*
G03X1470712Y1004891I-1814J571D01*
G01Y1004893D01*
G03X1470770Y1005357I-1843J466D01*
G01Y1012847D01*
X1470771Y1018469D01*
G03X1470263Y1019763I-1902J0D01*
G03X1470262Y1019765I-175J-86D01*
G01X1470261Y1019766D01*
G03X1470257Y1019770I-143J-139D01*
G02X1470255Y1019771I84J171D01*
G02X1470253Y1019773I282J284D01*
G03X1470245Y1019782I-1425J-1259D01*
G03X1470240Y1019787I-144J-139D01*
G01X1470239Y1019788D01*
G03X1470237Y1019790I-142J-140D01*
G02X1470503Y1020455I298J267D01*
G01X1470507D01*
G02X1470520Y1020456I22J-198D01*
G01X1479501D01*
G02X1479619Y1020407I-14J-199D01*
G01X1481875Y1018151D01*
X1484615Y1015412D01*
G03X1484642Y1015385I1428J1402D01*
G01X1485142Y1014885D01*
G03X1485284Y1014826I142J141D01*
G01X1486776D01*
G03X1486918Y1014885I0J200D01*
G01X1487418Y1015385D01*
G02X1487420Y1015387I142J-140D01*
G03X1487470Y1015437I-1390J1440D01*
G02X1487472Y1015439I142J-140D01*
G01X1487972Y1015939D01*
G03X1488031Y1016081I-141J142D01*
G01Y1016784D01*
G03X1488032Y1016824I-2000J70D01*
G03Y1016830I-200J3D01*
G03X1488031Y1016870I-2001J-30D01*
G01Y1017573D01*
G03X1487972Y1017715I-200J0D01*
G01X1487472Y1018215D01*
G03X1487445Y1018242I-1429J-1401D01*
G01X1483301Y1022386D01*
G02X1483364Y1023002I284J282D01*
G03X1484037Y1024254I-828J1252D01*
G03X1482535Y1025756I-1502J0D01*
G03X1481076Y1024611I0J-1502D01*
G02X1481030Y1024524I-195J47D01*
G02X1480896Y1024459I-148J135D01*
G01X1480442D01*
G03X1480399Y1024460I-68J-2000D01*
G01X1468817D01*
G03X1468774Y1024459I25J-2001D01*
G01X1468071D01*
G03X1467929Y1024400I0J-200D01*
G01X1467882Y1024353D01*
G02X1467231Y1024481I-282J283D01*
G03X1465846Y1025402I-1385J-581D01*
G03X1464344Y1023900I0J-1502D01*
G01Y1023839D01*
G03X1464398Y1023494I1502J58D01*
G01X1464403Y1023471D01*
G02X1464039Y1023011I-395J-62D01*
G01X1464035D01*
G02X1464023Y1023010I-23J198D01*
G01X1461646D01*
G03X1461603Y1023009I25J-2001D01*
G01X1460900D01*
G03X1460758Y1022950I0J-200D01*
G01X1460258Y1022450D01*
G03X1460231Y1022423I1402J-1429D01*
G01X1457713Y1019905D01*
G03X1457685Y1019877I1401J-1429D01*
G01X1452638Y1014830D01*
G02X1451955Y1015112I-283J283D01*
G01Y1016161D01*
G03X1451896Y1016303I-200J0D01*
G01X1451125Y1017074D01*
G02X1451081Y1017141I142J141D01*
G01X1451067Y1017175D01*
Y1021138D01*
G02X1451069Y1021165I200J-1D01*
G01X1456915Y1027011D01*
G02X1456937Y1027030I141J-141D01*
G02X1457057Y1027070I120J-160D01*
G01X1458889D01*
G02X1458982Y1027047I0J-200D01*
G03X1459669Y1026874I700J1330D01*
G01X1459703Y1026875D01*
X1459704D01*
G03X1461185Y1028377I-21J1502D01*
G03X1459707Y1029879I-1502J0D01*
G01X1459682Y1029880D01*
X1459681D01*
G03X1458983Y1029707I2J-1503D01*
G02X1458890Y1029684I-93J177D01*
G01X1456433D01*
G03X1455509Y1029301I0J-1306D01*
G01X1447452Y1021244D01*
G03X1447070Y1020322I924J-923D01*
G01Y1006128D01*
G02X1447051Y1006105I-163J115D01*
G01X1426053Y985107D01*
G02X1425986Y985063I-141J142D01*
G01X1425952Y985049D01*
X1416031D01*
G02X1415943Y985077I15J200D01*
G02X1415902Y985109I101J172D01*
G01X1415701Y985315D01*
G02X1415659Y985379I143J140D01*
G01X1415655Y985390D01*
X1415645Y985414D01*
Y985486D01*
G03X1412641I-1502J0D01*
G01Y985457D01*
X1412642Y985417D01*
X1412627Y985379D01*
G02X1412585Y985315I-185J76D01*
G01X1412380Y985105D01*
G02X1412256Y985050I-138J144D01*
G02X1412241Y985049I-21J199D01*
G01X1331186D01*
G02X1330986Y985249I0J200D01*
G01Y986608D01*
G02X1331090Y986783I200J0D01*
G01X1331446Y986979D01*
X1331554Y986975D01*
X1331600Y986946D01*
G03X1332403Y986713I804J1269D01*
G01X1332404D01*
G03X1333906Y988215I0J1502D01*
G03X1333883Y988476I-1502J-1D01*
G01Y988477D01*
G02X1333951Y988664I197J34D01*
G01X1334254Y988922D01*
X1334359Y988941D01*
X1334409Y988923D01*
G03X1334908Y988838I498J1417D01*
G01X1334910D01*
G03X1335486Y988953I0J1502D01*
G02X1335689Y988925I78J-184D01*
G01X1336005Y988671D01*
X1336043Y988570D01*
X1336034Y988516D01*
G03X1336012Y988261I1480J-256D01*
G01Y988259D01*
G03X1337514Y989761I1502J0D01*
G01X1337513D01*
G03X1336937Y989646I0J-1502D01*
G02X1336734Y989674I-78J184D01*
G01X1336418Y989928D01*
X1336380Y990029D01*
X1336389Y990083D01*
G03X1336411Y990338I-1480J256D01*
G01Y990340D01*
G03X1333407I-1502J0D01*
G03X1333430Y990079I1502J1D01*
G01Y990078D01*
G02X1333362Y989891I-197J-34D01*
G01X1333059Y989633D01*
X1332954Y989614D01*
X1332904Y989632D01*
G03X1332406Y989717I-498J-1417D01*
G01X1332404D01*
G03X1331292Y989225I0J-1503D01*
G02X1331150Y989159I-149J134D01*
G01X1331116Y989158D01*
G02X1330965Y989219I-7J200D01*
G03X1330840Y989336I-1133J-1085D01*
G01X1330839Y989373D01*
X1330849Y989420D01*
X1330859Y989441D01*
G03X1331005Y990086I-1356J646D01*
G01Y990088D01*
G03X1330938Y990529I-1502J-3D01*
G02Y990647I192J59D01*
G03X1331005Y991088I-1435J444D01*
G03X1328001I-1502J0D01*
G03X1328068Y990647I1502J3D01*
G02X1328067Y990529I-192J-57D01*
G03X1328056Y990490I1440J-427D01*
G03X1328019Y990319I1447J-403D01*
G03X1328002Y990135I1484J-230D01*
G01Y990133D01*
X1328000Y990090D01*
X1327976Y990041D01*
G02X1327934Y989987I-176J94D01*
G01X1327890Y989951D01*
G02X1327888Y989949I-142J140D01*
G01X1327692Y989791D01*
G02X1327616Y989752I-127J154D01*
G01X1327576Y989742D01*
X1327546Y989748D01*
G03X1327267Y989773I-273J-1477D01*
G03X1326767Y989688I-2J-1502D01*
G01X1326766D01*
G02X1326675Y989678I-67J188D01*
G01X1326630Y989683D01*
X1326323Y989888D01*
G02X1326260Y989957I112J166D01*
G01X1326238Y989996D01*
X1326235Y990044D01*
Y990045D01*
G03X1324911Y991458I-1500J-79D01*
G01X1324861Y991464D01*
G03X1324735Y991469I-123J-1498D01*
G03X1323430Y990713I0J-1504D01*
G01X1323416Y990689D01*
X1323390Y990660D01*
X1323370Y990647D01*
G02X1323290Y990616I-111J167D01*
G01X1322965Y990572D01*
G02X1322802Y990630I-21J199D01*
G01X1319070Y994362D01*
G02X1319026Y994429I142J141D01*
G01X1319012Y994463D01*
Y1018788D01*
G02X1319212Y1018988I200J0D01*
G01X1345032D01*
G03X1345174Y1019047I0J200D01*
G01X1347353Y1021226D01*
G03X1347412Y1021368I-141J142D01*
G01Y1030228D01*
G03X1347353Y1030370I-200J0D01*
G01X1345175Y1032548D01*
G03X1345033Y1032607I-142J-141D01*
G01X1335815D01*
G02X1335665Y1032676I1J200D01*
G01X1335461Y1032938D01*
G02X1335428Y1033106I161J119D01*
G01Y1033107D01*
G03X1335432Y1033121I-1442J419D01*
G01X1335434Y1033129D01*
G03X1335476Y1033480I-1460J353D01*
G01Y1033483D01*
G03X1332472I-1502J0D01*
G01Y1033480D01*
G03X1332514Y1033128I1502J1D01*
G01X1332520Y1033104D01*
Y1033007D01*
G02X1332485Y1032935I-194J50D01*
G01X1332478Y1032926D01*
X1332289Y1032682D01*
G02X1332147Y1032607I-157J125D01*
G01X1314082D01*
G02X1313991Y1032629I0J200D01*
G02X1313941Y1032665I90J178D01*
G01X1303832Y1042774D01*
G02X1303796Y1042824I142J140D01*
G02X1303774Y1042915I178J91D01*
G01Y1088490D01*
G02X1303796Y1088581I200J0D01*
G02X1303832Y1088631I178J-90D01*
G01X1303869Y1088668D01*
G03X1303932Y1088738I-861J838D01*
G01X1303951Y1088762D01*
G03X1304214Y1089511I-938J750D01*
G01Y1115312D01*
G02X1304218Y1115349I200J-3D01*
G01Y1115351D01*
G02X1304271Y1115452I196J-39D01*
G01X1306198Y1117379D01*
G03X1306257Y1117521I-141J142D01*
G01Y1127660D01*
G02X1306306Y1127791I200J0D01*
G01X1306328Y1127817D01*
X1306391Y1127852D01*
X1306428Y1127857D01*
G03X1317818Y1141596I-1901J13167D01*
G03X1316108Y1147570I-13291J-573D01*
G01X1316091Y1147601D01*
X1316092Y1147707D01*
X1316111Y1147739D01*
X1316296Y1148055D01*
G02X1316465Y1148150I170J-105D01*
G01X1344942D01*
G02X1345033Y1148128I0J-200D01*
G02X1345083Y1148092I-90J-178D01*
G01X1345580Y1147595D01*
G02X1345616Y1147545I-142J-140D01*
G02X1345638Y1147454I-178J-91D01*
G01Y1133211D01*
G02X1345579Y1133069I-200J0D01*
G01X1342487Y1129976D01*
G03X1341974Y1128738I1237J-1238D01*
G03X1343725Y1126986I1752J0D01*
G03X1344963Y1127500I-1J1751D01*
G01X1345057Y1127594D01*
G02X1345275Y1127637I141J-142D01*
G01X1345331Y1127614D01*
X1345398Y1127514D01*
Y1125787D01*
G02X1345339Y1125645I-200J0D01*
G01X1340456Y1120762D01*
G03X1339900Y1119420I1346J-1344D01*
G01Y1114629D01*
G03X1340456Y1113287I1902J2D01*
G01X1341591Y1112153D01*
G02X1341645Y1111970I-142J-141D01*
G01X1341575Y1111641D01*
G02X1341451Y1111496I-196J42D01*
G01X1341450D01*
G03X1340482Y1110092I534J-1404D01*
G03X1341984Y1108590I1502J0D01*
G03X1343388Y1109558I0J1502D01*
G01Y1109559D01*
G02X1343533Y1109683I187J-72D01*
G01X1343861Y1109753D01*
G02X1344045Y1109699I43J-195D01*
G01X1344534Y1109210D01*
G02X1344592Y1109068I-142J-141D01*
G01Y1108199D01*
G02X1344535Y1108060I-200J1D01*
G01X1344313Y1107832D01*
X1344242Y1107801D01*
X1344203Y1107800D01*
G03X1342739Y1106298I38J-1502D01*
G03X1344241Y1104796I1502J0D01*
G03X1345124Y1105083I0J1502D01*
G01X1345143Y1105097D01*
X1345165Y1105106D01*
G02X1345427Y1104998I77J-185D01*
G01X1345483Y1104861D01*
G03X1345895Y1104243I1758J726D01*
G01X1346718Y1103420D01*
G03X1348060Y1102864I1344J1346D01*
G01X1357522D01*
G03X1358864Y1103420I-2J1902D01*
G01X1362612Y1107169D01*
G02X1362831Y1107212I141J-141D01*
G01X1363172Y1107069D01*
G02X1363295Y1106883I-77J-185D01*
G01Y1106867D01*
G03X1363304Y1106699I1502J-4D01*
G02X1363267Y1106560I-199J-21D01*
G01X1363108Y1106341D01*
G02X1362988Y1106263I-162J118D01*
G01X1362987D01*
G03X1361788Y1104792I303J-1471D01*
G03X1364792I1502J0D01*
G03X1364783Y1104960I-1502J4D01*
G02X1364820Y1105099I199J21D01*
G01X1364978Y1105317D01*
G02X1365101Y1105396I162J-117D01*
G01X1365103Y1105397D01*
G02X1365268Y1105356I39J-196D01*
G01X1365508Y1105160D01*
G02X1365582Y1105005I-126J-155D01*
G01Y1103577D01*
G02X1365523Y1103435I-200J0D01*
G01X1363110Y1101022D01*
G03X1362670Y1099960I1062J-1062D01*
G01Y1098520D01*
G02X1362611Y1098378I-200J0D01*
G01X1361634Y1097401D01*
G02X1361492Y1097342I-142J141D01*
G01X1360246D01*
G02X1360104Y1097401I0J200D01*
G01X1355902Y1101603D01*
G03X1354842Y1102042I-1061J-1062D01*
G01X1345980D01*
G03X1344920Y1101603I1J-1501D01*
G01X1340718Y1097401D01*
G02X1340576Y1097342I-142J141D01*
G01X1338845D01*
G02X1338703Y1097400I-1J200D01*
G01X1338489Y1097614D01*
G02X1338430Y1097756I141J142D01*
G01Y1100058D01*
G02X1338505Y1100214I200J0D01*
G01X1338783Y1100438D01*
X1338871Y1100458D01*
X1338915Y1100449D01*
G03X1339232Y1100415I318J1468D01*
G01X1339234D01*
G03X1340736Y1101917I0J1502D01*
G03X1339321Y1103416I-1501J0D01*
G01X1339320D01*
G02X1339170Y1103500I13J199D01*
G01X1338962Y1103792D01*
X1338947Y1103881D01*
X1338959Y1103925D01*
G03X1339016Y1104335I-1446J410D01*
G03X1338921Y1104860I-1502J-1D01*
G01X1338904Y1104904D01*
X1338915Y1104998D01*
X1339115Y1105307D01*
G02X1339269Y1105398I168J-108D01*
G03X1340671Y1106897I-100J1499D01*
G03X1337667I-1502J0D01*
G03X1337762Y1106372I1502J1D01*
G01X1337779Y1106328D01*
X1337768Y1106234D01*
X1337568Y1105925D01*
G02X1337414Y1105834I-168J108D01*
G03X1336934Y1105721I100J-1499D01*
G02X1336770Y1105725I-78J184D01*
G01X1336502Y1105852D01*
G02X1336396Y1105976I86J181D01*
G03X1334956Y1107054I-1440J-423D01*
G03X1334592Y1107009I1J-1502D01*
G02X1334443Y1107030I-49J194D01*
G01X1334169Y1107187D01*
X1334123Y1107247D01*
X1334112Y1107285D01*
G03X1332669Y1108369I-1443J-418D01*
G03X1331167Y1106867I0J-1502D01*
G03X1331176Y1106699I1502J-4D01*
G02X1331139Y1106560I-199J-21D01*
G01X1330980Y1106341D01*
G02X1330860Y1106263I-162J118D01*
G01X1330859D01*
G03X1329660Y1104792I303J-1471D01*
G03X1332664I1502J0D01*
G03X1332655Y1104960I-1502J4D01*
G02X1332692Y1105099I199J21D01*
G01X1332850Y1105317D01*
G02X1332973Y1105396I162J-117D01*
G01X1332975Y1105397D01*
G02X1333140Y1105356I39J-196D01*
G01X1333380Y1105160D01*
G02X1333454Y1105005I-126J-155D01*
G01Y1103819D01*
G02X1333395Y1103677I-200J0D01*
G01X1332314Y1102595D01*
G02X1332172Y1102536I-142J141D01*
G01X1330437D01*
G03X1329377Y1102097I1J-1501D01*
G01X1328182Y1100902D01*
G03X1327742Y1099840I1062J-1062D01*
G01Y1097888D01*
G03X1328182Y1096826I1502J0D01*
G01X1335341Y1089667D01*
G02X1335400Y1089525I-141J-142D01*
G01Y1057470D01*
G03X1335840Y1056408I1502J0D01*
G01X1343374Y1048874D01*
G03X1344436Y1048434I1062J1062D01*
G01X1352700D01*
G02X1352842Y1048375I0J-200D01*
G01X1362399Y1038818D01*
G03X1363461Y1038378I1062J1062D01*
G01X1366265D01*
G03Y1041382I0J1502D01*
G01X1364166D01*
G02X1364024Y1041441I0J200D01*
G01X1354467Y1050998D01*
G03X1353405Y1051438I-1062J-1062D01*
G01X1345141D01*
G02X1344999Y1051497I0J200D01*
G01X1338463Y1058033D01*
G02X1338404Y1058175I141J142D01*
G01Y1090230D01*
G03X1337964Y1091292I-1502J0D01*
G01X1330805Y1098451D01*
G02X1330746Y1098593I141J142D01*
G01Y1099135D01*
G02X1330804Y1099277I200J1D01*
G01X1331002Y1099475D01*
G02X1331144Y1099534I142J-141D01*
G01X1332879D01*
G03X1333939Y1099973I-1J1501D01*
G01X1334815Y1100849D01*
G02X1335097Y1100850I142J-141D01*
G01X1335369Y1100578D01*
G02X1335428Y1100436I-141J-142D01*
G01Y1097049D01*
G03X1335867Y1095989I1501J1D01*
G01X1337078Y1094778D01*
G03X1338140Y1094338I1062J1062D01*
G01X1341281D01*
G03X1342343Y1094778I0J1502D01*
G01X1346545Y1098981D01*
G02X1346687Y1099040I142J-141D01*
G01X1354135D01*
G02X1354277Y1098981I0J-200D01*
G01X1358479Y1094778D01*
G03X1359541Y1094338I1062J1062D01*
G01X1362197D01*
G03X1363259Y1094778I0J1502D01*
G01X1365234Y1096753D01*
G03X1365674Y1097815I-1062J1062D01*
G01Y1099255D01*
G02X1365733Y1099397I200J0D01*
G01X1368146Y1101810D01*
G03X1368565Y1102625I-1062J1061D01*
G01Y1102626D01*
G02X1368663Y1102766I197J-34D01*
G01X1368972Y1102943D01*
X1369061Y1102949D01*
X1369103Y1102933D01*
G03X1369554Y1102836I538J1402D01*
G01X1369556D01*
G02X1369706Y1102752I-13J-199D01*
G01X1369914Y1102460D01*
X1369929Y1102371D01*
X1369917Y1102327D01*
G03X1369860Y1101917I1446J-410D01*
G03X1372864I1502J0D01*
G03X1371449Y1103416I-1501J0D01*
G01X1371448D01*
G02X1371298Y1103500I13J199D01*
G01X1371090Y1103792D01*
X1371075Y1103881D01*
X1371087Y1103925D01*
G03X1371144Y1104335I-1446J410D01*
G03X1371049Y1104860I-1502J-1D01*
G01X1371032Y1104904D01*
X1371043Y1104998D01*
X1371243Y1105307D01*
G02X1371397Y1105398I168J-108D01*
G03X1372799Y1106897I-100J1499D01*
G03X1369795I-1502J0D01*
G03X1369890Y1106372I1502J1D01*
G01X1369907Y1106328D01*
X1369896Y1106234D01*
X1369696Y1105925D01*
G02X1369542Y1105834I-168J108D01*
G03X1369062Y1105721I100J-1499D01*
G02X1368898Y1105725I-78J184D01*
G01X1368630Y1105852D01*
G02X1368524Y1105976I86J181D01*
G03X1367084Y1107054I-1440J-423D01*
G03X1366720Y1107009I1J-1502D01*
G02X1366571Y1107030I-49J194D01*
G01X1366297Y1107187D01*
X1366251Y1107247D01*
X1366240Y1107285D01*
G03X1364797Y1108369I-1443J-418D01*
G01X1364781D01*
G02X1364595Y1108492I-1J200D01*
G01X1364452Y1108833D01*
G02X1364495Y1109052I184J78D01*
G01X1364562Y1109119D01*
G02X1364704Y1109178I142J-141D01*
G01X1370859D01*
G03X1372201Y1109734I-2J1902D01*
G01X1372313Y1109846D01*
G02X1372596I142J-141D01*
G01X1372615Y1109827D01*
X1372643Y1109778D01*
X1372649Y1109750D01*
G03X1374112Y1108590I1463J343D01*
G03X1375486Y1109486I0J1502D01*
G01Y1109487D01*
G02X1375633Y1109602I183J-82D01*
G01X1375957Y1109663D01*
G02X1376135Y1109608I37J-197D01*
G01X1377201Y1108542D01*
G02X1377247Y1108332I-142J-141D01*
G01X1377104Y1107937D01*
X1377011Y1107866D01*
X1376953Y1107861D01*
G03X1375585Y1106365I134J-1496D01*
G03X1377087Y1104863I1502J0D01*
G03X1378132Y1105287I0J1500D01*
G02X1378275Y1105344I140J-143D01*
G01X1378399Y1105341D01*
G02X1378542Y1105278I-3J-200D01*
G03X1378580Y1105239I1381J1308D01*
G01X1380085Y1103734D01*
G03X1381427Y1103178I1344J1346D01*
G01X1388539D01*
G03X1389881Y1103734I-2J1902D01*
G01X1395243Y1109097D01*
G02X1395385Y1109156I142J-141D01*
G01X1404089D01*
G03X1405431Y1109712I-2J1902D01*
G01X1405485Y1109767D01*
G02X1405673Y1109821I142J-141D01*
G01X1406004Y1109743D01*
G02X1406148Y1109613I-45J-195D01*
G01Y1109612D01*
G03X1407571Y1108590I1423J480D01*
G03X1409073Y1110092I0J1502D01*
G03X1408051Y1111515I-1502J0D01*
G01X1408050D01*
G02X1407920Y1111659I65J189D01*
G01X1407842Y1111991D01*
G02X1407896Y1112178I195J45D01*
G01X1408734Y1113015D01*
G03X1409290Y1114357I-1346J1344D01*
G01Y1114689D01*
G02X1409425Y1114878I200J0D01*
G01X1409843Y1115022D01*
X1409966Y1114985D01*
X1410005Y1114935D01*
G03X1411237Y1114334I1232J962D01*
G03X1412799Y1115896I0J1562D01*
G03X1412461Y1116866I-1561J0D01*
G01X1412414Y1116926D01*
X1412416Y1116961D01*
X1412383D01*
X1412325Y1117017D01*
G03X1412299Y1117041I-1072J-1136D01*
G01X1412296Y1117248D01*
G02X1412348Y1117386I200J3D01*
G03X1412739Y1118396I-1110J1011D01*
G03X1409735I-1502J0D01*
G03X1410074Y1117446I1501J0D01*
G01Y1117445D01*
G02X1410119Y1117316I-155J-126D01*
G01X1410114Y1117021D01*
X1410089Y1116956D01*
X1410065Y1116929D01*
G03X1409811Y1116534I1172J-1033D01*
G03X1409688Y1116099I1426J-638D01*
G02X1409490Y1115925I-198J26D01*
G01X1409407D01*
X1409290Y1116042D01*
Y1120553D01*
G02X1409349Y1120695I200J0D01*
G01X1410770Y1122115D01*
G03X1411326Y1123457I-1346J1344D01*
G01Y1127785D01*
G02X1411450Y1127970I200J0D01*
G02X1411667Y1127927I76J-185D01*
G01X1411939Y1127656D01*
G03X1413177Y1127142I1239J1237D01*
G03X1414928Y1128892I0J1751D01*
G01Y1128894D01*
G03X1414415Y1130132I-1750J0D01*
G01X1414131Y1130416D01*
G02X1414072Y1130558I141J142D01*
G01Y1148845D01*
G03X1413559Y1150083I-1750J0D01*
G01X1413145Y1150497D01*
G02X1413087Y1150639I142J141D01*
G01Y1151070D01*
G02X1412836Y1151095I-110J167D01*
G01X1412585Y1151345D01*
G03X1411347Y1151858I-1238J-1237D01*
G01X1381148D01*
G03X1380721Y1151805I0J-1750D01*
G01X1380716Y1151804D01*
X1348965D01*
G03X1347727Y1151290I1J-1751D01*
G01X1347639Y1151202D01*
G02X1347357I-141J142D01*
G01X1347161Y1151398D01*
G03X1345816Y1151955I-1345J-1346D01*
G01X1345815D01*
G03X1345753Y1151954I0J-1903D01*
G01X1316907D01*
G02X1316766Y1152012I0J200D01*
G01X1314311Y1154466D01*
G02X1314267Y1154532I141J142D01*
G02X1314269Y1154687I186J75D01*
G02X1314311Y1154748I183J-81D01*
G01X1315450Y1155887D01*
G02X1315556Y1155941I140J-143D01*
G01X1315558D01*
G02X1315590Y1155944I35J-197D01*
G37*
G36*
G01X1611280Y54588D02*
X1639405D01*
X1639599Y54394D01*
Y52785D01*
X1639405Y52591D01*
X1611280D01*
G03X1605343Y46654I0J-5937D01*
G01Y7874D01*
G02X1599469Y2000I-5874J0D01*
G01X1552224D01*
G02X1546350Y7874I0J5874D01*
G01Y46654D01*
G03X1545263Y50079I-5939J0D01*
G01Y50191D01*
X1545272Y50200D01*
X1547511D01*
G02X1548348Y46654I-7097J-3547D01*
G01Y7874D01*
G03X1552224Y3998I3876J0D01*
G01X1599469D01*
G03X1603346Y7874I0J3877D01*
G01Y46654D01*
G02X1611280Y54588I7934J0D01*
G37*
G36*
G01X1604300Y1221504D02*
X1604348Y1221532D01*
X1604458Y1221531D01*
X1604807Y1221317D01*
G02X1604902Y1221136I-105J-170D01*
G01Y1221135D01*
G03X1604900Y1221062I1200J-69D01*
G03X1606102Y1219860I1202J0D01*
G03X1606322Y1219881I-4J1202D01*
G01X1606324D01*
G02X1606501Y1219826I36J-197D01*
G01X1606736Y1219591D01*
G02X1606791Y1219413I-142J-141D01*
G03X1606770Y1219192I1181J-224D01*
G03X1607972Y1217990I1202J0D01*
G03X1608193Y1218011I-3J1202D01*
G02X1608371Y1217956I37J-197D01*
G01X1608606Y1217721D01*
G02X1608661Y1217544I-142J-141D01*
G01Y1217542D01*
G03X1608640Y1217323I1181J-224D01*
G01Y1217321D01*
G03X1608661Y1217102I1202J5D01*
G01Y1217100D01*
G02X1608606Y1216923I-197J-36D01*
G01X1608371Y1216688D01*
G02X1608194Y1216633I-141J142D01*
G01X1608193D01*
G03X1607972Y1216654I-224J-1181D01*
G03X1609174Y1215452I0J-1202D01*
G03X1609153Y1215672I-1202J-4D01*
G01Y1215674D01*
G02X1609208Y1215851I197J36D01*
G01X1609443Y1216086D01*
G02X1609620Y1216141I141J-142D01*
G01X1609621D01*
G03X1609841Y1216120I224J1181D01*
G01X1609843D01*
G03X1610062Y1216141I-5J1202D01*
G01X1610064D01*
G02X1610241Y1216086I36J-197D01*
G01X1610476Y1215851D01*
G02X1610531Y1215674I-142J-141D01*
G01Y1215672D01*
G03X1610510Y1215452I1181J-224D01*
G03X1612914I1202J0D01*
G03X1612893Y1215672I-1202J-4D01*
G01Y1215674D01*
G02X1612948Y1215851I197J36D01*
G01X1613183Y1216086D01*
G02X1613360Y1216141I141J-142D01*
G01X1613361D01*
G03X1613581Y1216120I224J1181D01*
G01X1613583D01*
G03X1613802Y1216141I-5J1202D01*
G01X1613804D01*
G02X1613981Y1216086I36J-197D01*
G01X1614216Y1215851D01*
G02X1614271Y1215674I-142J-141D01*
G01Y1215672D01*
G03X1614250Y1215452I1181J-224D01*
G03X1615452Y1216654I1202J0D01*
G03X1615232Y1216633I4J-1202D01*
G01X1615230D01*
G02X1615053Y1216688I-36J197D01*
G01X1614818Y1216923D01*
G02X1614763Y1217100I142J141D01*
G01Y1217102D01*
G03X1614784Y1217321I-1181J224D01*
G01Y1217323D01*
G03X1614763Y1217542I-1202J-5D01*
G01Y1217544D01*
G02X1614818Y1217721I197J36D01*
G01X1615053Y1217956D01*
G02X1615231Y1218011I141J-142D01*
G03X1615452Y1217990I224J1181D01*
G03X1616654Y1219187I0J1202D01*
G01Y1219194D01*
G03X1616651Y1219287I-1202J8D01*
G01X1616650Y1219294D01*
Y1219307D01*
G02X1616743Y1219477I200J1D01*
G01X1617036Y1219661D01*
G02X1617200Y1219684I107J-169D01*
G01X1617246Y1219671D01*
X1617268Y1219658D01*
G03X1617803Y1219398I1922J3275D01*
G01X1617831Y1219387D01*
X1617876Y1219352D01*
X1617971Y1219217D01*
X1617990Y1219165D01*
X1617991Y1219135D01*
G03X1619192Y1217990I1201J57D01*
G03X1620393Y1219136I0J1202D01*
G01X1620394Y1219166D01*
X1620413Y1219219D01*
X1620506Y1219350D01*
X1620552Y1219386D01*
X1620579Y1219397D01*
G03X1621108Y1219654I-1390J3533D01*
G01X1621131Y1219668D01*
X1621194Y1219685D01*
G02X1621351Y1219660I50J-194D01*
G01X1621520Y1219554D01*
X1621622Y1219489D01*
G03X1621632Y1219483I108J169D01*
G01X1621685Y1219454D01*
X1621741Y1219348D01*
X1621734Y1219283D01*
G03X1621731Y1219198I1199J-85D01*
G01Y1219188D01*
G03X1624135I1202J4D01*
G01Y1219193D01*
G03X1624131Y1219292I-1202J1D01*
G01Y1219293D01*
X1624127Y1219353D01*
X1624183Y1219455D01*
X1624234Y1219483D01*
G03X1624244Y1219489I-98J175D01*
G01X1624419Y1219600D01*
X1624421D01*
X1624521Y1219662D01*
G02X1624677Y1219686I106J-170D01*
G01X1624725Y1219673D01*
X1624750Y1219658D01*
G03X1625341Y1219377I1920J3276D01*
G02X1625471Y1219190I-70J-187D01*
G03X1627875I1202J2D01*
G02X1628005Y1219377I200J0D01*
G03X1628474Y1219589I-1326J3558D01*
G01X1628475Y1219590D01*
X1628498Y1219602D01*
X1628545Y1219614D01*
X1628657D01*
G02X1628762Y1219584I0J-200D01*
G01X1629017Y1219426D01*
G02X1629112Y1219256I-105J-170D01*
G01Y1219231D01*
G03X1629111Y1219193I1301J-53D01*
G01Y1219191D01*
G03X1630413Y1217890I1302J1D01*
G03X1631715Y1219192I0J1302D01*
G03X1631714Y1219231I-1302J-14D01*
G01Y1219256D01*
G02X1631809Y1219426I200J0D01*
G01X1632099Y1219605D01*
G02X1632102Y1219607I112J-165D01*
G02X1632259Y1219627I102J-172D01*
G01X1632285Y1219620D01*
X1632322Y1219605D01*
X1632333Y1219599D01*
G03X1632726Y1219414I1811J3337D01*
G02X1632851Y1219229I-75J-185D01*
G01Y1219192D01*
G03X1635455I1302J0D01*
G01Y1219223D01*
X1635453Y1219269D01*
X1635492Y1219354D01*
X1635552Y1219402D01*
X1635581Y1219414D01*
X1635582D01*
G03X1635999Y1219614I-1430J3517D01*
G02X1636042Y1219632I98J-174D01*
G01X1636087Y1219644D01*
X1636190Y1219625D01*
G02X1636256Y1219600I-37J-197D01*
G01X1636285Y1219582D01*
X1636308Y1219555D01*
X1636309Y1219554D01*
G03X1636355Y1219513I154J127D01*
G01X1636497Y1219425D01*
G02X1636502Y1219422I-100J-173D01*
G01X1636503Y1219421D01*
G02X1636592Y1219255I-111J-166D01*
G01Y1219230D01*
G03X1636591Y1219193I1301J-54D01*
G01Y1219191D01*
G03X1637893Y1217890I1302J1D01*
G03X1639195Y1219192I0J1302D01*
G03X1639194Y1219231I-1302J-14D01*
G01Y1219256D01*
G02X1639289Y1219426I200J0D01*
G01X1639579Y1219605D01*
G02X1639582Y1219607I112J-165D01*
G02X1639739Y1219627I102J-172D01*
G01X1639765Y1219620D01*
X1639806Y1219604D01*
X1639817Y1219598D01*
G03X1640152Y1219436I1818J3333D01*
G01X1640174Y1219418D01*
X1640239Y1219365D01*
X1640256Y1219340D01*
X1640314Y1219254D01*
X1640331Y1219199D01*
X1640332Y1219170D01*
G03X1641634Y1217890I1302J22D01*
G03X1642934Y1219131I0J1301D01*
G01X1642935Y1219146D01*
X1642943Y1219189D01*
X1642945Y1219203D01*
X1642961Y1219251D01*
G02X1642971Y1219277I191J-59D01*
G02X1642985Y1219301I179J-89D01*
G01X1643003Y1219328D01*
X1643027Y1219363D01*
X1643108Y1219433D01*
X1643136Y1219445D01*
G03X1643479Y1219614I-1505J3486D01*
G01X1643527Y1219640D01*
X1643634Y1219638D01*
X1643830Y1219518D01*
X1643935Y1219454D01*
G02X1644006Y1219378I-106J-170D01*
G01X1644048Y1219300D01*
G02X1644072Y1219205I-176J-95D01*
G01Y1219191D01*
G03X1645374Y1217890I1302J1D01*
G03X1646676Y1219192I0J1302D01*
G03X1646675Y1219231I-1302J-14D01*
G01Y1219256D01*
G02X1646770Y1219426I200J0D01*
G01X1647060Y1219605D01*
G02X1647063Y1219607I112J-165D01*
G02X1647220Y1219627I102J-172D01*
G01X1647246Y1219620D01*
X1647283Y1219605D01*
X1647294Y1219599D01*
G03X1647687Y1219414I1811J3337D01*
G02X1647812Y1219229I-75J-185D01*
G01Y1219192D01*
G03X1650416I1302J0D01*
G01Y1219223D01*
X1650414Y1219269D01*
X1650453Y1219354D01*
X1650513Y1219402D01*
X1650542Y1219414D01*
X1650543D01*
G03X1650960Y1219614I-1430J3517D01*
G02X1651003Y1219632I98J-174D01*
G01X1651048Y1219644D01*
X1651151Y1219625D01*
G02X1651217Y1219600I-37J-197D01*
G01X1651246Y1219582D01*
X1651269Y1219555D01*
X1651270Y1219554D01*
G03X1651316Y1219513I154J127D01*
G01X1651458Y1219425D01*
G02X1651463Y1219422I-100J-173D01*
G01X1651464Y1219421D01*
G02X1651553Y1219255I-111J-166D01*
G01Y1219230D01*
G03X1651552Y1219193I1301J-54D01*
G01Y1219191D01*
G03X1652854Y1217890I1302J1D01*
G03X1654156Y1219192I0J1302D01*
G03X1654155Y1219231I-1302J-14D01*
G01Y1219256D01*
G02X1654250Y1219426I200J0D01*
G01X1654540Y1219605D01*
G02X1654543Y1219607I112J-165D01*
G02X1654700Y1219627I102J-172D01*
G01X1654726Y1219620D01*
X1654763Y1219605D01*
X1654774Y1219599D01*
G03X1655167Y1219414I1811J3337D01*
G02X1655292Y1219229I-75J-185D01*
G01Y1219192D01*
G03X1657896I1302J0D01*
G01Y1219223D01*
X1657894Y1219268D01*
X1657933Y1219353D01*
X1657993Y1219402D01*
X1658022Y1219414D01*
G03X1658508Y1219654I-1434J3515D01*
G01X1658532Y1219668D01*
X1658594Y1219684D01*
G02X1658750Y1219660I50J-194D01*
G01X1658925Y1219551D01*
X1659036Y1219481D01*
G02X1659127Y1219343I-106J-169D01*
G01X1659134Y1219300D01*
X1659133Y1219263D01*
Y1219260D01*
G03X1659131Y1219194I1201J-69D01*
G01Y1219191D01*
G03X1660333Y1217989I1203J1D01*
G01X1660335D01*
G03X1660426Y1217993I-7J1203D01*
G01X1660470Y1217996D01*
X1660552Y1217966D01*
X1660605Y1217913D01*
G02X1660633Y1217878I-141J-142D01*
G01X1660803Y1217608D01*
G02X1660826Y1217447I-170J-106D01*
G01X1660810Y1217391D01*
X1660797Y1217369D01*
G03X1660567Y1216905I3278J-1914D01*
G01X1660555Y1216877D01*
X1660512Y1216825D01*
G02X1660358Y1216754I-153J129D01*
G01X1660334D01*
G03Y1214150I0J-1302D01*
G01X1660365D01*
X1660427Y1214152D01*
X1660532Y1214084D01*
X1660556Y1214025D01*
G03X1660756Y1213606I3520J1423D01*
G01X1660783Y1213558D01*
X1660780Y1213451D01*
X1660696Y1213315D01*
X1660585Y1213137D01*
G02X1660557Y1213101I-171J104D01*
G01X1660528Y1213072D01*
G02X1660460Y1213027I-142J141D01*
G01X1660420Y1213011D01*
X1660378Y1213013D01*
G03X1660334Y1213014I-52J-1301D01*
G03X1659032Y1211712I0J-1302D01*
G03X1660333Y1210410I1302J0D01*
G01X1660335D01*
G03X1660373Y1210411I-15J1302D01*
G01X1660398D01*
G02X1660568Y1210316I0J-200D01*
G01X1660744Y1210031D01*
G02X1660761Y1209996I-171J-105D01*
G01X1660766Y1209981D01*
G02X1660759Y1209822I-187J-71D01*
G01X1660758Y1209820D01*
X1660732Y1209772D01*
G03X1660567Y1209425I3341J-1802D01*
G01X1660555Y1209396D01*
X1660511Y1209345D01*
G02X1660358Y1209274I-153J129D01*
G01X1660334D01*
G03Y1206670I0J-1302D01*
G01X1660365D01*
X1660427Y1206672D01*
X1660532Y1206604D01*
X1660556Y1206545D01*
G03X1660756Y1206126I3520J1423D01*
G01X1660783Y1206078D01*
X1660780Y1205971D01*
X1660696Y1205835D01*
X1660585Y1205657D01*
G02X1660557Y1205621I-171J104D01*
G01X1660528Y1205592D01*
G02X1660460Y1205547I-142J141D01*
G01X1660420Y1205531D01*
X1660378Y1205533D01*
G03X1660334Y1205534I-52J-1301D01*
G03X1659032Y1204232I0J-1302D01*
G03X1660333Y1202930I1302J0D01*
G01X1660335D01*
G03X1660373Y1202931I-15J1302D01*
G01X1660398D01*
G02X1660568Y1202837I0J-200D01*
G01X1660660Y1202689D01*
Y1202687D01*
X1660780Y1202490D01*
X1660782Y1202383D01*
X1660755Y1202335D01*
G03X1660670Y1202173I3319J-1845D01*
G01X1660647Y1202127D01*
Y1202126D01*
X1660606Y1202039D01*
G03X1660555Y1201919I3469J-1545D01*
G01X1660533Y1201862D01*
X1660431Y1201793D01*
X1660334D01*
G03Y1199189I0J-1302D01*
G01X1660365D01*
X1660406Y1199190D01*
X1660486Y1199158D01*
X1660541Y1199099D01*
X1660555Y1199065D01*
G03X1660584Y1198997I3506J1455D01*
G01Y1198996D01*
G03X1660754Y1198649I3490J1495D01*
G01X1660756Y1198645D01*
X1660760Y1198637D01*
G02X1660751Y1198442I-179J-89D01*
G01X1660573Y1198156D01*
X1660557Y1198140D01*
X1660528Y1198111D01*
G02X1660460Y1198066I-142J141D01*
G01X1660420Y1198050D01*
X1660378Y1198052D01*
G03X1660334Y1198053I-52J-1301D01*
G03X1661636Y1196751I0J-1302D01*
G03X1661635Y1196790I-1302J-14D01*
G01Y1196815D01*
G02X1661730Y1196985I200J0D01*
G01X1662023Y1197165D01*
X1662036Y1197173D01*
X1662049Y1197179D01*
X1662054Y1197181D01*
G02X1662142Y1197197I79J-184D01*
G01X1662192Y1197195D01*
X1662233Y1197172D01*
G03X1662388Y1197091I1835J3323D01*
G02X1662480Y1196996I-90J-179D01*
G03X1662796Y1196448I3462J1631D01*
G02X1662823Y1196390I-166J-112D01*
G03X1663698Y1195504I1251J361D01*
G02X1663724Y1195495I-52J-193D01*
G01X1663764Y1195476D01*
X1663779Y1195466D01*
G03X1664558Y1195055I2163J3156D01*
G01X1664559D01*
G02X1664648Y1194985I-74J-186D01*
G01X1664726Y1194876D01*
X1664744Y1194825D01*
X1664746Y1194797D01*
G03X1665945Y1193679I1199J84D01*
G03X1667111Y1194589I0J1202D01*
G01X1667118Y1194619D01*
X1667149Y1194669D01*
X1667280Y1194785D01*
X1667338Y1194810D01*
X1667369Y1194813D01*
G03X1667568Y1194838I-377J3808D01*
G01X1667631Y1194849D01*
G03X1667774Y1194876I-638J3773D01*
G02X1667856I41J-196D01*
G03X1667999Y1194849I781J3746D01*
G01X1668062Y1194838D01*
G03X1668261Y1194813I576J3783D01*
G01X1668292Y1194810D01*
X1668350Y1194785D01*
X1668481Y1194669D01*
X1668512Y1194619D01*
X1668519Y1194589D01*
G03X1669685Y1193679I1166J292D01*
G03X1669905Y1193700I-4J1202D01*
G01X1669907D01*
G02X1670084Y1193645I36J-197D01*
G01X1670319Y1193410D01*
G02X1670374Y1193233I-142J-141D01*
G01Y1193231D01*
G03X1670353Y1193011I1181J-224D01*
G03X1671555Y1194213I1202J0D01*
G03X1671335Y1194192I4J-1202D01*
G01X1671333D01*
G02X1671156Y1194247I-36J197D01*
G01X1670921Y1194482D01*
G02X1670866Y1194659I142J141D01*
G01Y1194661D01*
G03X1670879Y1194746I-1181J224D01*
G01Y1194747D01*
X1670880Y1194758D01*
G03X1670884Y1194797I-1193J142D01*
G01X1670888Y1194853D01*
X1670982Y1194985D01*
G02X1671071Y1195055I163J-116D01*
G01X1671072D01*
G03X1671299Y1195152I-1389J3565D01*
G03X1671848Y1195464I-1610J3471D01*
G02X1671873Y1195479I115J-163D01*
G01X1671915Y1195500D01*
X1671931Y1195504D01*
G03X1672724Y1196178I-377J1246D01*
G02X1672904Y1196290I180J-88D01*
G01X1673946D01*
G02X1674126Y1196178I0J-200D01*
G03X1676464I1169J573D01*
G02X1676644Y1196290I180J-88D01*
G01X1677686D01*
G02X1677866Y1196178I0J-200D01*
G03X1679035Y1195449I1169J573D01*
G03X1679247Y1195467I-4J1302D01*
G01X1679294Y1195475D01*
X1679383Y1195448D01*
X1679651Y1195193D01*
G02X1679712Y1195027I-138J-145D01*
G01Y1195023D01*
G03X1679703Y1194882I1193J-147D01*
G01Y1194880D01*
G03X1679724Y1194661I1202J5D01*
G01Y1194659D01*
G02X1679669Y1194482I-197J-36D01*
G01X1679434Y1194247D01*
G02X1679257Y1194192I-141J142D01*
G01X1679256D01*
G03X1679035Y1194213I-224J-1181D01*
G03X1680237Y1193011I0J-1202D01*
G03X1680216Y1193231I-1202J-4D01*
G01Y1193233D01*
G02X1680271Y1193410I197J36D01*
G01X1680506Y1193645D01*
G02X1680683Y1193700I141J-142D01*
G01X1680684D01*
G03X1680904Y1193679I224J1181D01*
G01X1680906D01*
G03X1681125Y1193700I-5J1202D01*
G01X1681127D01*
G02X1681304Y1193645I36J-197D01*
G01X1681539Y1193410D01*
G02X1681594Y1193233I-142J-141D01*
G01Y1193231D01*
G03X1681573Y1193011I1181J-224D01*
G03X1682775Y1194213I1202J0D01*
G03X1682555Y1194192I4J-1202D01*
G01X1682553D01*
G02X1682376Y1194247I-36J197D01*
G01X1682141Y1194482D01*
G02X1682086Y1194659I142J141D01*
G01Y1194661D01*
G03X1682107Y1194880I-1181J224D01*
G01Y1194882D01*
G03X1682098Y1195023I-1202J-6D01*
G01Y1195027D01*
G02X1682159Y1195193I199J21D01*
G01X1682427Y1195448D01*
X1682516Y1195475D01*
X1682563Y1195467D01*
G03X1682775Y1195449I216J1284D01*
G03X1683944Y1196178I0J1302D01*
G02X1684124Y1196290I180J-88D01*
G01X1685166D01*
G02X1685346Y1196178I0J-200D01*
G03X1687684I1169J573D01*
G02X1687864Y1196290I180J-88D01*
G01X1688907D01*
G02X1689087Y1196178I0J-200D01*
G03X1691425I1169J573D01*
G02X1691605Y1196290I180J-88D01*
G01X1692646D01*
G02X1692753Y1196259I0J-200D01*
G01X1692754Y1196258D01*
G02X1692825Y1196180I-107J-169D01*
G01X1692826Y1196178D01*
X1692827Y1196177D01*
G03X1693996Y1195448I1169J573D01*
G01X1697757D01*
G03X1698680Y1195853I-21J1303D01*
G01X1698704Y1195879D01*
X1698768Y1195911D01*
G02X1698857Y1195932I89J-179D01*
G01X1699132D01*
G02X1699279Y1195868I0J-200D01*
G03X1700235Y1195449I957J883D01*
G01X1700236D01*
G03X1701250Y1195935I0J1301D01*
G02X1701399Y1196010I156J-125D01*
G01X1705616D01*
G03X1706237Y1196060I-4J3926D01*
G01X1706281Y1196067D01*
X1706326Y1196054D01*
G02X1706406Y1196009I-55J-192D01*
G01X1706636Y1195797D01*
G02X1706700Y1195637I-135J-147D01*
G01Y1195634D01*
G03X1706696Y1195522I1498J-110D01*
G03X1708198Y1194020I1502J0D01*
G03X1709661Y1195181I0J1502D01*
G01X1709671Y1195222D01*
X1709754Y1195333D01*
X1709779Y1195358D01*
X1709805Y1195376D01*
X1710086Y1195524D01*
X1710174Y1195528D01*
X1710216Y1195510D01*
G03X1710415Y1195442I584J1384D01*
G01X1710465Y1195429D01*
X1710539Y1195359D01*
X1710674Y1194941D01*
X1710655Y1194841D01*
X1710622Y1194801D01*
G03X1710281Y1193848I1161J-953D01*
G03X1711783Y1192346I1502J0D01*
G03X1713285Y1193822I0J1502D01*
G01Y1193848D01*
G03X1713040Y1194670I-1501J0D01*
G01Y1194671D01*
G02X1713015Y1194833I167J109D01*
G01X1713094Y1195122D01*
G02X1713200Y1195249I193J-53D01*
G03X1714044Y1196600I-659J1351D01*
G03X1712604Y1198101I-1502J0D01*
G01X1712535Y1198104D01*
X1712432Y1198190D01*
X1712403Y1198321D01*
G02X1712407Y1198424I195J44D01*
G02X1712523Y1198550I191J-59D01*
G01X1712564Y1198566D01*
X1712601Y1198581D01*
X1717680D01*
G02X1717737Y1198572I-2J-200D01*
G01X1717812Y1198550D01*
X1717847Y1198528D01*
X1717882Y1198508D01*
G03X1717895Y1198502I635J1359D01*
G02X1717905Y1198496I-98J-174D01*
G03X1717936Y1198479I738J1308D01*
G01X1717971Y1198462D01*
X1717972Y1198461D01*
G03X1717987Y1198454I643J1357D01*
G01X1718007Y1198445D01*
G03X1718174Y1198381I620J1368D01*
G03X1718625Y1198311I453J1432D01*
G03X1719187Y1198421I-2J1502D01*
G03X1719388Y1198520I-561J1393D01*
G03X1719413Y1198535I-760J1295D01*
G01X1719436Y1198549D01*
X1719542Y1198581D01*
X1764715D01*
G02X1764857Y1198522I0J-200D01*
G01X1766662Y1196717D01*
G03X1766804Y1196658I142J141D01*
G01X1831499D01*
G02X1831641Y1196599I0J-200D01*
G01X1834181Y1194059D01*
G02X1834183Y1194057I-140J-142D01*
G02X1834240Y1193917I-143J-140D01*
G01Y1003103D01*
G02X1834181Y1002961I-200J0D01*
G01X1832124Y1000904D01*
X1832096Y1000875D01*
X1832022Y1000845D01*
X1811922D01*
G03X1811870Y1000838I0J-200D01*
G01X1811857Y1000834D01*
X1811842Y1000828D01*
G02X1811770Y1000815I-71J187D01*
G01X1806118D01*
G03X1806019Y1000788I1J-200D01*
G01X1806014Y1000786D01*
X1805997Y1000777D01*
G02X1805908Y1000756I-89J179D01*
G01X1623832D01*
X1623758Y1000786D01*
X1623730Y1000815D01*
X1613622Y1010923D01*
G02X1613566Y1011031I141J142D01*
G01X1610668Y1027786D01*
X1610655Y1027864D01*
G02X1610652Y1027898I197J35D01*
G01Y1071779D01*
X1610658Y1071806D01*
G02X1610747Y1071931I195J-45D01*
G01X1610812Y1071971D01*
X1610813Y1071972D01*
X1610817Y1071974D01*
X1611018Y1072108D01*
X1611020D01*
G02X1611208Y1072126I111J-166D01*
G01X1611209D01*
G03X1611710Y1072024I505J1199D01*
G01X1611712D01*
G03X1611923Y1072042I-5J1302D01*
G01X1611971Y1072050D01*
X1612060Y1072023D01*
X1612327Y1071767D01*
G02X1612389Y1071631I-138J-145D01*
G01X1612390Y1071614D01*
X1612388Y1071598D01*
G03X1612379Y1071455I1193J-147D01*
G03X1613581Y1072657I1202J0D01*
G03X1613440Y1072648I6J-1202D01*
G01X1613435D01*
G02X1613270Y1072709I-20J199D01*
G01X1613049Y1072940D01*
G02X1612996Y1073112I144J139D01*
G03X1613014Y1073326I-1284J216D01*
G03X1612996Y1073538I-1302J-4D01*
G01X1612988Y1073585D01*
X1613015Y1073674D01*
X1613231Y1073901D01*
X1613325Y1073933D01*
X1613374Y1073925D01*
G03X1613581Y1073908I209J1271D01*
G03Y1076484I0J1288D01*
G03X1613374Y1076467I2J-1288D01*
G01X1613325Y1076459D01*
X1613231Y1076491D01*
X1613015Y1076718D01*
X1612988Y1076807D01*
X1612996Y1076854D01*
G03X1613014Y1077066I-1284J216D01*
G03X1612996Y1077278I-1302J-4D01*
G01X1612988Y1077325D01*
X1613015Y1077414D01*
X1613231Y1077641D01*
X1613325Y1077673D01*
X1613374Y1077665D01*
G03X1613581Y1077648I209J1271D01*
G03Y1080224I0J1288D01*
G03X1613384Y1080208I5J-1288D01*
G01X1613381D01*
G02X1613211Y1080264I-29J198D01*
G01X1613035Y1080439D01*
X1613004Y1080524D01*
X1613009Y1080570D01*
G03X1613016Y1080707I-1296J135D01*
G01Y1081084D01*
G02X1613082Y1081232I200J0D01*
G01X1613302Y1081431D01*
G02X1613455Y1081481I133J-149D01*
G01X1613456D01*
G03X1613582Y1081475I120J1196D01*
G03Y1083879I0J1202D01*
G03X1613456Y1083873I-6J-1202D01*
G01X1613455D01*
G02X1613302Y1083923I-20J199D01*
G01X1613082Y1084122D01*
G02X1613016Y1084270I134J148D01*
G01Y1084456D01*
G03X1613014Y1084529I-1303J1D01*
G01Y1084552D01*
G03X1612997Y1084762I-1303J0D01*
G01X1612989Y1084808D01*
X1613017Y1084897D01*
X1613271Y1085163D01*
G02X1613436Y1085224I145J-138D01*
G01X1613439D01*
G03X1613582Y1085215I147J1193D01*
G03Y1087619I0J1202D01*
G03X1613440Y1087610I5J-1202D01*
G01X1613436D01*
G02X1613270Y1087671I-21J199D01*
G01X1613015Y1087939D01*
X1612988Y1088028D01*
X1612996Y1088075D01*
G03X1613014Y1088287I-1283J216D01*
G03X1612996Y1088499I-1302J-4D01*
G01X1612988Y1088546D01*
X1613015Y1088635D01*
X1613270Y1088903D01*
G02X1613436Y1088964I145J-138D01*
G01X1613438D01*
G03X1613582Y1088955I147J1193D01*
G03X1612380Y1090157I0J1202D01*
G03X1612389Y1090015I1202J5D01*
G01Y1090011D01*
G02X1612328Y1089845I-199J-21D01*
G01X1612060Y1089590D01*
X1611971Y1089563D01*
X1611924Y1089571D01*
G03X1611712Y1089589I-216J-1284D01*
G03X1611500Y1089571I4J-1302D01*
G01X1611453Y1089563D01*
X1611364Y1089590D01*
X1611096Y1089845D01*
G02X1611035Y1090011I138J145D01*
G01Y1090015D01*
G03X1611044Y1090157I-1193J147D01*
G03X1608640I-1202J0D01*
G03X1608649Y1090015I1202J5D01*
G01Y1090011D01*
G02X1608588Y1089845I-199J-21D01*
G01X1608320Y1089590D01*
X1608231Y1089563D01*
X1608184Y1089571D01*
G03X1607973Y1089589I-216J-1284D01*
G01X1607971D01*
G03X1607760Y1089571I5J-1303D01*
G01X1607713Y1089563D01*
X1607624Y1089590D01*
X1607356Y1089845D01*
G02X1607295Y1090011I138J145D01*
G01Y1090015D01*
G03X1607304Y1090157I-1193J147D01*
G03X1606102Y1091359I-1202J0D01*
G03X1604978Y1090583I0J-1202D01*
G01X1604960Y1090534D01*
X1604884Y1090469D01*
X1604504Y1090387D01*
G02X1604321Y1090441I-42J196D01*
G01X1602893Y1091869D01*
G03X1602751Y1091928I-142J-141D01*
G01X1601911D01*
X1601797Y1092035D01*
X1601791Y1092114D01*
G03X1601776Y1092240I-1299J-91D01*
G01X1601768Y1092287D01*
X1601795Y1092376D01*
X1602050Y1092643D01*
G02X1602215Y1092704I145J-138D01*
G01X1602218D01*
G03X1602362Y1092695I147J1193D01*
G03X1601160Y1093897I0J1202D01*
G03X1601169Y1093755I1202J5D01*
G01Y1093751D01*
G02X1601108Y1093585I-199J-21D01*
G01X1600876Y1093364D01*
G02X1600708Y1093311I-138J145D01*
G01X1600706D01*
G03X1600280I-213J-1284D01*
G01X1600276D01*
G02X1600108Y1093364I-30J198D01*
G01X1599876Y1093585D01*
G02X1599815Y1093751I138J145D01*
G01Y1093755D01*
G03X1599824Y1093897I-1193J147D01*
G03X1598622Y1095099I-1202J0D01*
G03X1598496Y1095092I4J-1202D01*
G01X1598453Y1095088D01*
X1598413Y1095101D01*
G02X1598342Y1095142I62J190D01*
G01X1598120Y1095341D01*
G02X1598054Y1095489I134J148D01*
G01Y1095667D01*
G03X1598053Y1095702I-1302J-20D01*
G02Y1095718I200J8D01*
G03X1598054Y1095767I-1301J51D01*
G03X1598036Y1095979I-1302J-4D01*
G01X1598028Y1096026D01*
X1598055Y1096115D01*
X1598310Y1096383D01*
G02X1598476Y1096444I145J-138D01*
G01X1598478D01*
G03X1598622Y1096435I147J1193D01*
G03Y1098839I0J1202D01*
G03X1597420Y1097652I0J-1202D01*
G01Y1097636D01*
G03X1597485Y1097248I1202J2D01*
G01X1597490Y1097233D01*
X1597495Y1097204D01*
G02X1597438Y1097027I-197J-34D01*
G01X1597403Y1096992D01*
X1597310Y1096964D01*
X1597230Y1096979D01*
X1597213Y1096985D01*
G03X1597077Y1097028I-460J-1218D01*
G01X1597054Y1097034D01*
X1597033Y1097039D01*
G03X1596751Y1097070I-283J-1272D01*
G01X1596682D01*
X1596675Y1097069D01*
X1596670D01*
G03X1596656Y1097068I7J-200D01*
G01X1596648Y1097067D01*
X1596643Y1097066D01*
X1596637D01*
G03X1596292Y1096986I119J-1298D01*
G01X1596280Y1096981D01*
X1596252Y1096975D01*
G02X1596068Y1097023I-48J194D01*
G01X1596032Y1097058D01*
X1596000Y1097153D01*
X1596011Y1097217D01*
G02X1596019Y1097248I197J-34D01*
G03X1596084Y1097637I-1137J390D01*
G03X1594882Y1096435I-1202J0D01*
G03X1595023Y1096443I3J1202D01*
G01X1595070Y1096449D01*
X1595158Y1096417D01*
X1595412Y1096152D01*
G02X1595458Y1096076I-144J-139D01*
G01Y1096073D01*
X1595472Y1096028D01*
X1595465Y1095981D01*
Y1095980D01*
X1595463Y1095964D01*
G03X1595447Y1095767I1285J-204D01*
G01Y1095626D01*
X1595448D01*
Y1095250D01*
G02X1595248Y1095050I-200J0D01*
G01X1595221D01*
X1595196Y1095057D01*
G03X1594882Y1095099I-315J-1160D01*
G03X1593680Y1093897I0J-1202D01*
G03X1593689Y1093755I1202J5D01*
G01Y1093750D01*
G02X1593628Y1093585I-199J-20D01*
G01X1593396Y1093363D01*
G02X1593225Y1093311I-138J145D01*
G03X1592799I-213J-1284D01*
G01X1592795D01*
G02X1592627Y1093364I-30J198D01*
G01X1592395Y1093585D01*
G02X1592334Y1093751I138J145D01*
G01Y1093755D01*
G03X1592343Y1093897I-1193J147D01*
G03X1591141Y1095099I-1202J0D01*
G03X1591014Y1095092I3J-1202D01*
G01X1590971Y1095088D01*
X1590931Y1095101D01*
G02X1590860Y1095142I62J190D01*
G01X1590639Y1095340D01*
G02X1590578Y1095441I133J149D01*
G01X1590572Y1095465D01*
Y1095738D01*
G03X1590573Y1095766I-1300J60D01*
G01Y1095768D01*
G03X1590555Y1095979I-1302J-5D01*
G01X1590547Y1096026D01*
X1590574Y1096115D01*
X1590829Y1096383D01*
G02X1590995Y1096444I145J-138D01*
G01X1590997D01*
G03X1591141Y1096435I147J1193D01*
G03Y1098839I0J1202D01*
G03X1589939Y1097652I0J-1202D01*
G01Y1097636D01*
G03X1590004Y1097248I1202J2D01*
G01X1590009Y1097233D01*
X1590014Y1097204D01*
G02X1589957Y1097027I-197J-34D01*
G01X1589922Y1096992D01*
X1589829Y1096964D01*
X1589749Y1096979D01*
X1589732Y1096985D01*
G03X1589596Y1097028I-460J-1218D01*
G01X1589573Y1097034D01*
X1589552Y1097039D01*
G03X1589269Y1097070I-283J-1272D01*
G03X1589057Y1097053I-2J-1303D01*
G01X1589010Y1097045D01*
X1588921Y1097072D01*
X1588656Y1097324D01*
G02X1588636Y1097346I138J145D01*
G02X1588595Y1097494I158J123D01*
G01Y1097496D01*
G03X1588603Y1097637I-1194J138D01*
G03X1587401Y1096435I-1202J0D01*
G03X1587542Y1096443I3J1202D01*
G01X1587589Y1096449D01*
X1587677Y1096417D01*
X1587931Y1096152D01*
G02X1587977Y1096076I-144J-139D01*
G01Y1096073D01*
X1587991Y1096028D01*
X1587984Y1095981D01*
Y1095980D01*
X1587982Y1095964D01*
G03X1587966Y1095767I1287J-204D01*
G01Y1095490D01*
G02X1587900Y1095342I-200J0D01*
G01X1587680Y1095143D01*
G02X1587527Y1095093I-133J149D01*
G01X1587526D01*
G03X1587401Y1095099I-120J-1196D01*
G03X1586199Y1093897I0J-1202D01*
G03X1586208Y1093755I1202J5D01*
G01Y1093751D01*
G02X1586147Y1093585I-199J-21D01*
G01X1585915Y1093364D01*
G02X1585747Y1093311I-138J145D01*
G01X1585745D01*
G03X1585319I-213J-1284D01*
G01X1585315D01*
G02X1585147Y1093364I-30J198D01*
G01X1584915Y1093585D01*
G02X1584854Y1093751I138J145D01*
G01Y1093755D01*
G03X1584863Y1093897I-1193J147D01*
G03X1583661Y1095099I-1202J0D01*
G03X1583534Y1095092I3J-1202D01*
G01X1583491Y1095088D01*
X1583451Y1095101D01*
G02X1583380Y1095142I62J190D01*
G01X1583159Y1095340D01*
G02X1583098Y1095441I133J149D01*
G01X1583092Y1095465D01*
Y1095667D01*
X1583091Y1095676D01*
Y1095721D01*
G03X1583093Y1095766I-1299J80D01*
G01Y1095768D01*
G03X1583075Y1095979I-1302J-5D01*
G01X1583067Y1096026D01*
X1583094Y1096115D01*
X1583349Y1096383D01*
G02X1583515Y1096444I145J-138D01*
G01X1583517D01*
G03X1583661Y1096435I147J1193D01*
G03Y1098839I0J1202D01*
G03X1582459Y1097652I0J-1202D01*
G01Y1097636D01*
G03X1582524Y1097248I1202J2D01*
G01X1582529Y1097233D01*
X1582534Y1097204D01*
G02X1582477Y1097027I-197J-34D01*
G01X1582442Y1096992D01*
X1582349Y1096964D01*
X1582269Y1096979D01*
X1582252Y1096985D01*
G03X1582040Y1097045I-459J-1219D01*
G03X1581953Y1097059I-250J-1278D01*
G03X1581951Y1097060I-85J-168D01*
G03X1581791Y1097070I-161J-1293D01*
G01X1581720D01*
X1581713Y1097069D01*
X1581708D01*
G03X1581694Y1097068I7J-200D01*
G01X1581686Y1097067D01*
X1581680Y1097066D01*
X1581674D01*
G03X1581317Y1096982I117J-1298D01*
G01X1581291Y1096971D01*
X1581237Y1096966D01*
X1581210Y1096971D01*
G02X1581048Y1097203I35J197D01*
G01X1581053Y1097232D01*
X1581058Y1097247D01*
Y1097248D01*
G03X1581123Y1097637I-1137J390D01*
G03X1579921Y1096435I-1202J0D01*
G01X1579924D01*
G03X1580061Y1096443I-1J1202D01*
G01X1580108Y1096449D01*
X1580196Y1096417D01*
X1580450Y1096152D01*
G02X1580496Y1096076I-144J-139D01*
G01Y1096073D01*
X1580510Y1096028D01*
X1580503Y1095980D01*
Y1095979D01*
X1580501Y1095963D01*
G03X1580485Y1095767I1285J-204D01*
G01Y1095626D01*
X1580486D01*
Y1095349D01*
G02X1580408Y1095191I-200J0D01*
G01X1580309Y1095115D01*
G02X1580237Y1095080I-122J159D01*
G01X1580191Y1095068D01*
G03X1579921Y1095099I-271J-1171D01*
G03X1578719Y1093897I0J-1202D01*
G03X1578728Y1093755I1202J5D01*
G01Y1093751D01*
G02X1578667Y1093585I-199J-21D01*
G01X1578435Y1093364D01*
G02X1578267Y1093311I-138J145D01*
G01X1578265D01*
G03X1577839I-213J-1284D01*
G01X1577835D01*
G02X1577667Y1093364I-30J198D01*
G01X1577435Y1093585D01*
G02X1577374Y1093751I138J145D01*
G01Y1093755D01*
G03X1577383Y1093897I-1193J147D01*
G03X1576181Y1095099I-1202J0D01*
G03X1576054Y1095092I3J-1202D01*
G01X1576011Y1095088D01*
X1575971Y1095101D01*
G02X1575900Y1095142I62J190D01*
G01X1575679Y1095340D01*
G02X1575618Y1095441I133J149D01*
G01X1575612Y1095465D01*
Y1095667D01*
X1575611Y1095676D01*
Y1095721D01*
G03X1575613Y1095766I-1299J80D01*
G01Y1095768D01*
G03X1575595Y1095979I-1302J-5D01*
G01X1575587Y1096026D01*
X1575614Y1096115D01*
X1575869Y1096383D01*
G02X1576035Y1096444I145J-138D01*
G01X1576037D01*
G03X1576181Y1096435I147J1193D01*
G03Y1098839I0J1202D01*
G03X1574979Y1097652I0J-1202D01*
G01Y1097636D01*
G03X1575044Y1097248I1202J2D01*
G01X1575049Y1097233D01*
X1575054Y1097204D01*
G02X1574997Y1097027I-197J-34D01*
G01X1574962Y1096992D01*
X1574869Y1096964D01*
X1574789Y1096979D01*
X1574772Y1096985D01*
G03X1574560Y1097045I-459J-1219D01*
G03X1574473Y1097059I-250J-1278D01*
G03X1574471Y1097060I-85J-168D01*
G03X1574311Y1097070I-161J-1293D01*
G01X1574240D01*
X1574233Y1097069D01*
X1574228D01*
G03X1574214Y1097068I7J-200D01*
G01X1574206Y1097067D01*
X1574200Y1097066D01*
X1574194D01*
G03X1573837Y1096982I117J-1298D01*
G01X1573811Y1096971D01*
X1573757Y1096966D01*
X1573730Y1096971D01*
G02X1573568Y1097203I35J197D01*
G01X1573573Y1097232D01*
X1573578Y1097247D01*
Y1097248D01*
G03X1573643Y1097637I-1137J390D01*
G03X1572441Y1096435I-1202J0D01*
G01X1572444D01*
G03X1572581Y1096443I-1J1202D01*
G01X1572628Y1096449D01*
X1572716Y1096417D01*
X1572970Y1096152D01*
G02X1573016Y1096076I-144J-139D01*
G01Y1096073D01*
X1573030Y1096028D01*
X1573023Y1095980D01*
Y1095979D01*
X1573021Y1095963D01*
G03X1573005Y1095767I1285J-204D01*
G01Y1095626D01*
X1573006D01*
Y1095349D01*
G02X1572928Y1095191I-200J0D01*
G01X1572829Y1095115D01*
G02X1572757Y1095080I-122J159D01*
G01X1572711Y1095068D01*
G03X1572441Y1095099I-271J-1171D01*
G03X1571239Y1093897I0J-1202D01*
G03X1571248Y1093755I1202J5D01*
G01Y1093751D01*
G02X1571187Y1093585I-199J-21D01*
G01X1570955Y1093364D01*
G02X1570787Y1093311I-138J145D01*
G01X1570785D01*
G03X1570357I-214J-1284D01*
G02X1570186Y1093363I-33J197D01*
G01X1569954Y1093585D01*
G02X1569893Y1093750I138J145D01*
G01Y1093755D01*
G03X1569902Y1093897I-1193J147D01*
G03X1568700Y1095099I-1202J0D01*
G03X1568574Y1095092I4J-1202D01*
G01X1568531Y1095088D01*
X1568491Y1095101D01*
G02X1568420Y1095142I62J190D01*
G01X1568198Y1095341D01*
G02X1568132Y1095489I134J148D01*
G01Y1095667D01*
G03X1568131Y1095702I-1302J-20D01*
G02Y1095718I200J8D01*
G03X1568132Y1095767I-1301J51D01*
G03X1568114Y1095979I-1302J-4D01*
G01X1568106Y1096026D01*
X1568133Y1096115D01*
X1568388Y1096383D01*
G02X1568554Y1096444I145J-138D01*
G01X1568556D01*
G03X1568700Y1096435I147J1193D01*
G03Y1098839I0J1202D01*
G03X1567498Y1097652I0J-1202D01*
G01Y1097636D01*
G03X1567563Y1097248I1202J2D01*
G01X1567568Y1097233D01*
X1567573Y1097204D01*
G02X1567516Y1097027I-197J-34D01*
G01X1567481Y1096992D01*
X1567388Y1096964D01*
X1567308Y1096979D01*
X1567291Y1096985D01*
G03X1567155Y1097028I-460J-1218D01*
G01X1567132Y1097034D01*
X1567111Y1097039D01*
G03X1566829Y1097070I-283J-1272D01*
G01X1566760D01*
X1566753Y1097069D01*
X1566748D01*
G03X1566734Y1097068I7J-200D01*
G01X1566726Y1097067D01*
X1566721Y1097066D01*
X1566715D01*
G03X1566370Y1096986I119J-1298D01*
G01X1566358Y1096981D01*
X1566330Y1096975D01*
G02X1566146Y1097023I-48J194D01*
G01X1566110Y1097058D01*
X1566078Y1097153D01*
X1566089Y1097217D01*
G02X1566097Y1097248I197J-34D01*
G03X1566162Y1097637I-1137J390D01*
G03X1564960Y1096435I-1202J0D01*
G03X1565101Y1096443I3J1202D01*
G01X1565148Y1096449D01*
X1565236Y1096417D01*
X1565490Y1096152D01*
G02X1565536Y1096076I-144J-139D01*
G01Y1096073D01*
X1565550Y1096028D01*
X1565543Y1095981D01*
Y1095980D01*
X1565541Y1095964D01*
G03X1565525Y1095767I1285J-204D01*
G01Y1095626D01*
X1565526D01*
Y1095250D01*
G02X1565326Y1095050I-200J0D01*
G01X1565299D01*
X1565274Y1095057D01*
G03X1564960Y1095099I-315J-1160D01*
G03X1563758Y1093897I0J-1202D01*
G03X1563767Y1093755I1202J5D01*
G01Y1093751D01*
G02X1563706Y1093585I-199J-21D01*
G01X1563438Y1093330D01*
X1563349Y1093303D01*
X1563302Y1093311D01*
G03X1563091Y1093329I-216J-1284D01*
G01X1563088D01*
G03X1562875Y1093312I-3J-1302D01*
G01X1562829Y1093304D01*
X1562740Y1093332D01*
X1562474Y1093586D01*
G02X1562413Y1093751I138J145D01*
G01Y1093756D01*
G03X1562422Y1093897I-1193J147D01*
G03X1561404Y1095085I-1202J0D01*
G01X1561331Y1095096D01*
X1561235Y1095208D01*
Y1096326D01*
X1561331Y1096438D01*
X1561404Y1096449D01*
G03Y1098825I-184J1188D01*
G01X1561331Y1098836D01*
X1561235Y1098948D01*
Y1100066D01*
X1561331Y1100178D01*
X1561404Y1100189D01*
G03Y1102565I-184J1188D01*
G01X1561331Y1102576D01*
X1561235Y1102688D01*
Y1103806D01*
X1561331Y1103918D01*
X1561404Y1103929D01*
G03Y1106305I-184J1188D01*
G01X1561331Y1106316D01*
X1561235Y1106428D01*
Y1107547D01*
X1561331Y1107659D01*
X1561404Y1107670D01*
G03Y1110046I-184J1188D01*
G01X1561331Y1110057D01*
X1561235Y1110169D01*
Y1130315D01*
G02X1561294Y1130457I200J0D01*
G01X1561347Y1130510D01*
G02X1561470Y1130568I142J-141D01*
G01X1561497Y1130570D01*
X1561550D01*
X1561575Y1130568D01*
G02X1561711Y1130496I-18J-199D01*
G01X1561724Y1130480D01*
X1561802Y1130356D01*
X1561904Y1130193D01*
G02X1561929Y1130039I-170J-107D01*
G01X1561918Y1129996D01*
X1561909Y1129977D01*
G03X1561788Y1129429I1180J-548D01*
G03X1564392I1302J0D01*
G01Y1129431D01*
G03X1564275Y1129969I-1302J-1D01*
G01X1564272Y1129976D01*
X1564257Y1130017D01*
X1564250Y1130050D01*
G02X1564278Y1130198I196J40D01*
G01X1564481Y1130516D01*
X1564561Y1130564D01*
X1564606Y1130568D01*
X1564625Y1130570D01*
X1565277D01*
G02X1565291Y1130569I-7J-199D01*
G01X1565311Y1130568D01*
G02X1565451Y1130496I-14J-200D01*
G01X1565464Y1130480D01*
X1565542Y1130356D01*
X1565644Y1130193D01*
G02X1565669Y1130039I-170J-107D01*
G01X1565658Y1129996D01*
X1565649Y1129977D01*
G03X1565528Y1129429I1180J-548D01*
G03X1568132I1302J0D01*
G01Y1129431D01*
G03X1568015Y1129969I-1302J-1D01*
G01X1568012Y1129976D01*
X1567997Y1130017D01*
X1567990Y1130050D01*
G02X1568018Y1130198I196J40D01*
G01X1568221Y1130516D01*
X1568301Y1130564D01*
X1568346Y1130568D01*
X1568365Y1130570D01*
X1569150D01*
G02X1569321Y1130474I0J-200D01*
G01X1569527Y1130137D01*
X1569530Y1130032D01*
X1569505Y1129985D01*
X1569499Y1129973D01*
X1569494Y1129965D01*
G03X1569368Y1129429I1077J-536D01*
G01X1569369Y1129402D01*
Y1129401D01*
G03X1570571Y1128227I1202J28D01*
G03X1571773Y1129402I0J1202D01*
G01X1571774Y1129429D01*
G03X1571648Y1129965I-1203J0D01*
G01X1571643Y1129973D01*
X1571637Y1129985D01*
X1571612Y1130032D01*
X1571615Y1130137D01*
X1571821Y1130474D01*
G02X1571992Y1130570I171J-104D01*
G01X1572890D01*
G02X1573061Y1130474I0J-200D01*
G01X1573267Y1130137D01*
X1573270Y1130032D01*
X1573245Y1129985D01*
X1573239Y1129973D01*
X1573234Y1129965D01*
G03X1573108Y1129429I1077J-536D01*
G01X1573109Y1129402D01*
Y1129401D01*
G03X1574311Y1128227I1202J28D01*
G03X1575513Y1129402I0J1202D01*
G01X1575514Y1129429D01*
G03X1575388Y1129965I-1203J0D01*
G01X1575383Y1129973D01*
X1575377Y1129985D01*
X1575352Y1130032D01*
X1575355Y1130137D01*
X1575561Y1130474D01*
G02X1575732Y1130570I171J-104D01*
G01X1576630D01*
G02X1576801Y1130474I0J-200D01*
G01X1577007Y1130137D01*
X1577010Y1130032D01*
X1576985Y1129985D01*
X1576979Y1129973D01*
X1576974Y1129965D01*
G03X1576848Y1129429I1077J-536D01*
G01X1576849Y1129402D01*
Y1129401D01*
G03X1578051Y1128227I1202J28D01*
G03X1579253Y1129402I0J1202D01*
G01X1579254Y1129429D01*
G03X1579128Y1129965I-1203J0D01*
G01X1579123Y1129973D01*
X1579117Y1129985D01*
X1579092Y1130032D01*
X1579095Y1130137D01*
X1579301Y1130474D01*
G02X1579472Y1130570I171J-104D01*
G01X1580370D01*
G02X1580541Y1130474I0J-200D01*
G01X1580747Y1130137D01*
X1580750Y1130032D01*
X1580725Y1129985D01*
X1580719Y1129973D01*
X1580714Y1129965D01*
G03X1580588Y1129429I1077J-536D01*
G01X1580589Y1129402D01*
Y1129401D01*
G03X1581791Y1128227I1202J28D01*
G03X1582993Y1129402I0J1202D01*
G01X1582994Y1129429D01*
G03X1582868Y1129965I-1203J0D01*
G01X1582863Y1129973D01*
X1582857Y1129985D01*
X1582832Y1130032D01*
X1582835Y1130137D01*
X1583041Y1130474D01*
G02X1583212Y1130570I171J-104D01*
G01X1584110D01*
G02X1584281Y1130474I0J-200D01*
G01X1584487Y1130137D01*
X1584490Y1130032D01*
X1584465Y1129985D01*
X1584459Y1129973D01*
X1584454Y1129965D01*
G03X1584328Y1129429I1077J-536D01*
G01X1584329Y1129402D01*
Y1129401D01*
G03X1585531Y1128227I1202J28D01*
G03X1586733Y1129402I0J1202D01*
G01X1586734Y1129429D01*
G03X1586608Y1129965I-1203J0D01*
G01X1586603Y1129973D01*
X1586597Y1129985D01*
X1586572Y1130032D01*
X1586575Y1130137D01*
X1586781Y1130474D01*
G02X1586952Y1130570I171J-104D01*
G01X1587850D01*
G02X1588021Y1130474I0J-200D01*
G01X1588227Y1130137D01*
X1588230Y1130032D01*
X1588205Y1129985D01*
X1588199Y1129973D01*
X1588194Y1129965D01*
G03X1588068Y1129429I1077J-536D01*
G01X1588069Y1129402D01*
Y1129401D01*
G03X1589271Y1128227I1202J28D01*
G03X1590473Y1129402I0J1202D01*
G01X1590474Y1129429D01*
G03X1590348Y1129965I-1203J0D01*
G01X1590343Y1129973D01*
X1590337Y1129985D01*
X1590312Y1130032D01*
X1590315Y1130137D01*
X1590521Y1130474D01*
G02X1590692Y1130570I171J-104D01*
G01X1591590D01*
G02X1591761Y1130474I0J-200D01*
G01X1591967Y1130137D01*
X1591970Y1130032D01*
X1591945Y1129985D01*
X1591939Y1129973D01*
X1591934Y1129965D01*
G03X1591808Y1129429I1077J-536D01*
G01X1591809Y1129402D01*
Y1129401D01*
G03X1593011Y1128227I1202J28D01*
G03X1594213Y1129402I0J1202D01*
G01X1594214Y1129429D01*
G03X1594088Y1129965I-1203J0D01*
G01X1594083Y1129973D01*
X1594077Y1129985D01*
X1594052Y1130032D01*
X1594055Y1130137D01*
X1594261Y1130474D01*
G02X1594432Y1130570I171J-104D01*
G01X1595331D01*
G02X1595502Y1130474I0J-200D01*
G01X1595708Y1130137D01*
X1595711Y1130032D01*
X1595686Y1129985D01*
X1595680Y1129973D01*
X1595675Y1129965D01*
G03X1595549Y1129429I1077J-536D01*
G01X1595550Y1129402D01*
Y1129401D01*
G03X1596752Y1128227I1202J28D01*
G03X1597954Y1129402I0J1202D01*
G01X1597955Y1129429D01*
G03X1597829Y1129965I-1203J0D01*
G01X1597824Y1129973D01*
X1597818Y1129985D01*
X1597793Y1130032D01*
X1597796Y1130137D01*
X1598002Y1130474D01*
G02X1598173Y1130570I171J-104D01*
G01X1599071D01*
G02X1599242Y1130474I0J-200D01*
G01X1599448Y1130137D01*
X1599451Y1130032D01*
X1599426Y1129985D01*
X1599420Y1129973D01*
X1599415Y1129965D01*
G03X1599289Y1129429I1077J-536D01*
G01X1599290Y1129402D01*
Y1129401D01*
G03X1600492Y1128227I1202J28D01*
G03X1601694Y1129402I0J1202D01*
G01X1601695Y1129429D01*
G03X1601569Y1129965I-1203J0D01*
G01X1601564Y1129973D01*
X1601558Y1129985D01*
X1601533Y1130032D01*
X1601536Y1130137D01*
X1601742Y1130474D01*
G02X1601913Y1130570I171J-104D01*
G01X1606551D01*
G02X1606722Y1130474I0J-200D01*
G01X1606928Y1130137D01*
X1606931Y1130032D01*
X1606906Y1129985D01*
X1606900Y1129973D01*
X1606895Y1129965D01*
G03X1606769Y1129429I1077J-536D01*
G01X1606770Y1129402D01*
Y1129401D01*
G03X1607972Y1128227I1202J28D01*
G03X1609174Y1129402I0J1202D01*
G01X1609175Y1129429D01*
G03X1609049Y1129965I-1203J0D01*
G01X1609044Y1129973D01*
X1609038Y1129985D01*
X1609013Y1130032D01*
X1609016Y1130137D01*
X1609222Y1130474D01*
G02X1609393Y1130570I171J-104D01*
G01X1610291D01*
G02X1610462Y1130474I0J-200D01*
G01X1610668Y1130137D01*
X1610671Y1130032D01*
X1610646Y1129985D01*
X1610640Y1129973D01*
X1610635Y1129965D01*
G03X1610509Y1129429I1077J-536D01*
G01X1610510Y1129402D01*
Y1129401D01*
G03X1611712Y1128227I1202J28D01*
G03X1612914Y1129402I0J1202D01*
G01X1612915Y1129429D01*
G03X1612789Y1129965I-1203J0D01*
G01X1612784Y1129973D01*
X1612778Y1129985D01*
X1612753Y1130032D01*
X1612756Y1130137D01*
X1612962Y1130474D01*
G02X1613133Y1130570I171J-104D01*
G01X1614031D01*
G02X1614202Y1130474I0J-200D01*
G01X1614408Y1130137D01*
X1614411Y1130032D01*
X1614386Y1129985D01*
X1614380Y1129973D01*
X1614375Y1129965D01*
G03X1614249Y1129429I1077J-536D01*
G01X1614250Y1129402D01*
Y1129401D01*
G03X1615452Y1128227I1202J28D01*
G03X1616654Y1129402I0J1202D01*
G01X1616655Y1129429D01*
G03X1616529Y1129965I-1203J0D01*
G01X1616524Y1129973D01*
X1616518Y1129985D01*
X1616493Y1130032D01*
X1616496Y1130137D01*
X1616702Y1130474D01*
G02X1616873Y1130570I171J-104D01*
G01X1617772D01*
G02X1617943Y1130474I0J-200D01*
G01X1618149Y1130137D01*
X1618152Y1130032D01*
X1618127Y1129985D01*
X1618121Y1129973D01*
X1618116Y1129965D01*
G03X1617990Y1129429I1077J-536D01*
G01X1617991Y1129402D01*
Y1129401D01*
G03X1619193Y1128227I1202J28D01*
G03X1620395Y1129402I0J1202D01*
G01X1620396Y1129429D01*
G03X1620270Y1129965I-1203J0D01*
G01X1620265Y1129973D01*
X1620259Y1129985D01*
X1620234Y1130032D01*
X1620237Y1130137D01*
X1620443Y1130474D01*
G02X1620614Y1130570I171J-104D01*
G01X1621512D01*
G02X1621683Y1130474I0J-200D01*
G01X1621889Y1130137D01*
X1621892Y1130032D01*
X1621867Y1129985D01*
X1621861Y1129973D01*
X1621856Y1129965D01*
G03X1621730Y1129429I1077J-536D01*
G01X1621731Y1129402D01*
Y1129401D01*
G03X1622933Y1128227I1202J28D01*
G03X1624135Y1129402I0J1202D01*
G01X1624136Y1129429D01*
G03X1624010Y1129965I-1203J0D01*
G01X1624005Y1129973D01*
X1623999Y1129985D01*
X1623974Y1130032D01*
X1623977Y1130137D01*
X1624183Y1130474D01*
G02X1624354Y1130570I171J-104D01*
G01X1625252D01*
G02X1625423Y1130474I0J-200D01*
G01X1625629Y1130137D01*
X1625632Y1130032D01*
X1625607Y1129985D01*
X1625601Y1129973D01*
X1625596Y1129965D01*
G03X1625470Y1129429I1077J-536D01*
G01X1625471Y1129402D01*
Y1129401D01*
G03X1626673Y1128227I1202J28D01*
G03X1627875Y1129402I0J1202D01*
G01X1627876Y1129429D01*
G03X1627750Y1129965I-1203J0D01*
G01X1627745Y1129973D01*
X1627739Y1129985D01*
X1627714Y1130032D01*
X1627717Y1130137D01*
X1627923Y1130474D01*
G02X1628094Y1130570I171J-104D01*
G01X1628992D01*
G02X1629163Y1130474I0J-200D01*
G01X1629369Y1130137D01*
X1629372Y1130032D01*
X1629347Y1129985D01*
X1629341Y1129973D01*
X1629336Y1129965D01*
G03X1629210Y1129429I1077J-536D01*
G01X1629211Y1129402D01*
Y1129401D01*
G03X1630413Y1128227I1202J28D01*
G03X1631615Y1129402I0J1202D01*
G01X1631616Y1129429D01*
G03X1631490Y1129965I-1203J0D01*
G01X1631485Y1129973D01*
X1631479Y1129985D01*
X1631454Y1130032D01*
X1631457Y1130137D01*
X1631663Y1130474D01*
G02X1631834Y1130570I171J-104D01*
G01X1632732D01*
G02X1632903Y1130474I0J-200D01*
G01X1633109Y1130137D01*
X1633112Y1130032D01*
X1633087Y1129985D01*
X1633081Y1129973D01*
X1633076Y1129965D01*
G03X1632950Y1129429I1077J-536D01*
G01X1632951Y1129402D01*
Y1129401D01*
G03X1634153Y1128227I1202J28D01*
G03X1635355Y1129402I0J1202D01*
G01X1635356Y1129429D01*
G03X1635230Y1129965I-1203J0D01*
G01X1635225Y1129973D01*
X1635219Y1129985D01*
X1635194Y1130032D01*
X1635197Y1130137D01*
X1635403Y1130474D01*
G02X1635574Y1130570I171J-104D01*
G01X1636472D01*
G02X1636643Y1130474I0J-200D01*
G01X1636849Y1130137D01*
X1636852Y1130032D01*
X1636827Y1129985D01*
X1636821Y1129973D01*
X1636816Y1129965D01*
G03X1636690Y1129429I1077J-536D01*
G01X1636691Y1129402D01*
Y1129401D01*
G03X1637893Y1128227I1202J28D01*
G03X1639095Y1129402I0J1202D01*
G01X1639096Y1129429D01*
G03X1638970Y1129965I-1203J0D01*
G01X1638965Y1129973D01*
X1638959Y1129985D01*
X1638934Y1130032D01*
X1638937Y1130137D01*
X1639143Y1130474D01*
G02X1639314Y1130570I171J-104D01*
G01X1640080D01*
G02X1640094Y1130569I-7J-199D01*
G01X1640114Y1130568D01*
G02X1640254Y1130496I-14J-200D01*
G01X1640267Y1130480D01*
X1640345Y1130356D01*
X1640447Y1130193D01*
G02X1640472Y1130039I-170J-107D01*
G01X1640461Y1129996D01*
X1640452Y1129977D01*
G03X1640331Y1129429I1180J-548D01*
G03X1642935I1302J0D01*
G03X1642380Y1130495I-1301J0D01*
G02X1642294Y1130652I114J165D01*
G01X1642280Y1130808D01*
Y1130810D01*
X1642269Y1130942D01*
G02X1642268Y1130959I199J20D01*
G01Y1130966D01*
G02X1642327Y1131108I200J0D01*
G01X1644528Y1133309D01*
G03X1644587Y1133451I-141J142D01*
G01Y1135250D01*
G02X1644644Y1135390I200J0D01*
G01X1644645Y1135391D01*
X1644660Y1135406D01*
X1644751Y1135478D01*
X1644945Y1135632D01*
X1645033Y1135652D01*
X1645078Y1135641D01*
G03X1645373Y1135607I296J1268D01*
G01X1645374D01*
G03Y1138211I0J1302D01*
G01X1645373D01*
G03X1645078Y1138177I1J-1302D01*
G01X1645033Y1138166D01*
X1644945Y1138186D01*
X1644663Y1138410D01*
G02X1644587Y1138567I124J157D01*
G01Y1138990D01*
G02X1644644Y1139130I200J0D01*
G01X1644645Y1139131D01*
X1644660Y1139146D01*
X1644751Y1139218D01*
X1644945Y1139372D01*
X1645033Y1139392D01*
X1645078Y1139381D01*
G03X1645373Y1139347I296J1268D01*
G01X1645374D01*
G03Y1141951I0J1302D01*
G01X1645373D01*
G03X1645078Y1141917I1J-1302D01*
G01X1645033Y1141906D01*
X1644945Y1141926D01*
X1644663Y1142150D01*
G02X1644587Y1142307I124J157D01*
G01Y1142730D01*
G02X1644644Y1142870I200J0D01*
G01X1644645Y1142871D01*
X1644660Y1142886D01*
X1644751Y1142958D01*
X1644945Y1143112D01*
X1645033Y1143132D01*
X1645078Y1143121D01*
G03X1645373Y1143087I296J1268D01*
G01X1645374D01*
G03Y1145691I0J1302D01*
G01X1645373D01*
G03X1645078Y1145657I1J-1302D01*
G01X1645033Y1145646D01*
X1644945Y1145666D01*
X1644663Y1145890D01*
G02X1644587Y1146047I124J157D01*
G01Y1146470D01*
G02X1644644Y1146610I200J0D01*
G01X1644645Y1146611D01*
X1644660Y1146626D01*
X1644751Y1146698D01*
X1644945Y1146852D01*
X1645033Y1146872D01*
X1645078Y1146861D01*
G03X1645373Y1146827I296J1268D01*
G01X1645374D01*
G03Y1149431I0J1302D01*
G01X1645373D01*
G03X1645078Y1149397I1J-1302D01*
G01X1645033Y1149386D01*
X1644945Y1149406D01*
X1644663Y1149630D01*
G02X1644587Y1149787I124J157D01*
G01Y1150210D01*
G02X1644644Y1150350I200J0D01*
G01X1644645Y1150351D01*
X1644660Y1150366D01*
X1644751Y1150438D01*
X1644945Y1150592D01*
X1645033Y1150612D01*
X1645078Y1150601D01*
G03X1645373Y1150567I296J1268D01*
G01X1645374D01*
G03Y1153171I0J1302D01*
G01X1645373D01*
G03X1645078Y1153137I1J-1302D01*
G01X1645033Y1153126D01*
X1644945Y1153146D01*
X1644663Y1153370D01*
G02X1644587Y1153527I124J157D01*
G01Y1153951D01*
G02X1644644Y1154091I200J0D01*
G01X1644645Y1154092D01*
X1644660Y1154107D01*
X1644751Y1154179D01*
X1644945Y1154333D01*
X1645033Y1154353D01*
X1645078Y1154342D01*
G03X1645373Y1154308I296J1268D01*
G01X1645374D01*
G03Y1156912I0J1302D01*
G01X1645373D01*
G03X1645078Y1156878I1J-1302D01*
G01X1645033Y1156867D01*
X1644945Y1156887D01*
X1644663Y1157111D01*
G02X1644587Y1157268I124J157D01*
G01Y1157691D01*
G02X1644644Y1157831I200J0D01*
G01X1644645Y1157832D01*
X1644660Y1157847D01*
X1644751Y1157919D01*
X1644945Y1158073D01*
X1645033Y1158093D01*
X1645078Y1158082D01*
G03X1645373Y1158048I296J1268D01*
G01X1645374D01*
G03Y1160652I0J1302D01*
G01X1645373D01*
G03X1645078Y1160618I1J-1302D01*
G01X1645033Y1160607D01*
X1644945Y1160627D01*
X1644663Y1160851D01*
G02X1644587Y1161008I124J157D01*
G01Y1165171D01*
G02X1644644Y1165311I200J0D01*
G01X1644645Y1165312D01*
X1644660Y1165327D01*
X1644751Y1165399D01*
X1644945Y1165553D01*
X1645033Y1165573D01*
X1645078Y1165562D01*
G03X1645373Y1165528I296J1268D01*
G01X1645374D01*
G03Y1168132I0J1302D01*
G01X1645373D01*
G03X1645078Y1168098I1J-1302D01*
G01X1645033Y1168087D01*
X1644945Y1168107D01*
X1644663Y1168331D01*
G02X1644587Y1168488I124J157D01*
G01Y1168911D01*
G02X1644644Y1169051I200J0D01*
G01X1644645Y1169052D01*
X1644660Y1169067D01*
X1644751Y1169139D01*
X1644945Y1169293D01*
X1645033Y1169313D01*
X1645078Y1169302D01*
G03X1645373Y1169268I296J1268D01*
G01X1645374D01*
G03Y1171872I0J1302D01*
G01X1645373D01*
G03X1645078Y1171838I1J-1302D01*
G01X1645033Y1171827D01*
X1644945Y1171847D01*
X1644663Y1172071D01*
G02X1644587Y1172228I124J157D01*
G01Y1172651D01*
G02X1644644Y1172791I200J0D01*
G01X1644645Y1172792D01*
X1644660Y1172807D01*
X1644751Y1172879D01*
X1644945Y1173033D01*
X1645033Y1173053D01*
X1645078Y1173042D01*
G03X1645373Y1173008I296J1268D01*
G01X1645374D01*
G03Y1175612I0J1302D01*
G01X1645373D01*
G03X1645078Y1175578I1J-1302D01*
G01X1645033Y1175567D01*
X1644945Y1175587D01*
X1644663Y1175811D01*
G02X1644587Y1175968I124J157D01*
G01Y1176392D01*
G02X1644644Y1176532I200J0D01*
G01X1644645Y1176533D01*
X1644660Y1176548D01*
X1644751Y1176620D01*
X1644945Y1176774D01*
X1645033Y1176794D01*
X1645078Y1176783D01*
G03X1645373Y1176749I296J1268D01*
G01X1645374D01*
G03Y1179353I0J1302D01*
G01X1645373D01*
G03X1645078Y1179319I1J-1302D01*
G01X1645033Y1179308D01*
X1644945Y1179328D01*
X1644663Y1179552D01*
G02X1644587Y1179709I124J157D01*
G01Y1180132D01*
G02X1644644Y1180272I200J0D01*
G01X1644645Y1180273D01*
X1644660Y1180288D01*
X1644751Y1180360D01*
X1644945Y1180514D01*
X1645033Y1180534D01*
X1645078Y1180523D01*
G03X1645373Y1180489I296J1268D01*
G01X1645374D01*
G03Y1183093I0J1302D01*
G01X1645373D01*
G03X1645078Y1183059I1J-1302D01*
G01X1645033Y1183048D01*
X1644945Y1183068D01*
X1644663Y1183292D01*
G02X1644587Y1183449I124J157D01*
G01Y1183872D01*
G02X1644644Y1184012I200J0D01*
G01X1644645Y1184013D01*
X1644660Y1184028D01*
X1644751Y1184100D01*
X1644945Y1184254D01*
X1645033Y1184274D01*
X1645078Y1184263D01*
G03X1645373Y1184229I296J1268D01*
G01X1645374D01*
G03Y1186833I0J1302D01*
G01X1645373D01*
G03X1645078Y1186799I1J-1302D01*
G01X1645033Y1186788D01*
X1644945Y1186808D01*
X1644663Y1187032D01*
G02X1644587Y1187189I124J157D01*
G01Y1187612D01*
G02X1644644Y1187752I200J0D01*
G01X1644645Y1187753D01*
X1644660Y1187768D01*
X1644751Y1187840D01*
X1644945Y1187994D01*
X1645033Y1188014D01*
X1645078Y1188003D01*
G03X1645373Y1187969I296J1268D01*
G01X1645374D01*
G03Y1190573I0J1302D01*
G01X1645373D01*
G03X1645078Y1190539I1J-1302D01*
G01X1645033Y1190528D01*
X1644945Y1190548D01*
X1644663Y1190772D01*
G02X1644587Y1190929I124J157D01*
G01Y1191352D01*
G02X1644644Y1191492I200J0D01*
G01X1644645Y1191493D01*
X1644660Y1191508D01*
X1644751Y1191580D01*
X1644945Y1191734D01*
X1645033Y1191754D01*
X1645078Y1191743D01*
G03X1645373Y1191709I296J1268D01*
G01X1645374D01*
G03Y1194313I0J1302D01*
G01X1645373D01*
G03X1645078Y1194279I1J-1302D01*
G01X1645033Y1194268D01*
X1644945Y1194288D01*
X1644663Y1194512D01*
G02X1644587Y1194669I124J157D01*
G01Y1195092D01*
G02X1644644Y1195232I200J0D01*
G01X1644645Y1195233D01*
X1644660Y1195248D01*
X1644751Y1195320D01*
X1644945Y1195474D01*
X1645033Y1195494D01*
X1645078Y1195483D01*
G03X1645373Y1195449I296J1268D01*
G01X1645374D01*
G03Y1198053I0J1302D01*
G03X1644079Y1196883I0J-1302D01*
G01X1644073Y1196825D01*
X1644001Y1196733D01*
X1643757Y1196649D01*
X1643605Y1196596D01*
G02X1643505Y1196588I-65J189D01*
G01X1643454Y1196597D01*
X1643414Y1196629D01*
X1643405Y1196636D01*
X1642885Y1197156D01*
X1642868Y1197198D01*
X1642854Y1197233D01*
G03X1642117Y1197948I-1201J-501D01*
G01X1642077Y1197964D01*
X1641526Y1198515D01*
G02X1641479Y1198723I142J141D01*
G01X1641586Y1199026D01*
G02X1641664Y1199126I189J-67D01*
G01X1641673Y1199132D01*
X1641764Y1199194D01*
X1641811Y1199201D01*
G03X1642935Y1200491I-178J1290D01*
G03X1640331I-1302J0D01*
G03X1640982Y1199363I1303J0D01*
G01X1641004Y1199350D01*
X1641040Y1199314D01*
X1641092Y1199226D01*
G02X1641106Y1199198I-171J-103D01*
G02X1641118Y1199159I-184J-78D01*
G02Y1199089I-197J-35D01*
G01X1641112Y1199059D01*
G02X1640915Y1198894I-197J35D01*
G01X1640772D01*
G02X1640632Y1198951I0J200D01*
G01X1640527Y1199054D01*
X1640526Y1199055D01*
G03X1640385Y1199114I-142J-141D01*
G01X1639163D01*
G02X1638983Y1199226I0J200D01*
G01X1638832Y1199535D01*
G02X1638823Y1199689I180J88D01*
G01X1638846Y1199757D01*
X1638864Y1199781D01*
G03X1639095Y1200489I-973J709D01*
G01Y1200491D01*
G03X1636691I-1202J0D01*
G01Y1200489D01*
G03X1636922Y1199781I1204J1D01*
G01X1636940Y1199757D01*
X1636963Y1199689D01*
G02X1636954Y1199535I-189J-66D01*
G01X1636803Y1199226D01*
G02X1636623Y1199114I-180J88D01*
G01X1635423D01*
G02X1635243Y1199226I0J200D01*
G01X1635092Y1199535D01*
G02X1635083Y1199689I180J88D01*
G01X1635106Y1199757D01*
X1635124Y1199781D01*
G03X1635355Y1200489I-973J709D01*
G01Y1200491D01*
G03X1632951I-1202J0D01*
G01Y1200489D01*
G03X1633182Y1199781I1204J1D01*
G01X1633200Y1199757D01*
X1633223Y1199689D01*
G02X1633214Y1199535I-189J-66D01*
G01X1633063Y1199226D01*
G02X1632883Y1199114I-180J88D01*
G01X1631683D01*
G02X1631503Y1199226I0J200D01*
G01X1631352Y1199535D01*
G02X1631343Y1199689I180J88D01*
G01X1631366Y1199757D01*
X1631384Y1199781D01*
G03X1631615Y1200489I-973J709D01*
G01Y1200491D01*
G03X1629211I-1202J0D01*
G01Y1200489D01*
G03X1629442Y1199781I1204J1D01*
G01X1629460Y1199757D01*
X1629483Y1199689D01*
G02X1629474Y1199535I-189J-66D01*
G01X1629323Y1199226D01*
G02X1629143Y1199114I-180J88D01*
G01X1627943D01*
G02X1627763Y1199226I0J200D01*
G01X1627612Y1199535D01*
G02X1627603Y1199689I180J88D01*
G01X1627626Y1199757D01*
X1627644Y1199781D01*
G03X1627875Y1200489I-973J709D01*
G01Y1200491D01*
G03X1625471I-1202J0D01*
G01Y1200489D01*
G03X1625702Y1199781I1204J1D01*
G01X1625720Y1199757D01*
X1625743Y1199689D01*
G02X1625734Y1199535I-189J-66D01*
G01X1625583Y1199226D01*
G02X1625403Y1199114I-180J88D01*
G01X1624203D01*
G02X1624023Y1199226I0J200D01*
G01X1623872Y1199535D01*
G02X1623863Y1199689I180J88D01*
G01X1623886Y1199757D01*
X1623904Y1199781D01*
G03X1624135Y1200489I-973J709D01*
G01Y1200491D01*
G03X1621731I-1202J0D01*
G01Y1200489D01*
G03X1621962Y1199781I1204J1D01*
G01X1621980Y1199757D01*
X1622003Y1199689D01*
G02X1621994Y1199535I-189J-66D01*
G01X1621843Y1199226D01*
G02X1621663Y1199114I-180J88D01*
G01X1620463D01*
G02X1620283Y1199226I0J200D01*
G01X1620132Y1199535D01*
G02X1620123Y1199689I180J88D01*
G01X1620146Y1199757D01*
X1620164Y1199781D01*
G03X1620395Y1200489I-973J709D01*
G01Y1200491D01*
G03X1617991I-1202J0D01*
G01Y1200489D01*
G03X1618222Y1199781I1204J1D01*
G01X1618240Y1199757D01*
X1618263Y1199689D01*
G02X1618254Y1199535I-189J-66D01*
G01X1618103Y1199226D01*
G02X1617923Y1199114I-180J88D01*
G01X1616722D01*
G02X1616542Y1199226I0J200D01*
G01X1616391Y1199535D01*
G02X1616382Y1199689I180J88D01*
G01X1616405Y1199757D01*
X1616423Y1199781D01*
G03X1616654Y1200489I-973J709D01*
G01Y1200491D01*
G03X1614250I-1202J0D01*
G01Y1200489D01*
G03X1614481Y1199781I1204J1D01*
G01X1614499Y1199757D01*
X1614522Y1199689D01*
G02X1614513Y1199535I-189J-66D01*
G01X1614362Y1199226D01*
G02X1614182Y1199114I-180J88D01*
G01X1612982D01*
G02X1612802Y1199226I0J200D01*
G01X1612651Y1199535D01*
G02X1612642Y1199689I180J88D01*
G01X1612665Y1199757D01*
X1612683Y1199781D01*
G03X1612914Y1200489I-973J709D01*
G01Y1200491D01*
G03X1610510I-1202J0D01*
G01Y1200489D01*
G03X1610741Y1199781I1204J1D01*
G01X1610759Y1199757D01*
X1610782Y1199689D01*
G02X1610773Y1199535I-189J-66D01*
G01X1610622Y1199226D01*
G02X1610442Y1199114I-180J88D01*
G01X1609242D01*
G02X1609062Y1199226I0J200D01*
G01X1608911Y1199535D01*
G02X1608902Y1199689I180J88D01*
G01X1608925Y1199757D01*
X1608943Y1199781D01*
G03X1609174Y1200489I-973J709D01*
G01Y1200491D01*
G03X1606770I-1202J0D01*
G01Y1200489D01*
G03X1607001Y1199781I1204J1D01*
G01X1607019Y1199757D01*
X1607042Y1199689D01*
G02X1607033Y1199535I-189J-66D01*
G01X1606882Y1199226D01*
G02X1606702Y1199114I-180J88D01*
G01X1601762D01*
G02X1601582Y1199226I0J200D01*
G01X1601431Y1199535D01*
G02X1601422Y1199689I180J88D01*
G01X1601445Y1199757D01*
X1601463Y1199781D01*
G03X1601694Y1200489I-973J709D01*
G01Y1200491D01*
G03X1599290I-1202J0D01*
G01Y1200489D01*
G03X1599521Y1199781I1204J1D01*
G01X1599539Y1199757D01*
X1599562Y1199689D01*
G02X1599553Y1199535I-189J-66D01*
G01X1599402Y1199226D01*
G02X1599222Y1199114I-180J88D01*
G01X1598022D01*
G02X1597842Y1199226I0J200D01*
G01X1597691Y1199535D01*
G02X1597682Y1199689I180J88D01*
G01X1597705Y1199757D01*
X1597723Y1199781D01*
G03X1597954Y1200489I-973J709D01*
G01Y1200491D01*
G03X1595550I-1202J0D01*
G01Y1200489D01*
G03X1595781Y1199781I1204J1D01*
G01X1595799Y1199757D01*
X1595822Y1199689D01*
G02X1595813Y1199535I-189J-66D01*
G01X1595662Y1199226D01*
G02X1595482Y1199114I-180J88D01*
G01X1594281D01*
G02X1594101Y1199226I0J200D01*
G01X1593950Y1199535D01*
G02X1593941Y1199689I180J88D01*
G01X1593964Y1199757D01*
X1593982Y1199781D01*
G03X1594213Y1200489I-973J709D01*
G01Y1200491D01*
G03X1591809I-1202J0D01*
G01Y1200489D01*
G03X1592040Y1199781I1204J1D01*
G01X1592058Y1199757D01*
X1592081Y1199689D01*
G02X1592072Y1199535I-189J-66D01*
G01X1591921Y1199226D01*
G02X1591741Y1199114I-180J88D01*
G01X1590541D01*
G02X1590361Y1199226I0J200D01*
G01X1590210Y1199535D01*
G02X1590201Y1199689I180J88D01*
G01X1590224Y1199757D01*
X1590242Y1199781D01*
G03X1590473Y1200489I-973J709D01*
G01Y1200491D01*
G03X1588069I-1202J0D01*
G01Y1200489D01*
G03X1588300Y1199781I1204J1D01*
G01X1588318Y1199757D01*
X1588341Y1199689D01*
G02X1588332Y1199535I-189J-66D01*
G01X1588181Y1199226D01*
G02X1588001Y1199114I-180J88D01*
G01X1586801D01*
G02X1586621Y1199226I0J200D01*
G01X1586470Y1199535D01*
G02X1586461Y1199689I180J88D01*
G01X1586484Y1199757D01*
X1586502Y1199781D01*
G03X1586733Y1200489I-973J709D01*
G01Y1200491D01*
G03X1584329I-1202J0D01*
G01Y1200489D01*
G03X1584560Y1199781I1204J1D01*
G01X1584578Y1199757D01*
X1584601Y1199689D01*
G02X1584592Y1199535I-189J-66D01*
G01X1584441Y1199226D01*
G02X1584261Y1199114I-180J88D01*
G01X1583061D01*
G02X1582881Y1199226I0J200D01*
G01X1582730Y1199535D01*
G02X1582721Y1199689I180J88D01*
G01X1582744Y1199757D01*
X1582762Y1199781D01*
G03X1582993Y1200489I-973J709D01*
G01Y1200491D01*
G03X1580589I-1202J0D01*
G01Y1200489D01*
G03X1580820Y1199781I1204J1D01*
G01X1580838Y1199757D01*
X1580861Y1199689D01*
G02X1580852Y1199535I-189J-66D01*
G01X1580701Y1199226D01*
G02X1580521Y1199114I-180J88D01*
G01X1579321D01*
G02X1579141Y1199226I0J200D01*
G01X1578990Y1199535D01*
G02X1578981Y1199689I180J88D01*
G01X1579004Y1199757D01*
X1579022Y1199781D01*
G03X1579253Y1200489I-973J709D01*
G01Y1200491D01*
G03X1576849I-1202J0D01*
G01Y1200489D01*
G03X1577080Y1199781I1204J1D01*
G01X1577098Y1199757D01*
X1577121Y1199689D01*
G02X1577112Y1199535I-189J-66D01*
G01X1576961Y1199226D01*
G02X1576781Y1199114I-180J88D01*
G01X1575581D01*
G02X1575401Y1199226I0J200D01*
G01X1575250Y1199535D01*
G02X1575241Y1199689I180J88D01*
G01X1575264Y1199757D01*
X1575282Y1199781D01*
G03X1575513Y1200489I-973J709D01*
G01Y1200491D01*
G03X1573109I-1202J0D01*
G01Y1200489D01*
G03X1573340Y1199781I1204J1D01*
G01X1573358Y1199757D01*
X1573381Y1199689D01*
G02X1573372Y1199535I-189J-66D01*
G01X1573221Y1199226D01*
G02X1573041Y1199114I-180J88D01*
G01X1571841D01*
G02X1571661Y1199226I0J200D01*
G01X1571510Y1199535D01*
G02X1571501Y1199689I180J88D01*
G01X1571524Y1199757D01*
X1571542Y1199781D01*
G03X1571773Y1200489I-973J709D01*
G01Y1200491D01*
G03X1570571Y1201693I-1202J0D01*
G03X1569387Y1200701I0J-1203D01*
G02X1569250Y1200545I-197J35D01*
G01X1568912Y1200439D01*
G02X1568711Y1200488I-60J191D01*
G01X1568331Y1200868D01*
G02X1568272Y1201010I141J142D01*
G01Y1217420D01*
G02X1568331Y1217562I200J0D01*
G01X1569062Y1218293D01*
G02X1569206Y1218352I142J-141D01*
G01X1569454Y1218349D01*
G02X1569532Y1218332I-3J-200D01*
G01X1569568Y1218316D01*
X1569572Y1218314D01*
X1569573D01*
X1569637Y1218288D01*
G03X1569660Y1218261I163J116D01*
G03X1570570Y1217890I910J931D01*
G01X1570571D01*
G03X1571873Y1219192I0J1302D01*
G01Y1219223D01*
X1571871Y1219283D01*
X1571937Y1219387D01*
X1571994Y1219411D01*
G03X1572017Y1219421I-1502J3487D01*
G01X1572056Y1219438D01*
X1572057D01*
G03X1572397Y1219603I-1486J3494D01*
G01X1572420Y1219615D01*
X1572474Y1219628D01*
G02X1572626Y1219604I47J-194D01*
G01X1572888Y1219441D01*
G02X1572924Y1219413I-104J-171D01*
G01X1572951Y1219386D01*
G02X1572996Y1219318I-141J-142D01*
G01X1573011Y1219279D01*
X1573010Y1219234D01*
Y1219233D01*
G03X1573009Y1219193I1301J-53D01*
G01Y1219191D01*
G03X1574311Y1217890I1302J1D01*
G03X1575613Y1219192I0J1302D01*
G03X1575612Y1219231I-1302J-14D01*
G01Y1219256D01*
G02X1575707Y1219426I200J0D01*
G01X1576000Y1219606D01*
X1576013Y1219614D01*
X1576026Y1219620D01*
X1576031Y1219622D01*
G02X1576119Y1219638I79J-184D01*
G01X1576169Y1219636D01*
X1576210Y1219613D01*
G03X1576596Y1219426I1845J3317D01*
G01X1576624Y1219414D01*
X1576676Y1219371D01*
G02X1576749Y1219216I-127J-155D01*
G01Y1219192D01*
G03X1579353I1302J0D01*
G01Y1219223D01*
X1579351Y1219283D01*
X1579417Y1219387D01*
X1579474Y1219411D01*
G03X1579497Y1219421I-1502J3487D01*
G01X1579536Y1219438D01*
X1579537D01*
G03X1579877Y1219603I-1486J3494D01*
G01X1579900Y1219615D01*
X1579954Y1219628D01*
G02X1580106Y1219604I47J-194D01*
G01X1580368Y1219441D01*
G02X1580404Y1219413I-104J-171D01*
G01X1580431Y1219386D01*
G02X1580476Y1219318I-141J-142D01*
G01X1580491Y1219279D01*
X1580490Y1219234D01*
Y1219233D01*
G03X1580489Y1219193I1301J-53D01*
G01Y1219191D01*
G03X1581791Y1217890I1302J1D01*
G03X1583093Y1219192I0J1302D01*
G03X1583092Y1219231I-1302J-14D01*
G01Y1219256D01*
G02X1583187Y1219426I200J0D01*
G01X1583480Y1219606D01*
X1583493Y1219614D01*
X1583506Y1219620D01*
X1583511Y1219622D01*
G02X1583599Y1219638I79J-184D01*
G01X1583649Y1219636D01*
X1583690Y1219613D01*
G03X1584076Y1219426I1845J3317D01*
G01X1584104Y1219414D01*
X1584156Y1219371D01*
G02X1584229Y1219216I-127J-155D01*
G01Y1219192D01*
G03X1586833I1302J0D01*
G01Y1219223D01*
X1586831Y1219283D01*
X1586897Y1219387D01*
X1586954Y1219411D01*
G03X1586977Y1219421I-1502J3487D01*
G01X1587016Y1219438D01*
X1587017D01*
G03X1587357Y1219603I-1486J3494D01*
G01X1587380Y1219615D01*
X1587434Y1219628D01*
G02X1587586Y1219604I47J-194D01*
G01X1587848Y1219441D01*
G02X1587884Y1219413I-104J-171D01*
G01X1587911Y1219386D01*
G02X1587956Y1219318I-141J-142D01*
G01X1587971Y1219279D01*
X1587970Y1219234D01*
Y1219233D01*
G03X1587969Y1219193I1301J-53D01*
G01Y1219191D01*
G03X1589271Y1217890I1302J1D01*
G03X1589483Y1217908I-4J1302D01*
G01X1589530Y1217916D01*
X1589619Y1217889D01*
X1589887Y1217634D01*
G02X1589948Y1217468I-138J-145D01*
G01Y1217464D01*
G03X1589939Y1217323I1193J-147D01*
G01Y1217321D01*
G03X1589960Y1217102I1202J5D01*
G01Y1217100D01*
G02X1589905Y1216923I-197J-36D01*
G01X1589670Y1216688D01*
G02X1589493Y1216633I-141J142D01*
G01X1589492D01*
G03X1589271Y1216654I-224J-1181D01*
G03X1590473Y1215452I0J-1202D01*
G03X1590452Y1215672I-1202J-4D01*
G01Y1215674D01*
G02X1590507Y1215851I197J36D01*
G01X1590742Y1216086D01*
G02X1590919Y1216141I141J-142D01*
G01X1590920D01*
G03X1591141Y1216120I224J1181D01*
G03X1591364Y1216141I-1J1202D01*
G02X1591542Y1216086I37J-197D01*
G01X1591776Y1215852D01*
G02X1591831Y1215674I-142J-141D01*
G03X1591810Y1215452I1181J-224D01*
G03X1593012Y1216654I1202J0D01*
G03X1592789Y1216633I1J-1202D01*
G01X1592741Y1216624D01*
X1592646Y1216653D01*
X1592377Y1216922D01*
G02X1592322Y1217100I142J141D01*
G03X1592343Y1217322I-1181J224D01*
G03X1592334Y1217464I-1202J-5D01*
G01Y1217468D01*
G02X1592395Y1217634I199J21D01*
G01X1592663Y1217889D01*
X1592752Y1217916D01*
X1592799Y1217908D01*
G03X1593011Y1217890I216J1284D01*
G03X1594313Y1219192I0J1302D01*
G01Y1219205D01*
G02X1594372Y1219347I200J0D01*
G01X1594439Y1219414D01*
X1594476Y1219429D01*
G03X1594559Y1219464I-1434J3516D01*
G01X1594631Y1219498D01*
X1594654Y1219509D01*
G03X1594762Y1219563I-1644J3423D01*
G01X1594806Y1219586D01*
X1594807D01*
X1594843Y1219606D01*
X1594860Y1219615D01*
G02X1595032Y1219622I93J-177D01*
G01X1595055Y1219612D01*
X1595208Y1219518D01*
X1595313Y1219454D01*
G02X1595384Y1219378I-106J-170D01*
G01X1595426Y1219300D01*
G02X1595450Y1219205I-176J-95D01*
G01Y1219191D01*
G03X1596752Y1217890I1302J1D01*
G03X1598054Y1219192I0J1302D01*
G03X1598053Y1219235I-1302J-9D01*
G01Y1219255D01*
G02X1598143Y1219422I200J0D01*
G01X1598145Y1219423D01*
X1598490Y1219637D01*
X1598599Y1219640D01*
X1598647Y1219613D01*
G03X1599105Y1219397I1845J3318D01*
G01X1599132Y1219386D01*
X1599178Y1219350D01*
X1599271Y1219219D01*
X1599290Y1219166D01*
X1599291Y1219136D01*
G03X1600492Y1217990I1201J56D01*
G03X1601693Y1219135I0J1202D01*
G01X1601694Y1219165D01*
X1601713Y1219217D01*
X1601810Y1219354D01*
G02X1601947Y1219437I163J-115D01*
G01X1601989Y1219443D01*
G03X1602842Y1219951I-1499J3488D01*
G01X1602851Y1219958D01*
X1602888Y1219981D01*
X1602897Y1219985D01*
G03X1603440Y1220528I-534J1077D01*
G01X1603444Y1220537D01*
X1603467Y1220574D01*
X1603474Y1220583D01*
G03X1603892Y1221246I-2986J2346D01*
G02X1603986Y1221338I179J-89D01*
G03X1604300Y1221504I-1629J3462D01*
G37*
G36*
G01X1750229Y995486D02*
X1751354D01*
G02X1751554Y995286I0J-200D01*
G01Y992857D01*
X1751476Y992752D01*
X1751412Y992733D01*
G03Y989861I443J-1436D01*
G01X1751476Y989842D01*
X1751554Y989737D01*
Y986292D01*
G02X1751495Y986151I-200J1D01*
G01X1747509Y982165D01*
G02X1747368Y982106I-142J141D01*
G01X1731735D01*
G03X1730104Y981431I-1J-2306D01*
G01X1657510Y908837D01*
G03X1656834Y907206I1631J-1632D01*
G01Y776741D01*
G02X1656776Y776600I-200J0D01*
G01X1655411Y775235D01*
G03X1655039Y774748I1631J-1631D01*
G01X1655014Y774737D01*
X1654955Y774731D01*
X1654733Y774776D01*
G02X1654575Y774938I39J196D01*
G01X1635381Y885154D01*
X1635466Y885285D01*
X1635543Y885304D01*
G03X1636678Y886761I-368J1457D01*
G03X1635176Y888263I-1502J0D01*
G03X1635029Y888256I-2J-1502D01*
G01X1634950Y888248D01*
X1634826Y888343D01*
X1629546Y918656D01*
X1617077Y990738D01*
G02X1617074Y990772I197J35D01*
G01Y992128D01*
G02X1617133Y992270I200J0D01*
G01X1620290Y995427D01*
G02X1620432Y995486I142J-141D01*
G01X1651546D01*
X1651548D01*
G02X1651715Y995393I-2J-200D01*
G02X1651729Y995366I-170J-105D01*
G01X1651869Y995049D01*
G02X1651872Y994896I-183J-80D01*
G01X1651840Y994816D01*
X1651817Y994789D01*
G03X1651442Y993796I1127J-993D01*
G01Y993762D01*
G03X1652352Y992416I1502J35D01*
G01X1652401Y992395D01*
X1652463Y992313D01*
X1652520Y991925D01*
G02X1652494Y991794I-198J-29D01*
G01X1652476Y991764D01*
X1652450Y991742D01*
G03X1651912Y990590I964J-1152D01*
G03X1654916I1502J0D01*
G03X1654006Y991970I-1501J0D01*
G01X1653957Y991991D01*
X1653895Y992073D01*
X1653838Y992461D01*
G02X1653864Y992592I198J29D01*
G01X1653882Y992622D01*
X1653908Y992644D01*
G03X1654446Y993762I-964J1152D01*
G01Y993796D01*
G03X1654071Y994789I-1502J0D01*
G01X1654048Y994816D01*
X1654016Y994896D01*
G02X1654019Y995049I186J73D01*
G01X1654159Y995366D01*
G02X1654173Y995393I184J-78D01*
G02X1654340Y995486I169J-107D01*
G01X1747125D01*
G02X1747303Y995378I0J-200D01*
G01X1747492Y995012D01*
X1747484Y994901D01*
X1747452Y994855D01*
G03X1747175Y993986I1225J-869D01*
G03X1750179I1502J0D01*
G03X1749902Y994855I-1502J0D01*
G01X1749870Y994901D01*
X1749862Y995012D01*
X1750051Y995378D01*
G02X1750229Y995486I178J-92D01*
G37*
G36*
G01X1713642Y54588D02*
X1742687D01*
X1742830Y54445D01*
Y52734D01*
X1742687Y52591D01*
X1713642D01*
G03X1707705Y46654I0J-5937D01*
G01Y7874D01*
G02X1701831Y2000I-5874J0D01*
G01X1654587D01*
G02X1648713Y7874I0J5874D01*
G01Y46210D01*
X1650710D01*
Y7874D01*
G03X1654585Y3998I3876J0D01*
G01X1701831D01*
G03X1705708Y7874I0J3877D01*
G01Y46654D01*
G02X1713642Y54588I7934J0D01*
G37*
%LPC*%
G75*
G36*
G01X1798857Y1264675D02*
X1798858Y1264676D01*
G02X1799845Y1265046I987J-1131D01*
G02X1801347Y1263544I0J-1502D01*
G02X1800977Y1262557I-1501J0D01*
G01Y1262556D01*
X1800976D01*
G03X1800928Y1262426I152J-130D01*
G01Y1262162D01*
G03X1800976Y1262032I200J0D01*
G01X1800977Y1262031D01*
G02X1801347Y1261044I-1131J-987D01*
G02X1799845Y1259542I-1502J0D01*
G02X1798858Y1259912I0J1501D01*
G01X1798857D01*
Y1259913D01*
G03X1798727Y1259961I-130J-152D01*
G01X1798463D01*
G03X1798333Y1259913I0J-200D01*
G01X1798332Y1259912D01*
G02X1796358I-987J1131D01*
G01X1796357D01*
Y1259913D01*
G03X1796227Y1259961I-130J-152D01*
G01X1795963D01*
G03X1795833Y1259913I0J-200D01*
G01X1795832Y1259912D01*
G02X1794845Y1259542I-987J1131D01*
G02X1793343Y1261044I0J1502D01*
G02X1793713Y1262031I1501J0D01*
G01Y1262032D01*
X1793714D01*
G03X1793762Y1262162I-152J130D01*
G01Y1262426D01*
G03X1793714Y1262556I-200J0D01*
G01X1793713Y1262557D01*
G02X1793343Y1263544I1131J987D01*
G02X1794845Y1265046I1502J0D01*
G02X1795832Y1264676I0J-1501D01*
G01X1795833D01*
Y1264675D01*
G03X1795963Y1264627I130J152D01*
G01X1796227D01*
G03X1796357Y1264675I0J200D01*
G01X1796358Y1264676D01*
G02X1798332I987J-1131D01*
G01X1798333Y1264675D01*
G03X1798463Y1264627I130J152D01*
G01X1798727D01*
G03X1798857Y1264675I0J200D01*
G37*
G36*
G01X1811565Y1299696D02*
G03X1811712Y1299761I-1J200D01*
G02X1813924I1106J-1017D01*
G03X1814071Y1299696I148J135D01*
G01X1814365D01*
G03X1814512Y1299761I-1J200D01*
G02X1815618Y1300246I1106J-1019D01*
G02X1817120Y1298744I0J-1502D01*
G02X1816635Y1297638I-1504J0D01*
G03X1816570Y1297491I135J-148D01*
G01Y1297197D01*
G03X1816635Y1297050I200J1D01*
G02X1817120Y1295944I-1019J-1106D01*
G02X1815618Y1294442I-1502J0D01*
G02X1814512Y1294927I0J1504D01*
G03X1814365Y1294992I-148J-135D01*
G01X1814071D01*
G03X1813924Y1294927I1J-200D01*
G02X1811712I-1106J1017D01*
G03X1811565Y1294992I-148J-135D01*
G01X1811271D01*
G03X1811124Y1294927I1J-200D01*
G02X1810018Y1294442I-1106J1019D01*
G02X1808516Y1295944I0J1502D01*
G02X1809001Y1297050I1504J0D01*
G03X1809066Y1297197I-135J148D01*
G01Y1297491D01*
G03X1809001Y1297638I-200J-1D01*
G02X1808516Y1298744I1019J1106D01*
G02X1810018Y1300246I1502J0D01*
G02X1811124Y1299761I0J-1504D01*
G03X1811271Y1299696I148J135D01*
G01X1811565D01*
G37*
G36*
G01X1591968Y1459365D02*
G02X1591141Y1460707I675J1342D01*
G02X1594145I1502J0D01*
G02X1593614Y1459561I-1502J0D01*
G03X1593694Y1458899I259J-305D01*
G02X1594521Y1457557I-675J-1342D01*
G02X1591517I-1502J0D01*
G02X1592048Y1458703I1502J0D01*
G03X1591968Y1459365I-259J305D01*
G37*
G36*
G01X1802710Y1466164D02*
G02X1802260Y1467236I1052J1072D01*
G02X1805264I1502J0D01*
G02X1804064Y1465765I-1502J0D01*
G03X1803865Y1465087I81J-392D01*
G02X1804315Y1464015I-1052J-1072D01*
G02X1801311I-1502J0D01*
G02X1802511Y1465486I1502J0D01*
G03X1802710Y1466164I-81J392D01*
G37*
G36*
G01X1597039Y1473598D02*
G02Y1476602I0J1502D01*
G02X1598143Y1476118I0J-1501D01*
G01X1598144Y1476117D01*
G03X1598282Y1476054I146J137D01*
G01X1598605Y1476041D01*
X1598679Y1476068D01*
X1598708Y1476095D01*
G02X1599725Y1476492I1017J-1105D01*
G01X1599726D01*
G02Y1473488I0J-1502D01*
G02X1598622Y1473972I0J1501D01*
G01X1598621Y1473973D01*
G03X1598483Y1474036I-146J-137D01*
G01X1598160Y1474049D01*
X1598086Y1474022D01*
X1598057Y1473995D01*
G02X1597040Y1473598I-1017J1105D01*
G01X1597039D01*
G37*
G36*
G01X1667246Y1496659D02*
G02X1667448Y1496862I202J1D01*
G01X1670268D01*
G02X1670470Y1496659I-1J-203D01*
G01Y1495533D01*
G03X1670498Y1495430I200J-1D01*
G02X1670770Y1494449I-1640J-983D01*
G02X1670498Y1493468I-1912J2D01*
G03X1670470Y1493365I172J-102D01*
G01Y1490415D01*
G03X1670498Y1490312I200J-1D01*
G02X1670770Y1489331I-1640J-983D01*
G02X1670498Y1488350I-1912J2D01*
G03X1670470Y1488247I172J-102D01*
G01Y1487121D01*
G02X1670268Y1486918I-202J-1D01*
G01X1667448D01*
G02X1667246Y1487121I1J203D01*
G01Y1488247D01*
G03X1667218Y1488350I-200J1D01*
G02X1666946Y1489331I1640J983D01*
G02X1667218Y1490312I1912J-2D01*
G03X1667246Y1490415I-172J102D01*
G01Y1493365D01*
G03X1667218Y1493468I-200J1D01*
G02X1666946Y1494449I1640J983D01*
G02X1667218Y1495430I1912J-2D01*
G03X1667246Y1495533I-172J102D01*
G01Y1496659D01*
G37*
G36*
G01X1684568D02*
G02X1684771Y1496862I203J0D01*
G01X1687591D01*
G02X1687794Y1496659I0J-203D01*
G01Y1495533D01*
G03X1687822Y1495430I200J-1D01*
G02Y1493468I-1642J-981D01*
G03X1687794Y1493365I172J-102D01*
G01Y1490415D01*
G03X1687822Y1490312I200J-1D01*
G02Y1488350I-1642J-981D01*
G03X1687794Y1488247I172J-102D01*
G01Y1487121D01*
G02X1687591Y1486918I-203J0D01*
G01X1684771D01*
G02X1684568Y1487121I0J203D01*
G01Y1488247D01*
G03X1684540Y1488350I-200J1D01*
G02Y1490312I1642J981D01*
G03X1684568Y1490415I-172J102D01*
G01Y1493365D01*
G03X1684540Y1493468I-200J1D01*
G02Y1495430I1642J981D01*
G03X1684568Y1495533I-172J102D01*
G01Y1496659D01*
G37*
G36*
G01X1701890D02*
G02X1702093Y1496862I203J0D01*
G01X1704913D01*
G02X1705116Y1496659I0J-203D01*
G01Y1495533D01*
G03X1705144Y1495430I200J-1D01*
G02Y1493468I-1642J-981D01*
G03X1705116Y1493365I172J-102D01*
G01Y1490415D01*
G03X1705144Y1490312I200J-1D01*
G02Y1488350I-1642J-981D01*
G03X1705116Y1488247I172J-102D01*
G01Y1487121D01*
G02X1704913Y1486918I-203J0D01*
G01X1702093D01*
G02X1701890Y1487121I0J203D01*
G01Y1488247D01*
G03X1701862Y1488350I-200J1D01*
G02Y1490312I1642J981D01*
G03X1701890Y1490415I-172J102D01*
G01Y1493365D01*
G03X1701862Y1493468I-200J1D01*
G02Y1495430I1642J981D01*
G03X1701890Y1495533I-172J102D01*
G01Y1496659D01*
G37*
G36*
G01X1658584Y1500989D02*
G02X1658786Y1501192I202J1D01*
G01X1661606D01*
G02X1661808Y1500989I-1J-203D01*
G01Y1499864D01*
G03X1661836Y1499761I200J-1D01*
G02X1662108Y1498780I-1640J-983D01*
G02X1661836Y1497799I-1912J2D01*
G03X1661808Y1497696I172J-102D01*
G01Y1494746D01*
G03X1661836Y1494643I200J-1D01*
G02X1662108Y1493662I-1640J-983D01*
G02X1661836Y1492681I-1912J2D01*
G03X1661808Y1492578I172J-102D01*
G01Y1491451D01*
G02X1661606Y1491248I-202J-1D01*
G01X1658786D01*
G02X1658584Y1491451I1J203D01*
G01Y1492578D01*
G03X1658556Y1492681I-200J1D01*
G02X1658284Y1493662I1640J983D01*
G02X1658556Y1494643I1912J-2D01*
G03X1658584Y1494746I-172J102D01*
G01Y1497696D01*
G03X1658556Y1497799I-200J1D01*
G02X1658284Y1498780I1640J983D01*
G02X1658556Y1499761I1912J-2D01*
G03X1658584Y1499864I-172J102D01*
G01Y1500989D01*
G37*
G36*
G01X1675906D02*
G02X1676109Y1501192I203J0D01*
G01X1678929D01*
G02X1679132Y1500989I0J-203D01*
G01Y1499864D01*
G03X1679160Y1499761I200J-1D01*
G02Y1497799I-1642J-981D01*
G03X1679132Y1497696I172J-102D01*
G01Y1494746D01*
G03X1679160Y1494643I200J-1D01*
G02Y1492681I-1642J-981D01*
G03X1679132Y1492578I172J-102D01*
G01Y1491451D01*
G02X1678929Y1491248I-203J0D01*
G01X1676109D01*
G02X1675906Y1491451I0J203D01*
G01Y1492578D01*
G03X1675878Y1492681I-200J1D01*
G02Y1494643I1642J981D01*
G03X1675906Y1494746I-172J102D01*
G01Y1497696D01*
G03X1675878Y1497799I-200J1D01*
G02Y1499761I1642J981D01*
G03X1675906Y1499864I-172J102D01*
G01Y1500989D01*
G37*
G36*
G01X1693230D02*
G02X1693432Y1501192I202J1D01*
G01X1696252D01*
G02X1696454Y1500989I-1J-203D01*
G01Y1499864D01*
G03X1696482Y1499761I200J-1D01*
G02X1696754Y1498780I-1640J-983D01*
G02X1696482Y1497799I-1912J2D01*
G03X1696454Y1497696I172J-102D01*
G01Y1494746D01*
G03X1696482Y1494643I200J-1D01*
G02X1696754Y1493662I-1640J-983D01*
G02X1696482Y1492681I-1912J2D01*
G03X1696454Y1492578I172J-102D01*
G01Y1491451D01*
G02X1696252Y1491248I-202J-1D01*
G01X1693432D01*
G02X1693230Y1491451I1J203D01*
G01Y1492578D01*
G03X1693202Y1492681I-200J1D01*
G02X1692930Y1493662I1640J983D01*
G02X1693202Y1494643I1912J-2D01*
G03X1693230Y1494746I-172J102D01*
G01Y1497696D01*
G03X1693202Y1497799I-200J1D01*
G02X1692930Y1498780I1640J983D01*
G02X1693202Y1499761I1912J-2D01*
G03X1693230Y1499864I-172J102D01*
G01Y1500989D01*
G37*
G36*
G01X1710552D02*
G02X1710755Y1501192I203J0D01*
G01X1713575D01*
G02X1713778Y1500989I0J-203D01*
G01Y1499864D01*
G03X1713806Y1499761I200J-1D01*
G02Y1497799I-1642J-981D01*
G03X1713778Y1497696I172J-102D01*
G01Y1494746D01*
G03X1713806Y1494643I200J-1D01*
G02Y1492681I-1642J-981D01*
G03X1713778Y1492578I172J-102D01*
G01Y1491451D01*
G02X1713575Y1491248I-203J0D01*
G01X1710755D01*
G02X1710552Y1491451I0J203D01*
G01Y1492578D01*
G03X1710524Y1492681I-200J1D01*
G02Y1494643I1642J981D01*
G03X1710552Y1494746I-172J102D01*
G01Y1497696D01*
G03X1710524Y1497799I-200J1D01*
G02Y1499761I1642J981D01*
G03X1710552Y1499864I-172J102D01*
G01Y1500989D01*
G37*
G36*
G01X1667246Y1512014D02*
G02X1667448Y1512216I202J0D01*
G01X1670268D01*
G02X1670470Y1512014I0J-202D01*
G01Y1510888D01*
G03X1670498Y1510785I200J-1D01*
G02X1670770Y1509804I-1640J-983D01*
G02X1670498Y1508823I-1912J2D01*
G03X1670470Y1508720I172J-102D01*
G01Y1505769D01*
G03X1670498Y1505666I200J-1D01*
G02X1670770Y1504685I-1640J-983D01*
G02X1670498Y1503704I-1912J2D01*
G03X1670470Y1503601I172J-102D01*
G01Y1502476D01*
G02X1670268Y1502274I-202J0D01*
G01X1667448D01*
G02X1667246Y1502476I0J202D01*
G01Y1503601D01*
G03X1667218Y1503704I-200J1D01*
G02X1666946Y1504685I1640J983D01*
G02X1667218Y1505666I1912J-2D01*
G03X1667246Y1505769I-172J102D01*
G01Y1508720D01*
G03X1667218Y1508823I-200J1D01*
G02X1666946Y1509804I1640J983D01*
G02X1667218Y1510785I1912J-2D01*
G03X1667246Y1510888I-172J102D01*
G01Y1512014D01*
G37*
G36*
G01X1684771Y1512216D02*
X1687591D01*
G02X1687794Y1512014I1J-202D01*
G01Y1510888D01*
G03X1687822Y1510785I200J-1D01*
G02Y1508823I-1642J-981D01*
G03X1687794Y1508720I172J-102D01*
G01Y1505769D01*
G03X1687822Y1505666I200J-1D01*
G02Y1503704I-1642J-981D01*
G03X1687794Y1503601I172J-102D01*
G01Y1502476D01*
G02X1687591Y1502274I-203J1D01*
G01X1684771D01*
G02X1684568Y1502476I-1J202D01*
G01Y1503601D01*
G03X1684540Y1503704I-200J1D01*
G02Y1505666I1642J981D01*
G03X1684568Y1505769I-172J102D01*
G01Y1508720D01*
G03X1684540Y1508823I-200J1D01*
G02Y1510785I1642J981D01*
G03X1684568Y1510888I-172J102D01*
G01Y1512014D01*
G02X1684771Y1512216I203J-1D01*
G37*
G36*
G01X1702093D02*
X1704913D01*
G02X1705116Y1512014I1J-202D01*
G01Y1510888D01*
G03X1705144Y1510785I200J-1D01*
G02Y1508823I-1642J-981D01*
G03X1705116Y1508720I172J-102D01*
G01Y1505769D01*
G03X1705144Y1505666I200J-1D01*
G02Y1503704I-1642J-981D01*
G03X1705116Y1503601I172J-102D01*
G01Y1502476D01*
G02X1704913Y1502274I-203J1D01*
G01X1702093D01*
G02X1701890Y1502476I-1J202D01*
G01Y1503601D01*
G03X1701862Y1503704I-200J1D01*
G02Y1505666I1642J981D01*
G03X1701890Y1505769I-172J102D01*
G01Y1508720D01*
G03X1701862Y1508823I-200J1D01*
G02Y1510785I1642J981D01*
G03X1701890Y1510888I-172J102D01*
G01Y1512014D01*
G02X1702093Y1512216I203J-1D01*
G37*
G36*
G01X1658584Y1516344D02*
G02X1658786Y1516546I202J0D01*
G01X1661606D01*
G02X1661808Y1516344I0J-202D01*
G01Y1515218D01*
G03X1661836Y1515115I200J-1D01*
G02X1662108Y1514134I-1640J-983D01*
G02X1661836Y1513153I-1912J2D01*
G03X1661808Y1513050I172J-102D01*
G01Y1510100D01*
G03X1661836Y1509997I200J-1D01*
G02X1662108Y1509016I-1640J-983D01*
G02X1661836Y1508035I-1912J2D01*
G03X1661808Y1507932I172J-102D01*
G01Y1506806D01*
G02X1661606Y1506604I-202J0D01*
G01X1658786D01*
G02X1658584Y1506806I0J202D01*
G01Y1507932D01*
G03X1658556Y1508035I-200J1D01*
G02X1658284Y1509016I1640J983D01*
G02X1658556Y1509997I1912J-2D01*
G03X1658584Y1510100I-172J102D01*
G01Y1513050D01*
G03X1658556Y1513153I-200J1D01*
G02X1658284Y1514134I1640J983D01*
G02X1658556Y1515115I1912J-2D01*
G03X1658584Y1515218I-172J102D01*
G01Y1516344D01*
G37*
G36*
G01X1693230D02*
G02X1693432Y1516546I202J0D01*
G01X1696252D01*
G02X1696454Y1516344I0J-202D01*
G01Y1515218D01*
G03X1696482Y1515115I200J-1D01*
G02X1696754Y1514134I-1640J-983D01*
G02X1696482Y1513153I-1912J2D01*
G03X1696454Y1513050I172J-102D01*
G01Y1510100D01*
G03X1696482Y1509997I200J-1D01*
G02X1696754Y1509016I-1640J-983D01*
G02X1696482Y1508035I-1912J2D01*
G03X1696454Y1507932I172J-102D01*
G01Y1506806D01*
G02X1696252Y1506604I-202J0D01*
G01X1693432D01*
G02X1693230Y1506806I0J202D01*
G01Y1507932D01*
G03X1693202Y1508035I-200J1D01*
G02X1692930Y1509016I1640J983D01*
G02X1693202Y1509997I1912J-2D01*
G03X1693230Y1510100I-172J102D01*
G01Y1513050D01*
G03X1693202Y1513153I-200J1D01*
G02X1692930Y1514134I1640J983D01*
G02X1693202Y1515115I1912J-2D01*
G03X1693230Y1515218I-172J102D01*
G01Y1516344D01*
G37*
G36*
G01X1676109Y1516546D02*
X1678929D01*
G02X1679132Y1516344I1J-202D01*
G01Y1515218D01*
G03X1679160Y1515115I200J-1D01*
G02Y1513153I-1642J-981D01*
G03X1679132Y1513050I172J-102D01*
G01Y1510100D01*
G03X1679160Y1509997I200J-1D01*
G02Y1508035I-1642J-981D01*
G03X1679132Y1507932I172J-102D01*
G01Y1506806D01*
G02X1678929Y1506604I-203J1D01*
G01X1676109D01*
G02X1675906Y1506806I-1J202D01*
G01Y1507932D01*
G03X1675878Y1508035I-200J1D01*
G02Y1509997I1642J981D01*
G03X1675906Y1510100I-172J102D01*
G01Y1513050D01*
G03X1675878Y1513153I-200J1D01*
G02Y1515115I1642J981D01*
G03X1675906Y1515218I-172J102D01*
G01Y1516344D01*
G02X1676109Y1516546I203J-1D01*
G37*
G36*
G01X1710755D02*
X1713575D01*
G02X1713778Y1516344I1J-202D01*
G01Y1515218D01*
G03X1713806Y1515115I200J-1D01*
G02Y1513153I-1642J-981D01*
G03X1713778Y1513050I172J-102D01*
G01Y1510100D01*
G03X1713806Y1509997I200J-1D01*
G02Y1508035I-1642J-981D01*
G03X1713778Y1507932I172J-102D01*
G01Y1506806D01*
G02X1713575Y1506604I-203J1D01*
G01X1710755D01*
G02X1710552Y1506806I-1J202D01*
G01Y1507932D01*
G03X1710524Y1508035I-200J1D01*
G02Y1509997I1642J981D01*
G03X1710552Y1510100I-172J102D01*
G01Y1513050D01*
G03X1710524Y1513153I-200J1D01*
G02Y1515115I1642J981D01*
G03X1710552Y1515218I-172J102D01*
G01Y1516344D01*
G02X1710755Y1516546I203J-1D01*
G37*
G36*
G01X1649922Y1583667D02*
G02X1650125Y1583870I203J0D01*
G01X1652945D01*
G02X1653148Y1583667I0J-203D01*
G01Y1582541D01*
G03X1653176Y1582438I200J-1D01*
G02Y1580476I-1642J-981D01*
G03X1653148Y1580373I172J-102D01*
G01Y1577423D01*
G03X1653176Y1577320I200J-1D01*
G02Y1575358I-1642J-981D01*
G03X1653148Y1575255I172J-102D01*
G01Y1574129D01*
G02X1652945Y1573926I-203J0D01*
G01X1650125D01*
G02X1649922Y1574129I0J203D01*
G01Y1575255D01*
G03X1649894Y1575358I-200J1D01*
G02Y1577320I1642J981D01*
G03X1649922Y1577423I-172J102D01*
G01Y1580373D01*
G03X1649894Y1580476I-200J1D01*
G02Y1582438I1642J981D01*
G03X1649922Y1582541I-172J102D01*
G01Y1583667D01*
G37*
G36*
G01X1667246D02*
G02X1667448Y1583870I202J1D01*
G01X1670268D01*
G02X1670470Y1583667I-1J-203D01*
G01Y1582541D01*
G03X1670498Y1582438I200J-1D01*
G02X1670770Y1581457I-1640J-983D01*
G02X1670498Y1580476I-1912J2D01*
G03X1670470Y1580373I172J-102D01*
G01Y1577423D01*
G03X1670498Y1577320I200J-1D01*
G02X1670770Y1576339I-1640J-983D01*
G02X1670498Y1575358I-1912J2D01*
G03X1670470Y1575255I172J-102D01*
G01Y1574129D01*
G02X1670268Y1573926I-202J-1D01*
G01X1667448D01*
G02X1667246Y1574129I1J203D01*
G01Y1575255D01*
G03X1667218Y1575358I-200J1D01*
G02X1666946Y1576339I1640J983D01*
G02X1667218Y1577320I1912J-2D01*
G03X1667246Y1577423I-172J102D01*
G01Y1580373D01*
G03X1667218Y1580476I-200J1D01*
G02X1666946Y1581457I1640J983D01*
G02X1667218Y1582438I1912J-2D01*
G03X1667246Y1582541I-172J102D01*
G01Y1583667D01*
G37*
G36*
G01X1684568D02*
G02X1684771Y1583870I203J0D01*
G01X1687591D01*
G02X1687794Y1583667I0J-203D01*
G01Y1582541D01*
G03X1687822Y1582438I200J-1D01*
G02Y1580476I-1642J-981D01*
G03X1687794Y1580373I172J-102D01*
G01Y1577423D01*
G03X1687822Y1577320I200J-1D01*
G02Y1575358I-1642J-981D01*
G03X1687794Y1575255I172J-102D01*
G01Y1574129D01*
G02X1687591Y1573926I-203J0D01*
G01X1684771D01*
G02X1684568Y1574129I0J203D01*
G01Y1575255D01*
G03X1684540Y1575358I-200J1D01*
G02Y1577320I1642J981D01*
G03X1684568Y1577423I-172J102D01*
G01Y1580373D01*
G03X1684540Y1580476I-200J1D01*
G02Y1582438I1642J981D01*
G03X1684568Y1582541I-172J102D01*
G01Y1583667D01*
G37*
G36*
G01X1701890D02*
G02X1702093Y1583870I203J0D01*
G01X1704913D01*
G02X1705116Y1583667I0J-203D01*
G01Y1582541D01*
G03X1705144Y1582438I200J-1D01*
G02Y1580476I-1642J-981D01*
G03X1705116Y1580373I172J-102D01*
G01Y1577423D01*
G03X1705144Y1577320I200J-1D01*
G02Y1575358I-1642J-981D01*
G03X1705116Y1575255I172J-102D01*
G01Y1574129D01*
G02X1704913Y1573926I-203J0D01*
G01X1702093D01*
G02X1701890Y1574129I0J203D01*
G01Y1575255D01*
G03X1701862Y1575358I-200J1D01*
G02Y1577320I1642J981D01*
G03X1701890Y1577423I-172J102D01*
G01Y1580373D01*
G03X1701862Y1580476I-200J1D01*
G02Y1582438I1642J981D01*
G03X1701890Y1582541I-172J102D01*
G01Y1583667D01*
G37*
G36*
G01X1658584Y1587998D02*
G02X1658786Y1588200I202J0D01*
G01X1661606D01*
G02X1661808Y1587998I0J-202D01*
G01Y1586872D01*
G03X1661836Y1586769I200J-1D01*
G02X1662108Y1585788I-1640J-983D01*
G02X1661836Y1584807I-1912J2D01*
G03X1661808Y1584704I172J-102D01*
G01Y1581754D01*
G03X1661836Y1581651I200J-1D01*
G02X1662108Y1580670I-1640J-983D01*
G02X1661836Y1579689I-1912J2D01*
G03X1661808Y1579586I172J-102D01*
G01Y1578460D01*
G02X1661606Y1578258I-202J0D01*
G01X1658786D01*
G02X1658584Y1578460I0J202D01*
G01Y1579586D01*
G03X1658556Y1579689I-200J1D01*
G02X1658284Y1580670I1640J983D01*
G02X1658556Y1581651I1912J-2D01*
G03X1658584Y1581754I-172J102D01*
G01Y1584704D01*
G03X1658556Y1584807I-200J1D01*
G02X1658284Y1585788I1640J983D01*
G02X1658556Y1586769I1912J-2D01*
G03X1658584Y1586872I-172J102D01*
G01Y1587998D01*
G37*
G36*
G01X1693230D02*
G02X1693432Y1588200I202J0D01*
G01X1696252D01*
G02X1696454Y1587998I0J-202D01*
G01Y1586872D01*
G03X1696482Y1586769I200J-1D01*
G02X1696754Y1585788I-1640J-983D01*
G02X1696482Y1584807I-1912J2D01*
G03X1696454Y1584704I172J-102D01*
G01Y1581754D01*
G03X1696482Y1581651I200J-1D01*
G02X1696754Y1580670I-1640J-983D01*
G02X1696482Y1579689I-1912J2D01*
G03X1696454Y1579586I172J-102D01*
G01Y1578460D01*
G02X1696252Y1578258I-202J0D01*
G01X1693432D01*
G02X1693230Y1578460I0J202D01*
G01Y1579586D01*
G03X1693202Y1579689I-200J1D01*
G02X1692930Y1580670I1640J983D01*
G02X1693202Y1581651I1912J-2D01*
G03X1693230Y1581754I-172J102D01*
G01Y1584704D01*
G03X1693202Y1584807I-200J1D01*
G02X1692930Y1585788I1640J983D01*
G02X1693202Y1586769I1912J-2D01*
G03X1693230Y1586872I-172J102D01*
G01Y1587998D01*
G37*
G36*
G01X1676109Y1588200D02*
X1678929D01*
G02X1679132Y1587998I1J-202D01*
G01Y1586872D01*
G03X1679160Y1586769I200J-1D01*
G02Y1584807I-1642J-981D01*
G03X1679132Y1584704I172J-102D01*
G01Y1581754D01*
G03X1679160Y1581651I200J-1D01*
G02Y1579689I-1642J-981D01*
G03X1679132Y1579586I172J-102D01*
G01Y1578460D01*
G02X1678929Y1578258I-203J1D01*
G01X1676109D01*
G02X1675906Y1578460I-1J202D01*
G01Y1579586D01*
G03X1675878Y1579689I-200J1D01*
G02Y1581651I1642J981D01*
G03X1675906Y1581754I-172J102D01*
G01Y1584704D01*
G03X1675878Y1584807I-200J1D01*
G02Y1586769I1642J981D01*
G03X1675906Y1586872I-172J102D01*
G01Y1587998D01*
G02X1676109Y1588200I203J-1D01*
G37*
G36*
G01X1710755D02*
X1713575D01*
G02X1713778Y1587998I1J-202D01*
G01Y1586872D01*
G03X1713806Y1586769I200J-1D01*
G02Y1584807I-1642J-981D01*
G03X1713778Y1584704I172J-102D01*
G01Y1581754D01*
G03X1713806Y1581651I200J-1D01*
G02Y1579689I-1642J-981D01*
G03X1713778Y1579586I172J-102D01*
G01Y1578460D01*
G02X1713575Y1578258I-203J1D01*
G01X1710755D01*
G02X1710552Y1578460I-1J202D01*
G01Y1579586D01*
G03X1710524Y1579689I-200J1D01*
G02Y1581651I1642J981D01*
G03X1710552Y1581754I-172J102D01*
G01Y1584704D01*
G03X1710524Y1584807I-200J1D01*
G02Y1586769I1642J981D01*
G03X1710552Y1586872I-172J102D01*
G01Y1587998D01*
G02X1710755Y1588200I203J-1D01*
G37*
G36*
G01X1649922Y1599021D02*
G02X1650125Y1599224I203J0D01*
G01X1652945D01*
G02X1653148Y1599021I0J-203D01*
G01Y1597895D01*
G03X1653176Y1597792I200J-1D01*
G02Y1595830I-1642J-981D01*
G03X1653148Y1595727I172J-102D01*
G01Y1592777D01*
G03X1653176Y1592674I200J-1D01*
G02Y1590712I-1642J-981D01*
G03X1653148Y1590609I172J-102D01*
G01Y1589483D01*
G02X1652945Y1589280I-203J0D01*
G01X1650125D01*
G02X1649922Y1589483I0J203D01*
G01Y1590609D01*
G03X1649894Y1590712I-200J1D01*
G02Y1592674I1642J981D01*
G03X1649922Y1592777I-172J102D01*
G01Y1595727D01*
G03X1649894Y1595830I-200J1D01*
G02Y1597792I1642J981D01*
G03X1649922Y1597895I-172J102D01*
G01Y1599021D01*
G37*
G36*
G01X1667246D02*
G02X1667448Y1599224I202J1D01*
G01X1670268D01*
G02X1670470Y1599021I-1J-203D01*
G01Y1597895D01*
G03X1670498Y1597792I200J-1D01*
G02X1670770Y1596811I-1640J-983D01*
G02X1670498Y1595830I-1912J2D01*
G03X1670470Y1595727I172J-102D01*
G01Y1592777D01*
G03X1670498Y1592674I200J-1D01*
G02X1670770Y1591693I-1640J-983D01*
G02X1670498Y1590712I-1912J2D01*
G03X1670470Y1590609I172J-102D01*
G01Y1589483D01*
G02X1670268Y1589280I-202J-1D01*
G01X1667448D01*
G02X1667246Y1589483I1J203D01*
G01Y1590609D01*
G03X1667218Y1590712I-200J1D01*
G02X1666946Y1591693I1640J983D01*
G02X1667218Y1592674I1912J-2D01*
G03X1667246Y1592777I-172J102D01*
G01Y1595727D01*
G03X1667218Y1595830I-200J1D01*
G02X1666946Y1596811I1640J983D01*
G02X1667218Y1597792I1912J-2D01*
G03X1667246Y1597895I-172J102D01*
G01Y1599021D01*
G37*
G36*
G01X1684568D02*
G02X1684771Y1599224I203J0D01*
G01X1687591D01*
G02X1687794Y1599021I0J-203D01*
G01Y1597895D01*
G03X1687822Y1597792I200J-1D01*
G02Y1595830I-1642J-981D01*
G03X1687794Y1595727I172J-102D01*
G01Y1592777D01*
G03X1687822Y1592674I200J-1D01*
G02Y1590712I-1642J-981D01*
G03X1687794Y1590609I172J-102D01*
G01Y1589483D01*
G02X1687591Y1589280I-203J0D01*
G01X1684771D01*
G02X1684568Y1589483I0J203D01*
G01Y1590609D01*
G03X1684540Y1590712I-200J1D01*
G02Y1592674I1642J981D01*
G03X1684568Y1592777I-172J102D01*
G01Y1595727D01*
G03X1684540Y1595830I-200J1D01*
G02Y1597792I1642J981D01*
G03X1684568Y1597895I-172J102D01*
G01Y1599021D01*
G37*
G36*
G01X1701890D02*
G02X1702093Y1599224I203J0D01*
G01X1704913D01*
G02X1705116Y1599021I0J-203D01*
G01Y1597895D01*
G03X1705144Y1597792I200J-1D01*
G02Y1595830I-1642J-981D01*
G03X1705116Y1595727I172J-102D01*
G01Y1592777D01*
G03X1705144Y1592674I200J-1D01*
G02Y1590712I-1642J-981D01*
G03X1705116Y1590609I172J-102D01*
G01Y1589483D01*
G02X1704913Y1589280I-203J0D01*
G01X1702093D01*
G02X1701890Y1589483I0J203D01*
G01Y1590609D01*
G03X1701862Y1590712I-200J1D01*
G02Y1592674I1642J981D01*
G03X1701890Y1592777I-172J102D01*
G01Y1595727D01*
G03X1701862Y1595830I-200J1D01*
G02Y1597792I1642J981D01*
G03X1701890Y1597895I-172J102D01*
G01Y1599021D01*
G37*
G36*
G01X1658584Y1603352D02*
G02X1658786Y1603554I202J0D01*
G01X1661606D01*
G02X1661808Y1603352I0J-202D01*
G01Y1602226D01*
G03X1661836Y1602123I200J-1D01*
G02X1662108Y1601142I-1640J-983D01*
G02X1661836Y1600161I-1912J2D01*
G03X1661808Y1600058I172J-102D01*
G01Y1597108D01*
G03X1661836Y1597005I200J-1D01*
G02X1662108Y1596024I-1640J-983D01*
G02X1661836Y1595043I-1912J2D01*
G03X1661808Y1594940I172J-102D01*
G01Y1593814D01*
G02X1661606Y1593612I-202J0D01*
G01X1658786D01*
G02X1658584Y1593814I0J202D01*
G01Y1594940D01*
G03X1658556Y1595043I-200J1D01*
G02X1658284Y1596024I1640J983D01*
G02X1658556Y1597005I1912J-2D01*
G03X1658584Y1597108I-172J102D01*
G01Y1600058D01*
G03X1658556Y1600161I-200J1D01*
G02X1658284Y1601142I1640J983D01*
G02X1658556Y1602123I1912J-2D01*
G03X1658584Y1602226I-172J102D01*
G01Y1603352D01*
G37*
G36*
G01X1693230D02*
G02X1693432Y1603554I202J0D01*
G01X1696252D01*
G02X1696454Y1603352I0J-202D01*
G01Y1602226D01*
G03X1696482Y1602123I200J-1D01*
G02X1696754Y1601142I-1640J-983D01*
G02X1696482Y1600161I-1912J2D01*
G03X1696454Y1600058I172J-102D01*
G01Y1597108D01*
G03X1696482Y1597005I200J-1D01*
G02X1696754Y1596024I-1640J-983D01*
G02X1696482Y1595043I-1912J2D01*
G03X1696454Y1594940I172J-102D01*
G01Y1593814D01*
G02X1696252Y1593612I-202J0D01*
G01X1693432D01*
G02X1693230Y1593814I0J202D01*
G01Y1594940D01*
G03X1693202Y1595043I-200J1D01*
G02X1692930Y1596024I1640J983D01*
G02X1693202Y1597005I1912J-2D01*
G03X1693230Y1597108I-172J102D01*
G01Y1600058D01*
G03X1693202Y1600161I-200J1D01*
G02X1692930Y1601142I1640J983D01*
G02X1693202Y1602123I1912J-2D01*
G03X1693230Y1602226I-172J102D01*
G01Y1603352D01*
G37*
G36*
G01X1676109Y1603554D02*
X1678929D01*
G02X1679132Y1603352I1J-202D01*
G01Y1602226D01*
G03X1679160Y1602123I200J-1D01*
G02Y1600161I-1642J-981D01*
G03X1679132Y1600058I172J-102D01*
G01Y1597108D01*
G03X1679160Y1597005I200J-1D01*
G02Y1595043I-1642J-981D01*
G03X1679132Y1594940I172J-102D01*
G01Y1593814D01*
G02X1678929Y1593612I-203J1D01*
G01X1676109D01*
G02X1675906Y1593814I-1J202D01*
G01Y1594940D01*
G03X1675878Y1595043I-200J1D01*
G02Y1597005I1642J981D01*
G03X1675906Y1597108I-172J102D01*
G01Y1600058D01*
G03X1675878Y1600161I-200J1D01*
G02Y1602123I1642J981D01*
G03X1675906Y1602226I-172J102D01*
G01Y1603352D01*
G02X1676109Y1603554I203J-1D01*
G37*
G36*
G01X1710755D02*
X1713575D01*
G02X1713778Y1603352I1J-202D01*
G01Y1602226D01*
G03X1713806Y1602123I200J-1D01*
G02Y1600161I-1642J-981D01*
G03X1713778Y1600058I172J-102D01*
G01Y1597108D01*
G03X1713806Y1597005I200J-1D01*
G02Y1595043I-1642J-981D01*
G03X1713778Y1594940I172J-102D01*
G01Y1593814D01*
G02X1713575Y1593612I-203J1D01*
G01X1710755D01*
G02X1710552Y1593814I-1J202D01*
G01Y1594940D01*
G03X1710524Y1595043I-200J1D01*
G02Y1597005I1642J981D01*
G03X1710552Y1597108I-172J102D01*
G01Y1600058D01*
G03X1710524Y1600161I-200J1D01*
G02Y1602123I1642J981D01*
G03X1710552Y1602226I-172J102D01*
G01Y1603352D01*
G02X1710755Y1603554I203J-1D01*
G37*
G36*
G01X1320790Y1614376D02*
G02X1320992Y1614578I202J0D01*
G01X1323812D01*
G02X1324014Y1614376I0J-202D01*
G01Y1613250D01*
G03X1324042Y1613147I200J-1D01*
G02X1324314Y1612166I-1640J-983D01*
G02X1324042Y1611185I-1912J2D01*
G03X1324014Y1611082I172J-102D01*
G01Y1608132D01*
G03X1324042Y1608029I200J-1D01*
G02X1324314Y1607048I-1640J-983D01*
G02X1324042Y1606067I-1912J2D01*
G03X1324014Y1605964I172J-102D01*
G01Y1604838D01*
G02X1323812Y1604636I-202J0D01*
G01X1320992D01*
G02X1320790Y1604838I0J202D01*
G01Y1605964D01*
G03X1320762Y1606067I-200J1D01*
G02X1320490Y1607048I1640J983D01*
G02X1320762Y1608029I1912J-2D01*
G03X1320790Y1608132I-172J102D01*
G01Y1611082D01*
G03X1320762Y1611185I-200J1D01*
G02X1320490Y1612166I1640J983D01*
G02X1320762Y1613147I1912J-2D01*
G03X1320790Y1613250I-172J102D01*
G01Y1614376D01*
G37*
G36*
G01X1494018D02*
G02X1494220Y1614578I202J0D01*
G01X1497040D01*
G02X1497242Y1614376I0J-202D01*
G01Y1613250D01*
G03X1497270Y1613147I200J-1D01*
G02X1497542Y1612166I-1640J-983D01*
G02X1497270Y1611185I-1912J2D01*
G03X1497242Y1611082I172J-102D01*
G01Y1608132D01*
G03X1497270Y1608029I200J-1D01*
G02X1497542Y1607048I-1640J-983D01*
G02X1497270Y1606067I-1912J2D01*
G03X1497242Y1605964I172J-102D01*
G01Y1604838D01*
G02X1497040Y1604636I-202J0D01*
G01X1494220D01*
G02X1494018Y1604838I0J202D01*
G01Y1605964D01*
G03X1493990Y1606067I-200J1D01*
G02X1493718Y1607048I1640J983D01*
G02X1493990Y1608029I1912J-2D01*
G03X1494018Y1608132I-172J102D01*
G01Y1611082D01*
G03X1493990Y1611185I-200J1D01*
G02X1493718Y1612166I1640J983D01*
G02X1493990Y1613147I1912J-2D01*
G03X1494018Y1613250I-172J102D01*
G01Y1614376D01*
G37*
G36*
G01X1667246D02*
G02X1667448Y1614578I202J0D01*
G01X1670268D01*
G02X1670470Y1614376I0J-202D01*
G01Y1613250D01*
G03X1670498Y1613147I200J-1D01*
G02X1670770Y1612166I-1640J-983D01*
G02X1670498Y1611185I-1912J2D01*
G03X1670470Y1611082I172J-102D01*
G01Y1608132D01*
G03X1670498Y1608029I200J-1D01*
G02X1670770Y1607048I-1640J-983D01*
G02X1670498Y1606067I-1912J2D01*
G03X1670470Y1605964I172J-102D01*
G01Y1604838D01*
G02X1670268Y1604636I-202J0D01*
G01X1667448D01*
G02X1667246Y1604838I0J202D01*
G01Y1605964D01*
G03X1667218Y1606067I-200J1D01*
G02X1666946Y1607048I1640J983D01*
G02X1667218Y1608029I1912J-2D01*
G03X1667246Y1608132I-172J102D01*
G01Y1611082D01*
G03X1667218Y1611185I-200J1D01*
G02X1666946Y1612166I1640J983D01*
G02X1667218Y1613147I1912J-2D01*
G03X1667246Y1613250I-172J102D01*
G01Y1614376D01*
G37*
G36*
G01X1303669Y1614578D02*
X1306489D01*
G02X1306692Y1614376I1J-202D01*
G01Y1613250D01*
G03X1306720Y1613147I200J-1D01*
G02Y1611185I-1642J-981D01*
G03X1306692Y1611082I172J-102D01*
G01Y1608132D01*
G03X1306720Y1608029I200J-1D01*
G02Y1606067I-1642J-981D01*
G03X1306692Y1605964I172J-102D01*
G01Y1604838D01*
G02X1306489Y1604636I-203J1D01*
G01X1303669D01*
G02X1303466Y1604838I-1J202D01*
G01Y1605964D01*
G03X1303438Y1606067I-200J1D01*
G02Y1608029I1642J981D01*
G03X1303466Y1608132I-172J102D01*
G01Y1611082D01*
G03X1303438Y1611185I-200J1D01*
G02Y1613147I1642J981D01*
G03X1303466Y1613250I-172J102D01*
G01Y1614376D01*
G02X1303669Y1614578I203J-1D01*
G37*
G36*
G01X1338315D02*
X1341135D01*
G02X1341338Y1614376I1J-202D01*
G01Y1613250D01*
G03X1341366Y1613147I200J-1D01*
G02Y1611185I-1642J-981D01*
G03X1341338Y1611082I172J-102D01*
G01Y1608132D01*
G03X1341366Y1608029I200J-1D01*
G02Y1606067I-1642J-981D01*
G03X1341338Y1605964I172J-102D01*
G01Y1604838D01*
G02X1341135Y1604636I-203J1D01*
G01X1338315D01*
G02X1338112Y1604838I-1J202D01*
G01Y1605964D01*
G03X1338084Y1606067I-200J1D01*
G02Y1608029I1642J981D01*
G03X1338112Y1608132I-172J102D01*
G01Y1611082D01*
G03X1338084Y1611185I-200J1D01*
G02Y1613147I1642J981D01*
G03X1338112Y1613250I-172J102D01*
G01Y1614376D01*
G02X1338315Y1614578I203J-1D01*
G37*
G36*
G01X1355637D02*
X1358457D01*
G02X1358660Y1614376I1J-202D01*
G01Y1613250D01*
G03X1358688Y1613147I200J-1D01*
G02Y1611185I-1642J-981D01*
G03X1358660Y1611082I172J-102D01*
G01Y1608132D01*
G03X1358688Y1608029I200J-1D01*
G02Y1606067I-1642J-981D01*
G03X1358660Y1605964I172J-102D01*
G01Y1604838D01*
G02X1358457Y1604636I-203J1D01*
G01X1355637D01*
G02X1355434Y1604838I-1J202D01*
G01Y1605964D01*
G03X1355406Y1606067I-200J1D01*
G02Y1608029I1642J981D01*
G03X1355434Y1608132I-172J102D01*
G01Y1611082D01*
G03X1355406Y1611185I-200J1D01*
G02Y1613147I1642J981D01*
G03X1355434Y1613250I-172J102D01*
G01Y1614376D01*
G02X1355637Y1614578I203J-1D01*
G37*
G36*
G01X1476897D02*
X1479717D01*
G02X1479920Y1614376I1J-202D01*
G01Y1613250D01*
G03X1479948Y1613147I200J-1D01*
G02Y1611185I-1642J-981D01*
G03X1479920Y1611082I172J-102D01*
G01Y1608132D01*
G03X1479948Y1608029I200J-1D01*
G02Y1606067I-1642J-981D01*
G03X1479920Y1605964I172J-102D01*
G01Y1604838D01*
G02X1479717Y1604636I-203J1D01*
G01X1476897D01*
G02X1476694Y1604838I-1J202D01*
G01Y1605964D01*
G03X1476666Y1606067I-200J1D01*
G02Y1608029I1642J981D01*
G03X1476694Y1608132I-172J102D01*
G01Y1611082D01*
G03X1476666Y1611185I-200J1D01*
G02Y1613147I1642J981D01*
G03X1476694Y1613250I-172J102D01*
G01Y1614376D01*
G02X1476897Y1614578I203J-1D01*
G37*
G36*
G01X1511543D02*
X1514363D01*
G02X1514566Y1614376I1J-202D01*
G01Y1613250D01*
G03X1514594Y1613147I200J-1D01*
G02Y1611185I-1642J-981D01*
G03X1514566Y1611082I172J-102D01*
G01Y1608132D01*
G03X1514594Y1608029I200J-1D01*
G02Y1606067I-1642J-981D01*
G03X1514566Y1605964I172J-102D01*
G01Y1604838D01*
G02X1514363Y1604636I-203J1D01*
G01X1511543D01*
G02X1511340Y1604838I-1J202D01*
G01Y1605964D01*
G03X1511312Y1606067I-200J1D01*
G02Y1608029I1642J981D01*
G03X1511340Y1608132I-172J102D01*
G01Y1611082D01*
G03X1511312Y1611185I-200J1D01*
G02Y1613147I1642J981D01*
G03X1511340Y1613250I-172J102D01*
G01Y1614376D01*
G02X1511543Y1614578I203J-1D01*
G37*
G36*
G01X1528865D02*
X1531685D01*
G02X1531888Y1614376I1J-202D01*
G01Y1613250D01*
G03X1531916Y1613147I200J-1D01*
G02Y1611185I-1642J-981D01*
G03X1531888Y1611082I172J-102D01*
G01Y1608132D01*
G03X1531916Y1608029I200J-1D01*
G02Y1606067I-1642J-981D01*
G03X1531888Y1605964I172J-102D01*
G01Y1604838D01*
G02X1531685Y1604636I-203J1D01*
G01X1528865D01*
G02X1528662Y1604838I-1J202D01*
G01Y1605964D01*
G03X1528634Y1606067I-200J1D01*
G02Y1608029I1642J981D01*
G03X1528662Y1608132I-172J102D01*
G01Y1611082D01*
G03X1528634Y1611185I-200J1D01*
G02Y1613147I1642J981D01*
G03X1528662Y1613250I-172J102D01*
G01Y1614376D01*
G02X1528865Y1614578I203J-1D01*
G37*
G36*
G01X1650125D02*
X1652945D01*
G02X1653148Y1614376I1J-202D01*
G01Y1613250D01*
G03X1653176Y1613147I200J-1D01*
G02Y1611185I-1642J-981D01*
G03X1653148Y1611082I172J-102D01*
G01Y1608132D01*
G03X1653176Y1608029I200J-1D01*
G02Y1606067I-1642J-981D01*
G03X1653148Y1605964I172J-102D01*
G01Y1604838D01*
G02X1652945Y1604636I-203J1D01*
G01X1650125D01*
G02X1649922Y1604838I-1J202D01*
G01Y1605964D01*
G03X1649894Y1606067I-200J1D01*
G02Y1608029I1642J981D01*
G03X1649922Y1608132I-172J102D01*
G01Y1611082D01*
G03X1649894Y1611185I-200J1D01*
G02Y1613147I1642J981D01*
G03X1649922Y1613250I-172J102D01*
G01Y1614376D01*
G02X1650125Y1614578I203J-1D01*
G37*
G36*
G01X1684771D02*
X1687591D01*
G02X1687794Y1614376I1J-202D01*
G01Y1613250D01*
G03X1687822Y1613147I200J-1D01*
G02Y1611185I-1642J-981D01*
G03X1687794Y1611082I172J-102D01*
G01Y1608132D01*
G03X1687822Y1608029I200J-1D01*
G02Y1606067I-1642J-981D01*
G03X1687794Y1605964I172J-102D01*
G01Y1604838D01*
G02X1687591Y1604636I-203J1D01*
G01X1684771D01*
G02X1684568Y1604838I-1J202D01*
G01Y1605964D01*
G03X1684540Y1606067I-200J1D01*
G02Y1608029I1642J981D01*
G03X1684568Y1608132I-172J102D01*
G01Y1611082D01*
G03X1684540Y1611185I-200J1D01*
G02Y1613147I1642J981D01*
G03X1684568Y1613250I-172J102D01*
G01Y1614376D01*
G02X1684771Y1614578I203J-1D01*
G37*
G36*
G01X1702093D02*
X1704913D01*
G02X1705116Y1614376I1J-202D01*
G01Y1613250D01*
G03X1705144Y1613147I200J-1D01*
G02Y1611185I-1642J-981D01*
G03X1705116Y1611082I172J-102D01*
G01Y1608132D01*
G03X1705144Y1608029I200J-1D01*
G02Y1606067I-1642J-981D01*
G03X1705116Y1605964I172J-102D01*
G01Y1604838D01*
G02X1704913Y1604636I-203J1D01*
G01X1702093D01*
G02X1701890Y1604838I-1J202D01*
G01Y1605964D01*
G03X1701862Y1606067I-200J1D01*
G02Y1608029I1642J981D01*
G03X1701890Y1608132I-172J102D01*
G01Y1611082D01*
G03X1701862Y1611185I-200J1D01*
G02Y1613147I1642J981D01*
G03X1701890Y1613250I-172J102D01*
G01Y1614376D01*
G02X1702093Y1614578I203J-1D01*
G37*
G36*
G01X1312128Y1618706D02*
G02X1312330Y1618908I202J0D01*
G01X1315150D01*
G02X1315352Y1618706I0J-202D01*
G01Y1617580D01*
G03X1315380Y1617477I200J-1D01*
G02X1315652Y1616496I-1640J-983D01*
G02X1315380Y1615515I-1912J2D01*
G03X1315352Y1615412I172J-102D01*
G01Y1612462D01*
G03X1315380Y1612359I200J-1D01*
G02X1315652Y1611378I-1640J-983D01*
G02X1315380Y1610397I-1912J2D01*
G03X1315352Y1610294I172J-102D01*
G01Y1609168D01*
G02X1315150Y1608966I-202J0D01*
G01X1312330D01*
G02X1312128Y1609168I0J202D01*
G01Y1610294D01*
G03X1312100Y1610397I-200J1D01*
G02X1311828Y1611378I1640J983D01*
G02X1312100Y1612359I1912J-2D01*
G03X1312128Y1612462I-172J102D01*
G01Y1615412D01*
G03X1312100Y1615515I-200J1D01*
G02X1311828Y1616496I1640J983D01*
G02X1312100Y1617477I1912J-2D01*
G03X1312128Y1617580I-172J102D01*
G01Y1618706D01*
G37*
G36*
G01X1346774D02*
G02X1346976Y1618908I202J0D01*
G01X1349796D01*
G02X1349998Y1618706I0J-202D01*
G01Y1617580D01*
G03X1350026Y1617477I200J-1D01*
G02X1350298Y1616496I-1640J-983D01*
G02X1350026Y1615515I-1912J2D01*
G03X1349998Y1615412I172J-102D01*
G01Y1612462D01*
G03X1350026Y1612359I200J-1D01*
G02X1350298Y1611378I-1640J-983D01*
G02X1350026Y1610397I-1912J2D01*
G03X1349998Y1610294I172J-102D01*
G01Y1609168D01*
G02X1349796Y1608966I-202J0D01*
G01X1346976D01*
G02X1346774Y1609168I0J202D01*
G01Y1610294D01*
G03X1346746Y1610397I-200J1D01*
G02X1346474Y1611378I1640J983D01*
G02X1346746Y1612359I1912J-2D01*
G03X1346774Y1612462I-172J102D01*
G01Y1615412D01*
G03X1346746Y1615515I-200J1D01*
G02X1346474Y1616496I1640J983D01*
G02X1346746Y1617477I1912J-2D01*
G03X1346774Y1617580I-172J102D01*
G01Y1618706D01*
G37*
G36*
G01X1485356D02*
G02X1485558Y1618908I202J0D01*
G01X1488378D01*
G02X1488580Y1618706I0J-202D01*
G01Y1617580D01*
G03X1488608Y1617477I200J-1D01*
G02X1488880Y1616496I-1640J-983D01*
G02X1488608Y1615515I-1912J2D01*
G03X1488580Y1615412I172J-102D01*
G01Y1612462D01*
G03X1488608Y1612359I200J-1D01*
G02X1488880Y1611378I-1640J-983D01*
G02X1488608Y1610397I-1912J2D01*
G03X1488580Y1610294I172J-102D01*
G01Y1609168D01*
G02X1488378Y1608966I-202J0D01*
G01X1485558D01*
G02X1485356Y1609168I0J202D01*
G01Y1610294D01*
G03X1485328Y1610397I-200J1D01*
G02X1485056Y1611378I1640J983D01*
G02X1485328Y1612359I1912J-2D01*
G03X1485356Y1612462I-172J102D01*
G01Y1615412D01*
G03X1485328Y1615515I-200J1D01*
G02X1485056Y1616496I1640J983D01*
G02X1485328Y1617477I1912J-2D01*
G03X1485356Y1617580I-172J102D01*
G01Y1618706D01*
G37*
G36*
G01X1520002D02*
G02X1520204Y1618908I202J0D01*
G01X1523024D01*
G02X1523226Y1618706I0J-202D01*
G01Y1617580D01*
G03X1523254Y1617477I200J-1D01*
G02X1523526Y1616496I-1640J-983D01*
G02X1523254Y1615515I-1912J2D01*
G03X1523226Y1615412I172J-102D01*
G01Y1612462D01*
G03X1523254Y1612359I200J-1D01*
G02X1523526Y1611378I-1640J-983D01*
G02X1523254Y1610397I-1912J2D01*
G03X1523226Y1610294I172J-102D01*
G01Y1609168D01*
G02X1523024Y1608966I-202J0D01*
G01X1520204D01*
G02X1520002Y1609168I0J202D01*
G01Y1610294D01*
G03X1519974Y1610397I-200J1D01*
G02X1519702Y1611378I1640J983D01*
G02X1519974Y1612359I1912J-2D01*
G03X1520002Y1612462I-172J102D01*
G01Y1615412D01*
G03X1519974Y1615515I-200J1D01*
G02X1519702Y1616496I1640J983D01*
G02X1519974Y1617477I1912J-2D01*
G03X1520002Y1617580I-172J102D01*
G01Y1618706D01*
G37*
G36*
G01X1658584D02*
G02X1658786Y1618908I202J0D01*
G01X1661606D01*
G02X1661808Y1618706I0J-202D01*
G01Y1617580D01*
G03X1661836Y1617477I200J-1D01*
G02X1662108Y1616496I-1640J-983D01*
G02X1661836Y1615515I-1912J2D01*
G03X1661808Y1615412I172J-102D01*
G01Y1612462D01*
G03X1661836Y1612359I200J-1D01*
G02X1662108Y1611378I-1640J-983D01*
G02X1661836Y1610397I-1912J2D01*
G03X1661808Y1610294I172J-102D01*
G01Y1609168D01*
G02X1661606Y1608966I-202J0D01*
G01X1658786D01*
G02X1658584Y1609168I0J202D01*
G01Y1610294D01*
G03X1658556Y1610397I-200J1D01*
G02X1658284Y1611378I1640J983D01*
G02X1658556Y1612359I1912J-2D01*
G03X1658584Y1612462I-172J102D01*
G01Y1615412D01*
G03X1658556Y1615515I-200J1D01*
G02X1658284Y1616496I1640J983D01*
G02X1658556Y1617477I1912J-2D01*
G03X1658584Y1617580I-172J102D01*
G01Y1618706D01*
G37*
G36*
G01X1693230D02*
G02X1693432Y1618908I202J0D01*
G01X1696252D01*
G02X1696454Y1618706I0J-202D01*
G01Y1617580D01*
G03X1696482Y1617477I200J-1D01*
G02X1696754Y1616496I-1640J-983D01*
G02X1696482Y1615515I-1912J2D01*
G03X1696454Y1615412I172J-102D01*
G01Y1612462D01*
G03X1696482Y1612359I200J-1D01*
G02X1696754Y1611378I-1640J-983D01*
G02X1696482Y1610397I-1912J2D01*
G03X1696454Y1610294I172J-102D01*
G01Y1609168D01*
G02X1696252Y1608966I-202J0D01*
G01X1693432D01*
G02X1693230Y1609168I0J202D01*
G01Y1610294D01*
G03X1693202Y1610397I-200J1D01*
G02X1692930Y1611378I1640J983D01*
G02X1693202Y1612359I1912J-2D01*
G03X1693230Y1612462I-172J102D01*
G01Y1615412D01*
G03X1693202Y1615515I-200J1D01*
G02X1692930Y1616496I1640J983D01*
G02X1693202Y1617477I1912J-2D01*
G03X1693230Y1617580I-172J102D01*
G01Y1618706D01*
G37*
G36*
G01X1329653Y1618908D02*
X1332473D01*
G02X1332676Y1618706I1J-202D01*
G01Y1617580D01*
G03X1332704Y1617477I200J-1D01*
G02Y1615515I-1642J-981D01*
G03X1332676Y1615412I172J-102D01*
G01Y1612462D01*
G03X1332704Y1612359I200J-1D01*
G02Y1610397I-1642J-981D01*
G03X1332676Y1610294I172J-102D01*
G01Y1609168D01*
G02X1332473Y1608966I-203J1D01*
G01X1329653D01*
G02X1329450Y1609168I-1J202D01*
G01Y1610294D01*
G03X1329422Y1610397I-200J1D01*
G02Y1612359I1642J981D01*
G03X1329450Y1612462I-172J102D01*
G01Y1615412D01*
G03X1329422Y1615515I-200J1D01*
G02Y1617477I1642J981D01*
G03X1329450Y1617580I-172J102D01*
G01Y1618706D01*
G02X1329653Y1618908I203J-1D01*
G37*
G36*
G01X1364299D02*
X1367119D01*
G02X1367322Y1618706I1J-202D01*
G01Y1617580D01*
G03X1367350Y1617477I200J-1D01*
G02Y1615515I-1642J-981D01*
G03X1367322Y1615412I172J-102D01*
G01Y1612462D01*
G03X1367350Y1612359I200J-1D01*
G02Y1610397I-1642J-981D01*
G03X1367322Y1610294I172J-102D01*
G01Y1609168D01*
G02X1367119Y1608966I-203J1D01*
G01X1364299D01*
G02X1364096Y1609168I-1J202D01*
G01Y1610294D01*
G03X1364068Y1610397I-200J1D01*
G02Y1612359I1642J981D01*
G03X1364096Y1612462I-172J102D01*
G01Y1615412D01*
G03X1364068Y1615515I-200J1D01*
G02Y1617477I1642J981D01*
G03X1364096Y1617580I-172J102D01*
G01Y1618706D01*
G02X1364299Y1618908I203J-1D01*
G37*
G36*
G01X1502881D02*
X1505701D01*
G02X1505904Y1618706I1J-202D01*
G01Y1617580D01*
G03X1505932Y1617477I200J-1D01*
G02Y1615515I-1642J-981D01*
G03X1505904Y1615412I172J-102D01*
G01Y1612462D01*
G03X1505932Y1612359I200J-1D01*
G02Y1610397I-1642J-981D01*
G03X1505904Y1610294I172J-102D01*
G01Y1609168D01*
G02X1505701Y1608966I-203J1D01*
G01X1502881D01*
G02X1502678Y1609168I-1J202D01*
G01Y1610294D01*
G03X1502650Y1610397I-200J1D01*
G02Y1612359I1642J981D01*
G03X1502678Y1612462I-172J102D01*
G01Y1615412D01*
G03X1502650Y1615515I-200J1D01*
G02Y1617477I1642J981D01*
G03X1502678Y1617580I-172J102D01*
G01Y1618706D01*
G02X1502881Y1618908I203J-1D01*
G37*
G36*
G01X1537527D02*
X1540347D01*
G02X1540550Y1618706I1J-202D01*
G01Y1617580D01*
G03X1540578Y1617477I200J-1D01*
G02Y1615515I-1642J-981D01*
G03X1540550Y1615412I172J-102D01*
G01Y1612462D01*
G03X1540578Y1612359I200J-1D01*
G02Y1610397I-1642J-981D01*
G03X1540550Y1610294I172J-102D01*
G01Y1609168D01*
G02X1540347Y1608966I-203J1D01*
G01X1537527D01*
G02X1537324Y1609168I-1J202D01*
G01Y1610294D01*
G03X1537296Y1610397I-200J1D01*
G02Y1612359I1642J981D01*
G03X1537324Y1612462I-172J102D01*
G01Y1615412D01*
G03X1537296Y1615515I-200J1D01*
G02Y1617477I1642J981D01*
G03X1537324Y1617580I-172J102D01*
G01Y1618706D01*
G02X1537527Y1618908I203J-1D01*
G37*
G36*
G01X1676109D02*
X1678929D01*
G02X1679132Y1618706I1J-202D01*
G01Y1617580D01*
G03X1679160Y1617477I200J-1D01*
G02Y1615515I-1642J-981D01*
G03X1679132Y1615412I172J-102D01*
G01Y1612462D01*
G03X1679160Y1612359I200J-1D01*
G02Y1610397I-1642J-981D01*
G03X1679132Y1610294I172J-102D01*
G01Y1609168D01*
G02X1678929Y1608966I-203J1D01*
G01X1676109D01*
G02X1675906Y1609168I-1J202D01*
G01Y1610294D01*
G03X1675878Y1610397I-200J1D01*
G02Y1612359I1642J981D01*
G03X1675906Y1612462I-172J102D01*
G01Y1615412D01*
G03X1675878Y1615515I-200J1D01*
G02Y1617477I1642J981D01*
G03X1675906Y1617580I-172J102D01*
G01Y1618706D01*
G02X1676109Y1618908I203J-1D01*
G37*
G36*
G01X1710755D02*
X1713575D01*
G02X1713778Y1618706I1J-202D01*
G01Y1617580D01*
G03X1713806Y1617477I200J-1D01*
G02Y1615515I-1642J-981D01*
G03X1713778Y1615412I172J-102D01*
G01Y1612462D01*
G03X1713806Y1612359I200J-1D01*
G02Y1610397I-1642J-981D01*
G03X1713778Y1610294I172J-102D01*
G01Y1609168D01*
G02X1713575Y1608966I-203J1D01*
G01X1710755D01*
G02X1710552Y1609168I-1J202D01*
G01Y1610294D01*
G03X1710524Y1610397I-200J1D01*
G02Y1612359I1642J981D01*
G03X1710552Y1612462I-172J102D01*
G01Y1615412D01*
G03X1710524Y1615515I-200J1D01*
G02Y1617477I1642J981D01*
G03X1710552Y1617580I-172J102D01*
G01Y1618706D01*
G02X1710755Y1618908I203J-1D01*
G37*
G36*
G01X404759Y1350874D02*
X408159D01*
G02Y1347270I0J-1802D01*
G01X404759D01*
G02Y1350874I0J1802D01*
G37*
G36*
G01X402489Y1419078D02*
X405889D01*
G02Y1415472I0J-1803D01*
G01X402489D01*
G02Y1419078I0J1803D01*
G37*
G36*
G01X26772Y1559218D02*
X20472D01*
G02Y1575428I0J8105D01*
G01X26772D01*
G02Y1559218I0J-8105D01*
G37*
G36*
G01X216125Y1441832D02*
X219525D01*
G02Y1438226I0J-1803D01*
G01X216125D01*
G02Y1441832I0J1803D01*
G37*
G36*
G01X413753Y1518690D02*
X417153D01*
G02Y1515084I0J-1803D01*
G01X413753D01*
G02Y1518690I0J1803D01*
G37*
G36*
G01X417334Y1475298D02*
X413934D01*
G02Y1478902I0J1802D01*
G01X417334D01*
G02Y1475298I0J-1802D01*
G37*
G36*
G01X35825Y1466648D02*
X39225D01*
G02Y1463044I0J-1802D01*
G01X35825D01*
G02Y1466648I0J1802D01*
G37*
G36*
G01X42316Y1066197D02*
X42343Y1066171D01*
X42414Y1066143D01*
X42764D01*
X42835Y1066171D01*
X42862Y1066197D01*
G02X43889Y1066603I1027J-1096D01*
G02X45391Y1065101I0J-1502D01*
G02X45021Y1064114I-1501J0D01*
G01Y1064113D01*
X45020D01*
G03X44972Y1063983I152J-130D01*
G01Y1063719D01*
G03X45020Y1063589I200J0D01*
G01X45021Y1063588D01*
G02X45391Y1062601I-1131J-987D01*
G02X43889Y1061099I-1502J0D01*
G02X42862Y1061505I0J1502D01*
G01X42835Y1061531D01*
X42764Y1061559D01*
X42414D01*
X42343Y1061531D01*
X42316Y1061505D01*
G02X40262I-1027J1096D01*
G01X40235Y1061531D01*
X40164Y1061559D01*
X39814D01*
X39743Y1061531D01*
X39716Y1061505D01*
G02X37662I-1027J1096D01*
G01X37635Y1061531D01*
X37564Y1061559D01*
X37214D01*
X37143Y1061531D01*
X37116Y1061505D01*
G02X36089Y1061099I-1027J1096D01*
G02X34587Y1062601I0J1502D01*
G02X34957Y1063588I1501J0D01*
G01Y1063589D01*
X34958D01*
G03X35006Y1063719I-152J130D01*
G01Y1063983D01*
G03X34958Y1064113I-200J0D01*
G01X34957Y1064114D01*
G02X34587Y1065101I1131J987D01*
G02X36089Y1066603I1502J0D01*
G02X37116Y1066197I0J-1502D01*
G01X37143Y1066171D01*
X37214Y1066143D01*
X37564D01*
X37635Y1066171D01*
X37662Y1066197D01*
G02X39716I1027J-1096D01*
G01X39743Y1066171D01*
X39814Y1066143D01*
X40164D01*
X40235Y1066171D01*
X40262Y1066197D01*
G02X42316I1027J-1096D01*
G37*
G36*
G01X27423Y1066625D02*
X27450Y1066599D01*
X27521Y1066571D01*
X27871D01*
X27942Y1066599D01*
X27969Y1066625D01*
G02X28996Y1067031I1027J-1096D01*
G02X30498Y1065529I0J-1502D01*
G02X30128Y1064542I-1501J0D01*
G01Y1064541D01*
X30127D01*
G03X30079Y1064411I152J-130D01*
G01Y1064147D01*
G03X30127Y1064017I200J0D01*
G01X30128Y1064016D01*
G02X30498Y1063029I-1131J-987D01*
G02X28996Y1061527I-1502J0D01*
G02X27969Y1061933I0J1502D01*
G01X27942Y1061959D01*
X27871Y1061987D01*
X27521D01*
X27450Y1061959D01*
X27423Y1061933D01*
G02X25369I-1027J1096D01*
G01X25342Y1061959D01*
X25271Y1061987D01*
X24921D01*
X24850Y1061959D01*
X24823Y1061933D01*
G02X22769I-1027J1096D01*
G01X22742Y1061959D01*
X22671Y1061987D01*
X22321D01*
X22250Y1061959D01*
X22223Y1061933D01*
G02X21196Y1061527I-1027J1096D01*
G02X19694Y1063029I0J1502D01*
G02X20064Y1064016I1501J0D01*
G01Y1064017D01*
X20065D01*
G03X20113Y1064147I-152J130D01*
G01Y1064411D01*
G03X20065Y1064541I-200J0D01*
G01X20064Y1064542D01*
G02X19694Y1065529I1131J987D01*
G02X21196Y1067031I1502J0D01*
G02X22223Y1066625I0J-1502D01*
G01X22250Y1066599D01*
X22321Y1066571D01*
X22671D01*
X22742Y1066599D01*
X22769Y1066625D01*
G02X24823I1027J-1096D01*
G01X24850Y1066599D01*
X24921Y1066571D01*
X25271D01*
X25342Y1066599D01*
X25369Y1066625D01*
G02X27423I1027J-1096D01*
G37*
G36*
G01X33425Y1074161D02*
G02Y1077165I0J1502D01*
G02X34412Y1076795I0J-1501D01*
G01X34413D01*
Y1076794D01*
G03X34543Y1076746I130J152D01*
G01X34807D01*
G03X34937Y1076794I0J200D01*
G01X34938Y1076795D01*
G02X35925Y1077165I987J-1131D01*
G02Y1074161I0J-1502D01*
G02X34938Y1074531I0J1501D01*
G01X34937D01*
Y1074532D01*
G03X34807Y1074580I-130J-152D01*
G01X34543D01*
G03X34413Y1074532I0J-200D01*
G01X34412Y1074531D01*
G02X33425Y1074161I-987J1131D01*
G37*
G36*
G01X27033Y1083774D02*
X27060Y1083748D01*
X27131Y1083720D01*
X27481D01*
X27552Y1083748D01*
X27579Y1083774D01*
G02X28606Y1084180I1027J-1096D01*
G02X30108Y1082678I0J-1502D01*
G02X29738Y1081691I-1501J0D01*
G01Y1081690D01*
X29737D01*
G03X29689Y1081560I152J-130D01*
G01Y1081296D01*
G03X29737Y1081166I200J0D01*
G01X29738Y1081165D01*
G02X30108Y1080178I-1131J-987D01*
G02X28606Y1078676I-1502J0D01*
G02X27579Y1079082I0J1502D01*
G01X27552Y1079108D01*
X27481Y1079136D01*
X27131D01*
X27060Y1079108D01*
X27033Y1079082D01*
G02X24979I-1027J1096D01*
G01X24952Y1079108D01*
X24881Y1079136D01*
X24531D01*
X24460Y1079108D01*
X24433Y1079082D01*
G02X22379I-1027J1096D01*
G01X22352Y1079108D01*
X22281Y1079136D01*
X21931D01*
X21860Y1079108D01*
X21833Y1079082D01*
G02X20806Y1078676I-1027J1096D01*
G02X19304Y1080178I0J1502D01*
G02X19674Y1081165I1501J0D01*
G01Y1081166D01*
X19675D01*
G03X19723Y1081296I-152J130D01*
G01Y1081560D01*
G03X19675Y1081690I-200J0D01*
G01X19674Y1081691D01*
G02X19304Y1082678I1131J987D01*
G02X20806Y1084180I1502J0D01*
G02X21833Y1083774I0J-1502D01*
G01X21860Y1083748D01*
X21931Y1083720D01*
X22281D01*
X22352Y1083748D01*
X22379Y1083774D01*
G02X24433I1027J-1096D01*
G01X24460Y1083748D01*
X24531Y1083720D01*
X24881D01*
X24952Y1083748D01*
X24979Y1083774D01*
G02X27033I1027J-1096D01*
G37*
G36*
G01X61263Y1085999D02*
Y1086313D01*
G03X61186Y1086471I-200J0D01*
G02X60607Y1087656I923J1185D01*
G02X63611I1502J0D01*
G02X63032Y1086471I-1502J0D01*
G03X62955Y1086313I123J-158D01*
G01Y1085999D01*
G03X63032Y1085841I200J0D01*
G02X63611Y1084656I-923J-1185D01*
G02X60607I-1502J0D01*
G02X61186Y1085841I1502J0D01*
G03X61263Y1085999I-123J158D01*
G37*
G36*
G01X27548Y1102431D02*
X27575Y1102405D01*
X27646Y1102377D01*
X27996D01*
X28067Y1102405D01*
X28094Y1102431D01*
G02X29121Y1102837I1027J-1096D01*
G02X30623Y1101335I0J-1502D01*
G02X30230Y1100322I-1502J0D01*
G01X30204Y1100294D01*
X30177Y1100225D01*
Y1099879D01*
X30204Y1099810D01*
X30230Y1099782D01*
G02X30623Y1098769I-1109J-1013D01*
G02X29121Y1097267I-1502J0D01*
G02X28094Y1097673I0J1502D01*
G01X28067Y1097699D01*
X27996Y1097727D01*
X27646D01*
X27575Y1097699D01*
X27548Y1097673D01*
G02X25494I-1027J1096D01*
G01X25467Y1097699D01*
X25396Y1097727D01*
X25046D01*
X24975Y1097699D01*
X24948Y1097673D01*
G02X22894I-1027J1096D01*
G01X22867Y1097699D01*
X22796Y1097727D01*
X22446D01*
X22375Y1097699D01*
X22348Y1097673D01*
G02X21321Y1097267I-1027J1096D01*
G02X19819Y1098769I0J1502D01*
G02X20212Y1099782I1502J0D01*
G01X20238Y1099810D01*
X20265Y1099879D01*
Y1100225D01*
X20238Y1100294D01*
X20212Y1100322D01*
G02X19819Y1101335I1109J1013D01*
G02X21321Y1102837I1502J0D01*
G02X22348Y1102431I0J-1502D01*
G01X22375Y1102405D01*
X22446Y1102377D01*
X22796D01*
X22867Y1102405D01*
X22894Y1102431D01*
G02X24948I1027J-1096D01*
G01X24975Y1102405D01*
X25046Y1102377D01*
X25396D01*
X25467Y1102405D01*
X25494Y1102431D01*
G02X27548I1027J-1096D01*
G37*
G36*
G01X44859Y1106602D02*
G02X45925Y1106158I0J-1502D01*
G03X46067Y1106099I142J141D01*
G01X46351D01*
G03X46493Y1106158I0J200D01*
G02X47559Y1106602I1066J-1058D01*
G02Y1103598I0J-1502D01*
G02X46493Y1104042I0J1502D01*
G03X46351Y1104101I-142J-141D01*
G01X46067D01*
G03X45925Y1104042I0J-200D01*
G02X44859Y1103598I-1066J1058D01*
G02X43832Y1104004I0J1502D01*
G01X43805Y1104030D01*
X43734Y1104058D01*
X43384D01*
X43313Y1104030D01*
X43286Y1104004D01*
G02X41232I-1027J1096D01*
G01X41205Y1104030D01*
X41134Y1104058D01*
X40784D01*
X40713Y1104030D01*
X40686Y1104004D01*
G02X39659Y1103598I-1027J1096D01*
G02Y1106602I0J1502D01*
G02X40686Y1106196I0J-1502D01*
G01X40713Y1106170D01*
X40784Y1106142D01*
X41134D01*
X41205Y1106170D01*
X41232Y1106196D01*
G02X43286I1027J-1096D01*
G01X43313Y1106170D01*
X43384Y1106142D01*
X43734D01*
X43805Y1106170D01*
X43832Y1106196D01*
G02X44859Y1106602I1027J-1096D01*
G37*
G36*
G01X29874Y1113135D02*
G02X30940Y1112691I0J-1502D01*
G03X31082Y1112632I142J141D01*
G01X31366D01*
G03X31508Y1112691I0J200D01*
G02X32574Y1113135I1066J-1058D01*
G02Y1110131I0J-1502D01*
G02X31508Y1110575I0J1502D01*
G03X31366Y1110634I-142J-141D01*
G01X31082D01*
G03X30940Y1110575I0J-200D01*
G02X29874Y1110131I-1066J1058D01*
G02X28847Y1110537I0J1502D01*
G01X28820Y1110563D01*
X28749Y1110591D01*
X28399D01*
X28328Y1110563D01*
X28301Y1110537D01*
G02X26247I-1027J1096D01*
G01X26220Y1110563D01*
X26149Y1110591D01*
X25799D01*
X25728Y1110563D01*
X25701Y1110537D01*
G02X24674Y1110131I-1027J1096D01*
G02Y1113135I0J1502D01*
G02X25701Y1112729I0J-1502D01*
G01X25728Y1112703D01*
X25799Y1112675D01*
X26149D01*
X26220Y1112703D01*
X26247Y1112729D01*
G02X28301I1027J-1096D01*
G01X28328Y1112703D01*
X28399Y1112675D01*
X28749D01*
X28820Y1112703D01*
X28847Y1112729D01*
G02X29874Y1113135I1027J-1096D01*
G37*
G36*
G01X44859Y1116302D02*
G02X45925Y1115858I0J-1502D01*
G03X46067Y1115799I142J141D01*
G01X46351D01*
G03X46493Y1115858I0J200D01*
G02X47559Y1116302I1066J-1058D01*
G02Y1113298I0J-1502D01*
G02X46493Y1113742I0J1502D01*
G03X46351Y1113801I-142J-141D01*
G01X46067D01*
G03X45925Y1113742I0J-200D01*
G02X44859Y1113298I-1066J1058D01*
G02X43832Y1113704I0J1502D01*
G01X43805Y1113730D01*
X43734Y1113758D01*
X43384D01*
X43313Y1113730D01*
X43286Y1113704D01*
G02X41232I-1027J1096D01*
G01X41205Y1113730D01*
X41134Y1113758D01*
X40784D01*
X40713Y1113730D01*
X40686Y1113704D01*
G02X39659Y1113298I-1027J1096D01*
G02Y1116302I0J1502D01*
G02X40686Y1115896I0J-1502D01*
G01X40713Y1115870D01*
X40784Y1115842D01*
X41134D01*
X41205Y1115870D01*
X41232Y1115896D01*
G02X43286I1027J-1096D01*
G01X43313Y1115870D01*
X43384Y1115842D01*
X43734D01*
X43805Y1115870D01*
X43832Y1115896D01*
G02X44859Y1116302I1027J-1096D01*
G37*
G36*
G01X29874Y1122835D02*
G02X30940Y1122391I0J-1502D01*
G03X31082Y1122332I142J141D01*
G01X31366D01*
G03X31508Y1122391I0J200D01*
G02X32574Y1122835I1066J-1058D01*
G02Y1119831I0J-1502D01*
G02X31508Y1120275I0J1502D01*
G03X31366Y1120334I-142J-141D01*
G01X31082D01*
G03X30940Y1120275I0J-200D01*
G02X29874Y1119831I-1066J1058D01*
G02X28847Y1120237I0J1502D01*
G01X28820Y1120263D01*
X28749Y1120291D01*
X28399D01*
X28328Y1120263D01*
X28301Y1120237D01*
G02X26247I-1027J1096D01*
G01X26220Y1120263D01*
X26149Y1120291D01*
X25799D01*
X25728Y1120263D01*
X25701Y1120237D01*
G02X24674Y1119831I-1027J1096D01*
G02Y1122835I0J1502D01*
G02X25701Y1122429I0J-1502D01*
G01X25728Y1122403D01*
X25799Y1122375D01*
X26149D01*
X26220Y1122403D01*
X26247Y1122429D01*
G02X28301I1027J-1096D01*
G01X28328Y1122403D01*
X28399Y1122375D01*
X28749D01*
X28820Y1122403D01*
X28847Y1122429D01*
G02X29874Y1122835I1027J-1096D01*
G37*
G36*
G01X21974Y1128831D02*
G02Y1131835I0J1502D01*
G02X23040Y1131391I0J-1502D01*
G03X23182Y1131332I142J141D01*
G01X23466D01*
G03X23608Y1131391I0J200D01*
G02X24674Y1131835I1066J-1058D01*
G02Y1128831I0J-1502D01*
G02X23608Y1129275I0J1502D01*
G03X23466Y1129334I-142J-141D01*
G01X23182D01*
G03X23040Y1129275I0J-200D01*
G02X21974Y1128831I-1066J1058D01*
G37*
G36*
G01X48547Y1132186D02*
G02Y1135190I0J1502D01*
G02X49534Y1134820I0J-1501D01*
G01X49535D01*
Y1134819D01*
G03X49665Y1134771I130J152D01*
G01X49929D01*
G03X50059Y1134819I0J200D01*
G01X50060Y1134820D01*
G02X51047Y1135190I987J-1131D01*
G02Y1132186I0J-1502D01*
G02X50060Y1132556I0J1501D01*
G01X50059D01*
Y1132557D01*
G03X49929Y1132605I-130J-152D01*
G01X49665D01*
G03X49535Y1132557I0J-200D01*
G01X49534Y1132556D01*
G02X48547Y1132186I-987J1131D01*
G37*
G36*
G01X21209Y1137203D02*
G02Y1140207I0J1502D01*
G02X22196Y1139837I0J-1501D01*
G01X22197D01*
Y1139836D01*
G03X22327Y1139788I130J152D01*
G01X22591D01*
G03X22721Y1139836I0J200D01*
G01X22722Y1139837D01*
G02X23709Y1140207I987J-1131D01*
G02Y1137203I0J-1502D01*
G02X22722Y1137573I0J1501D01*
G01X22721D01*
Y1137574D01*
G03X22591Y1137622I-130J-152D01*
G01X22327D01*
G03X22197Y1137574I0J-200D01*
G01X22196Y1137573D01*
G02X21209Y1137203I-987J1131D01*
G37*
G36*
G01X46685Y1255187D02*
X46686Y1255186D01*
G03X46816Y1255138I130J152D01*
G01X47080D01*
G03X47210Y1255186I0J200D01*
G01X47211Y1255187D01*
G02X48198Y1255557I987J-1131D01*
G02X49700Y1254055I0J-1502D01*
G02X49330Y1253068I-1501J0D01*
G01Y1253067D01*
X49329D01*
G03X49281Y1252937I152J-130D01*
G01Y1252673D01*
G03X49329Y1252543I200J0D01*
G01X49330Y1252542D01*
G02X49700Y1251555I-1131J-987D01*
G02X48198Y1250053I-1502J0D01*
G02X47211Y1250423I0J1501D01*
G01X47210D01*
Y1250424D01*
G03X47080Y1250472I-130J-152D01*
G01X46816D01*
G03X46686Y1250424I0J-200D01*
G01X46685Y1250423D01*
G02X44711I-987J1131D01*
G01X44710D01*
Y1250424D01*
G03X44580Y1250472I-130J-152D01*
G01X44316D01*
G03X44186Y1250424I0J-200D01*
G01X44185Y1250423D01*
G02X43198Y1250053I-987J1131D01*
G02X41696Y1251555I0J1502D01*
G02X42066Y1252542I1501J0D01*
G01Y1252543D01*
X42067D01*
G03X42115Y1252673I-152J130D01*
G01Y1252937D01*
G03X42067Y1253067I-200J0D01*
G01X42066Y1253068D01*
G02X41696Y1254055I1131J987D01*
G02X43198Y1255557I1502J0D01*
G02X44185Y1255187I0J-1501D01*
G01X44186D01*
Y1255186D01*
G03X44316Y1255138I130J152D01*
G01X44580D01*
G03X44710Y1255186I0J200D01*
G01X44711Y1255187D01*
G02X46685I987J-1131D01*
G37*
G36*
G01X445045Y1261006D02*
X445359D01*
G03X445517Y1261083I0J200D01*
G02X447887I1185J-923D01*
G03X448045Y1261006I158J123D01*
G01X448359D01*
G03X448517Y1261083I0J200D01*
G02X449702Y1261662I1185J-923D01*
G02X451204Y1260160I0J-1502D01*
G02X450625Y1258975I-1502J0D01*
G03X450548Y1258817I123J-158D01*
G01Y1258503D01*
G03X450625Y1258345I200J0D01*
G02X451204Y1257160I-923J-1185D01*
G02X449702Y1255658I-1502J0D01*
G02X448517Y1256237I0J1502D01*
G03X448359Y1256314I-158J-123D01*
G01X448045D01*
G03X447887Y1256237I0J-200D01*
G02X445517I-1185J923D01*
G03X445359Y1256314I-158J-123D01*
G01X445045D01*
G03X444887Y1256237I0J-200D01*
G02X442517I-1185J923D01*
G03X442359Y1256314I-158J-123D01*
G01X442045D01*
G03X441887Y1256237I0J-200D01*
G02X439517I-1185J923D01*
G03X439359Y1256314I-158J-123D01*
G01X439045D01*
G03X438887Y1256237I0J-200D01*
G02X436517I-1185J923D01*
G03X436359Y1256314I-158J-123D01*
G01X436045D01*
G03X435887Y1256237I0J-200D01*
G02X433517I-1185J923D01*
G03X433359Y1256314I-158J-123D01*
G01X433045D01*
G03X432887Y1256237I0J-200D01*
G02X430517I-1185J923D01*
G03X430359Y1256314I-158J-123D01*
G01X430045D01*
G03X429887Y1256237I0J-200D01*
G02X427517I-1185J923D01*
G03X427359Y1256314I-158J-123D01*
G01X427045D01*
G03X426887Y1256237I0J-200D01*
G02X424517I-1185J923D01*
G03X424359Y1256314I-158J-123D01*
G01X424045D01*
G03X423887Y1256237I0J-200D01*
G02X421517I-1185J923D01*
G03X421359Y1256314I-158J-123D01*
G01X421045D01*
G03X420887Y1256237I0J-200D01*
G02X419702Y1255658I-1185J923D01*
G02X418200Y1257160I0J1502D01*
G02X418779Y1258345I1502J0D01*
G03X418856Y1258503I-123J158D01*
G01Y1258817D01*
G03X418779Y1258975I-200J0D01*
G02X418200Y1260160I923J1185D01*
G02X419702Y1261662I1502J0D01*
G02X420887Y1261083I0J-1502D01*
G03X421045Y1261006I158J123D01*
G01X421359D01*
G03X421517Y1261083I0J200D01*
G02X423887I1185J-923D01*
G03X424045Y1261006I158J123D01*
G01X424359D01*
G03X424517Y1261083I0J200D01*
G02X426887I1185J-923D01*
G03X427045Y1261006I158J123D01*
G01X427359D01*
G03X427517Y1261083I0J200D01*
G02X429887I1185J-923D01*
G03X430045Y1261006I158J123D01*
G01X430359D01*
G03X430517Y1261083I0J200D01*
G02X432887I1185J-923D01*
G03X433045Y1261006I158J123D01*
G01X433359D01*
G03X433517Y1261083I0J200D01*
G02X435887I1185J-923D01*
G03X436045Y1261006I158J123D01*
G01X436359D01*
G03X436517Y1261083I0J200D01*
G02X438887I1185J-923D01*
G03X439045Y1261006I158J123D01*
G01X439359D01*
G03X439517Y1261083I0J200D01*
G02X441887I1185J-923D01*
G03X442045Y1261006I158J123D01*
G01X442359D01*
G03X442517Y1261083I0J200D01*
G02X444887I1185J-923D01*
G03X445045Y1261006I158J123D01*
G37*
G36*
G01X502990D02*
X503304D01*
G03X503462Y1261083I0J200D01*
G02X504647Y1261662I1185J-923D01*
G02X505713Y1261218I0J-1502D01*
G03X505855Y1261159I142J141D01*
G01X506139D01*
G03X506281Y1261218I0J200D01*
G02X507347Y1261662I1066J-1058D01*
G02X508849Y1260160I0J-1502D01*
G02X508270Y1258975I-1502J0D01*
G03X508193Y1258817I123J-158D01*
G01Y1258503D01*
G03X508270Y1258345I200J0D01*
G02X508849Y1257160I-923J-1185D01*
G02X507347Y1255658I-1502J0D01*
G02X506281Y1256102I0J1502D01*
G03X506139Y1256161I-142J-141D01*
G01X505855D01*
G03X505713Y1256102I0J-200D01*
G02X504647Y1255658I-1066J1058D01*
G02X503462Y1256237I0J1502D01*
G03X503304Y1256314I-158J-123D01*
G01X502990D01*
G03X502832Y1256237I0J-200D01*
G02X500462I-1185J923D01*
G03X500304Y1256314I-158J-123D01*
G01X499990D01*
G03X499832Y1256237I0J-200D01*
G02X497462I-1185J923D01*
G03X497304Y1256314I-158J-123D01*
G01X496990D01*
G03X496832Y1256237I0J-200D01*
G02X494462I-1185J923D01*
G03X494304Y1256314I-158J-123D01*
G01X493990D01*
G03X493832Y1256237I0J-200D01*
G02X491462I-1185J923D01*
G03X491304Y1256314I-158J-123D01*
G01X490990D01*
G03X490832Y1256237I0J-200D01*
G02X488462I-1185J923D01*
G03X488304Y1256314I-158J-123D01*
G01X487990D01*
G03X487832Y1256237I0J-200D01*
G02X485462I-1185J923D01*
G03X485304Y1256314I-158J-123D01*
G01X484990D01*
G03X484832Y1256237I0J-200D01*
G02X482462I-1185J923D01*
G03X482304Y1256314I-158J-123D01*
G01X481990D01*
G03X481832Y1256237I0J-200D01*
G02X479462I-1185J923D01*
G03X479304Y1256314I-158J-123D01*
G01X478990D01*
G03X478832Y1256237I0J-200D01*
G02X476462I-1185J923D01*
G03X476304Y1256314I-158J-123D01*
G01X475990D01*
G03X475832Y1256237I0J-200D01*
G02X473462I-1185J923D01*
G03X473304Y1256314I-158J-123D01*
G01X472990D01*
G03X472832Y1256237I0J-200D01*
G02X471647Y1255658I-1185J923D01*
G02X470145Y1257160I0J1502D01*
G02X470724Y1258345I1502J0D01*
G03X470801Y1258503I-123J158D01*
G01Y1258817D01*
G03X470724Y1258975I-200J0D01*
G02X470145Y1260160I923J1185D01*
G02X471647Y1261662I1502J0D01*
G02X472832Y1261083I0J-1502D01*
G03X472990Y1261006I158J123D01*
G01X473304D01*
G03X473462Y1261083I0J200D01*
G02X475832I1185J-923D01*
G03X475990Y1261006I158J123D01*
G01X476304D01*
G03X476462Y1261083I0J200D01*
G02X478832I1185J-923D01*
G03X478990Y1261006I158J123D01*
G01X479304D01*
G03X479462Y1261083I0J200D01*
G02X481832I1185J-923D01*
G03X481990Y1261006I158J123D01*
G01X482304D01*
G03X482462Y1261083I0J200D01*
G02X484832I1185J-923D01*
G03X484990Y1261006I158J123D01*
G01X485304D01*
G03X485462Y1261083I0J200D01*
G02X487832I1185J-923D01*
G03X487990Y1261006I158J123D01*
G01X488304D01*
G03X488462Y1261083I0J200D01*
G02X490832I1185J-923D01*
G03X490990Y1261006I158J123D01*
G01X491304D01*
G03X491462Y1261083I0J200D01*
G02X493832I1185J-923D01*
G03X493990Y1261006I158J123D01*
G01X494304D01*
G03X494462Y1261083I0J200D01*
G02X496832I1185J-923D01*
G03X496990Y1261006I158J123D01*
G01X497304D01*
G03X497462Y1261083I0J200D01*
G02X499832I1185J-923D01*
G03X499990Y1261006I158J123D01*
G01X500304D01*
G03X500462Y1261083I0J200D01*
G02X502832I1185J-923D01*
G03X502990Y1261006I158J123D01*
G37*
G36*
G01X487600Y1300598D02*
G02Y1303602I0J1502D01*
G02X488587Y1303232I0J-1501D01*
G01X488588D01*
Y1303231D01*
G03X488718Y1303183I130J152D01*
G01X488982D01*
G03X489112Y1303231I0J200D01*
G01X489113Y1303232D01*
G02X490100Y1303602I987J-1131D01*
G02Y1300598I0J-1502D01*
G02X489113Y1300968I0J1501D01*
G01X489112D01*
Y1300969D01*
G03X488982Y1301017I-130J-152D01*
G01X488718D01*
G03X488588Y1300969I0J-200D01*
G01X488587Y1300968D01*
G02X487600Y1300598I-987J1131D01*
G37*
G36*
G01X403419Y1321819D02*
G02X406423I1502J0D01*
G02X404922Y1320317I-1502J0D01*
G01X404920D01*
G02X404878Y1320318I15J1502D01*
G01X404877D01*
G03X404729Y1320258I-5J-200D01*
G01X404524Y1320047D01*
G03X404467Y1319896I143J-140D01*
G02X404469Y1319815I-1500J-78D01*
G02X401465I-1502J0D01*
G02X402966Y1321317I1502J0D01*
G01X402968D01*
G02X403010Y1321316I-15J-1502D01*
G01X403011D01*
G03X403159Y1321376I5J200D01*
G01X403364Y1321587D01*
G03X403421Y1321738I-143J140D01*
G02X403419Y1321819I1500J78D01*
G37*
G36*
G01X426447Y1327954D02*
X427212D01*
G02X427615Y1327884I-1J-1201D01*
G01X427616D01*
X431467Y1326506D01*
G02X431551Y1326448I-68J-188D01*
G01X431899Y1326045D01*
G02X431944Y1325951I-152J-130D01*
G01X431994Y1325689D01*
G03X432485Y1325284I491J95D01*
G01X432487D01*
G03X432805Y1325399I-1J500D01*
G01X432806Y1325400D01*
X433013Y1325572D01*
G02X433107Y1325615I127J-154D01*
G01X433630Y1325705D01*
G02X433732Y1325696I34J-197D01*
G01X434170Y1325539D01*
G02X434269Y1325498I-410J-1129D01*
G01X434270D01*
X434423Y1325427D01*
G02X435120Y1324338I-504J-1090D01*
G01Y1314417D01*
G02X434768Y1313568I-1201J1D01*
G01X434426Y1313227D01*
G02X433598Y1312875I-850J849D01*
G03X433482Y1312836I3J-200D01*
G01X433390Y1312767D01*
G03X433318Y1312666I119J-161D01*
G02X431885Y1311613I-1433J449D01*
G02X430864Y1312013I0J1503D01*
G03X430623Y1312036I-136J-147D01*
G02X429989Y1311854I-636J1020D01*
G01X429197D01*
G02X428347Y1312207I1J1202D01*
G01X422693Y1317862D01*
G03X422691Y1317864I-142J-140D01*
G01X422548Y1318003D01*
G02X422501Y1318071I137J145D01*
G01X422349Y1318448D01*
G02X422334Y1318523I185J76D01*
G01Y1323841D01*
G02X422686Y1324690I1201J-1D01*
G01X425598Y1327602D01*
G02X426447Y1327954I850J-849D01*
G37*
G36*
G01X425283Y1365525D02*
G02X426785Y1364023I0J-1502D01*
G01Y1364020D01*
G02X426753Y1363713I-1502J1D01*
G01X426744Y1363669D01*
X426764Y1363581D01*
X426989Y1363304D01*
G03X427144Y1363230I155J126D01*
G01X428319D01*
G02X428461Y1363171I0J-200D01*
G01X429953Y1361680D01*
G02X430012Y1361538I-141J-142D01*
G01Y1354649D01*
G02X429953Y1354507I-200J0D01*
G01X428376Y1352931D01*
G02X428234Y1352872I-142J141D01*
G01X416741D01*
G02X416599Y1352931I0J200D01*
G01X414311Y1355218D01*
G02X414252Y1355360I141J142D01*
G01Y1360571D01*
G02X414311Y1360713I200J0D01*
G01X416353Y1362755D01*
G03X416412Y1362897I-141J142D01*
G01Y1369670D01*
G03X416354Y1369810I-200J-1D01*
G01X416156Y1370011D01*
G03X416016Y1370070I-142J-141D01*
G02X414527Y1371572I13J1502D01*
G02X416029Y1373074I1502J0D01*
G02X416741Y1372894I-1J-1502D01*
G01X416800Y1372863D01*
X416930Y1372882D01*
X417576Y1373528D01*
G02X417718Y1373586I141J-142D01*
G01X422328D01*
G02X422470Y1373527I0J-200D01*
G01X423643Y1372354D01*
G02X423702Y1372212I-141J-142D01*
G01Y1365514D01*
G03X423815Y1365334I200J0D01*
G01X424139Y1365177D01*
G03X424350Y1365200I87J180D01*
G01X424351Y1365201D01*
G02X425283Y1365525I932J-1178D01*
G37*
G36*
G01X419698Y1417900D02*
G02X422702I1502J0D01*
G02X422370Y1416958I-1502J0D01*
G01X422347Y1416930D01*
X422324Y1416862D01*
X422336Y1416562D01*
G03X422391Y1416432I200J8D01*
G02X422802Y1415400I-1090J-1032D01*
G02X419798I-1502J0D01*
G02X420130Y1416342I1502J0D01*
G01X420153Y1416370D01*
X420176Y1416438D01*
X420164Y1416738D01*
G03X420109Y1416868I-200J-8D01*
G02X419698Y1417900I1090J1032D01*
G37*
G36*
G01X394650Y1422791D02*
X394338D01*
G03X394183Y1422717I0J-200D01*
G02X393094Y1422198I-1089J883D01*
G02Y1425002I0J1402D01*
G02X394183Y1424483I0J-1402D01*
G03X394338Y1424409I155J126D01*
G01X394650D01*
G03X394805Y1424483I0J200D01*
G02X395894Y1425002I1089J-883D01*
G02Y1422198I0J-1402D01*
G02X394805Y1422717I0J1402D01*
G03X394650Y1422791I-155J-126D01*
G37*
G36*
G01X410154Y1461843D02*
Y1462157D01*
G03X410077Y1462315I-200J0D01*
G02X409498Y1463500I923J1185D01*
G02X412502I1502J0D01*
G02X411923Y1462315I-1502J0D01*
G03X411846Y1462157I123J-158D01*
G01Y1461843D01*
G03X411923Y1461685I200J0D01*
G02Y1459315I-923J-1185D01*
G03X411846Y1459157I123J-158D01*
G01Y1458843D01*
G03X411923Y1458685I200J0D01*
G02Y1456315I-923J-1185D01*
G03X411846Y1456157I123J-158D01*
G01Y1455843D01*
G03X411923Y1455685I200J0D01*
G02X412502Y1454500I-923J-1185D01*
G02X409498I-1502J0D01*
G02X410077Y1455685I1502J0D01*
G03X410154Y1455843I-123J158D01*
G01Y1456157D01*
G03X410077Y1456315I-200J0D01*
G02Y1458685I923J1185D01*
G03X410154Y1458843I-123J158D01*
G01Y1459157D01*
G03X410077Y1459315I-200J0D01*
G02Y1461685I923J1185D01*
G03X410154Y1461843I-123J158D01*
G37*
G36*
G01X186222Y1469155D02*
Y1470281D01*
G02X186425Y1470484I203J0D01*
G01X189245D01*
G02X189448Y1470281I0J-203D01*
G01Y1469155D01*
G03X189476Y1469052I200J-1D01*
G02Y1467090I-1642J-981D01*
G03X189448Y1466987I172J-102D01*
G01Y1464037D01*
G03X189476Y1463934I200J-1D01*
G02Y1461972I-1642J-981D01*
G03X189448Y1461869I172J-102D01*
G01Y1460743D01*
G02X189245Y1460540I-203J0D01*
G01X186425D01*
G02X186222Y1460743I0J203D01*
G01Y1461869D01*
G03X186194Y1461972I-200J1D01*
G02Y1463934I1642J981D01*
G03X186222Y1464037I-172J102D01*
G01Y1466987D01*
G03X186194Y1467090I-200J1D01*
G02Y1469052I1642J981D01*
G03X186222Y1469155I-172J102D01*
G37*
G36*
G01Y1484510D02*
Y1485636D01*
G02X186425Y1485838I203J-1D01*
G01X189245D01*
G02X189448Y1485636I1J-202D01*
G01Y1484510D01*
G03X189476Y1484407I200J-1D01*
G02Y1482445I-1642J-981D01*
G03X189448Y1482342I172J-102D01*
G01Y1479392D01*
G03X189476Y1479289I200J-1D01*
G02Y1477327I-1642J-981D01*
G03X189448Y1477224I172J-102D01*
G01Y1476098D01*
G02X189245Y1475896I-203J1D01*
G01X186425D01*
G02X186222Y1476098I-1J202D01*
G01Y1477224D01*
G03X186194Y1477327I-200J1D01*
G02Y1479289I1642J981D01*
G03X186222Y1479392I-172J102D01*
G01Y1482342D01*
G03X186194Y1482445I-200J1D01*
G02Y1484407I1642J981D01*
G03X186222Y1484510I-172J102D01*
G37*
G36*
G01X125592Y1495533D02*
Y1496659D01*
G02X125795Y1496862I203J0D01*
G01X128615D01*
G02X128818Y1496659I0J-203D01*
G01Y1495533D01*
G03X128846Y1495430I200J-1D01*
G02Y1493468I-1642J-981D01*
G03X128818Y1493365I172J-102D01*
G01Y1490415D01*
G03X128846Y1490312I200J-1D01*
G02Y1488350I-1642J-981D01*
G03X128818Y1488247I172J-102D01*
G01Y1487121D01*
G02X128615Y1486918I-203J0D01*
G01X125795D01*
G02X125592Y1487121I0J203D01*
G01Y1488247D01*
G03X125564Y1488350I-200J1D01*
G02Y1490312I1642J981D01*
G03X125592Y1490415I-172J102D01*
G01Y1493365D01*
G03X125564Y1493468I-200J1D01*
G02Y1495430I1642J981D01*
G03X125592Y1495533I-172J102D01*
G37*
G36*
G01X142916D02*
Y1496659D01*
G02X143118Y1496862I202J1D01*
G01X145938D01*
G02X146140Y1496659I-1J-203D01*
G01Y1495533D01*
G03X146168Y1495430I200J-1D01*
G02X146440Y1494449I-1640J-983D01*
G02X146168Y1493468I-1912J2D01*
G03X146140Y1493365I172J-102D01*
G01Y1490415D01*
G03X146168Y1490312I200J-1D01*
G02X146440Y1489331I-1640J-983D01*
G02X146168Y1488350I-1912J2D01*
G03X146140Y1488247I172J-102D01*
G01Y1487121D01*
G02X145938Y1486918I-202J-1D01*
G01X143118D01*
G02X142916Y1487121I1J203D01*
G01Y1488247D01*
G03X142888Y1488350I-200J1D01*
G02X142616Y1489331I1640J983D01*
G02X142888Y1490312I1912J-2D01*
G03X142916Y1490415I-172J102D01*
G01Y1493365D01*
G03X142888Y1493468I-200J1D01*
G02X142616Y1494449I1640J983D01*
G02X142888Y1495430I1912J-2D01*
G03X142916Y1495533I-172J102D01*
G37*
G36*
G01X160238D02*
Y1496659D01*
G02X160440Y1496862I202J1D01*
G01X163260D01*
G02X163462Y1496659I-1J-203D01*
G01Y1495533D01*
G03X163490Y1495430I200J-1D01*
G02X163762Y1494449I-1640J-983D01*
G02X163490Y1493468I-1912J2D01*
G03X163462Y1493365I172J-102D01*
G01Y1490415D01*
G03X163490Y1490312I200J-1D01*
G02X163762Y1489331I-1640J-983D01*
G02X163490Y1488350I-1912J2D01*
G03X163462Y1488247I172J-102D01*
G01Y1487121D01*
G02X163260Y1486918I-202J-1D01*
G01X160440D01*
G02X160238Y1487121I1J203D01*
G01Y1488247D01*
G03X160210Y1488350I-200J1D01*
G02X159938Y1489331I1640J983D01*
G02X160210Y1490312I1912J-2D01*
G03X160238Y1490415I-172J102D01*
G01Y1493365D01*
G03X160210Y1493468I-200J1D01*
G02X159938Y1494449I1640J983D01*
G02X160210Y1495430I1912J-2D01*
G03X160238Y1495533I-172J102D01*
G37*
G36*
G01X116930Y1499864D02*
Y1500989D01*
G02X117133Y1501192I203J0D01*
G01X119953D01*
G02X120156Y1500989I0J-203D01*
G01Y1499864D01*
G03X120184Y1499761I200J-1D01*
G02Y1497799I-1642J-981D01*
G03X120156Y1497696I172J-102D01*
G01Y1494746D01*
G03X120184Y1494643I200J-1D01*
G02Y1492681I-1642J-981D01*
G03X120156Y1492578I172J-102D01*
G01Y1491451D01*
G02X119953Y1491248I-203J0D01*
G01X117133D01*
G02X116930Y1491451I0J203D01*
G01Y1492578D01*
G03X116902Y1492681I-200J1D01*
G02Y1494643I1642J981D01*
G03X116930Y1494746I-172J102D01*
G01Y1497696D01*
G03X116902Y1497799I-200J1D01*
G02Y1499761I1642J981D01*
G03X116930Y1499864I-172J102D01*
G37*
G36*
G01X134254D02*
Y1500989D01*
G02X134456Y1501192I202J1D01*
G01X137276D01*
G02X137478Y1500989I-1J-203D01*
G01Y1499864D01*
G03X137506Y1499761I200J-1D01*
G02X137778Y1498780I-1640J-983D01*
G02X137506Y1497799I-1912J2D01*
G03X137478Y1497696I172J-102D01*
G01Y1494746D01*
G03X137506Y1494643I200J-1D01*
G02X137778Y1493662I-1640J-983D01*
G02X137506Y1492681I-1912J2D01*
G03X137478Y1492578I172J-102D01*
G01Y1491451D01*
G02X137276Y1491248I-202J-1D01*
G01X134456D01*
G02X134254Y1491451I1J203D01*
G01Y1492578D01*
G03X134226Y1492681I-200J1D01*
G02X133954Y1493662I1640J983D01*
G02X134226Y1494643I1912J-2D01*
G03X134254Y1494746I-172J102D01*
G01Y1497696D01*
G03X134226Y1497799I-200J1D01*
G02X133954Y1498780I1640J983D01*
G02X134226Y1499761I1912J-2D01*
G03X134254Y1499864I-172J102D01*
G37*
G36*
G01X151576D02*
Y1500989D01*
G02X151779Y1501192I203J0D01*
G01X154599D01*
G02X154802Y1500989I0J-203D01*
G01Y1499864D01*
G03X154830Y1499761I200J-1D01*
G02Y1497799I-1642J-981D01*
G03X154802Y1497696I172J-102D01*
G01Y1494746D01*
G03X154830Y1494643I200J-1D01*
G02Y1492681I-1642J-981D01*
G03X154802Y1492578I172J-102D01*
G01Y1491451D01*
G02X154599Y1491248I-203J0D01*
G01X151779D01*
G02X151576Y1491451I0J203D01*
G01Y1492578D01*
G03X151548Y1492681I-200J1D01*
G02Y1494643I1642J981D01*
G03X151576Y1494746I-172J102D01*
G01Y1497696D01*
G03X151548Y1497799I-200J1D01*
G02Y1499761I1642J981D01*
G03X151576Y1499864I-172J102D01*
G37*
G36*
G01X168900D02*
Y1500989D01*
G02X169102Y1501192I202J1D01*
G01X171922D01*
G02X172124Y1500989I-1J-203D01*
G01Y1499864D01*
G03X172152Y1499761I200J-1D01*
G02X172424Y1498780I-1640J-983D01*
G02X172152Y1497799I-1912J2D01*
G03X172124Y1497696I172J-102D01*
G01Y1494746D01*
G03X172152Y1494643I200J-1D01*
G02X172424Y1493662I-1640J-983D01*
G02X172152Y1492681I-1912J2D01*
G03X172124Y1492578I172J-102D01*
G01Y1491451D01*
G02X171922Y1491248I-202J-1D01*
G01X169102D01*
G02X168900Y1491451I1J203D01*
G01Y1492578D01*
G03X168872Y1492681I-200J1D01*
G02X168600Y1493662I1640J983D01*
G02X168872Y1494643I1912J-2D01*
G03X168900Y1494746I-172J102D01*
G01Y1497696D01*
G03X168872Y1497799I-200J1D01*
G02X168600Y1498780I1640J983D01*
G02X168872Y1499761I1912J-2D01*
G03X168900Y1499864I-172J102D01*
G37*
G36*
G01X125592Y1510888D02*
Y1512014D01*
G02X125795Y1512216I203J-1D01*
G01X128615D01*
G02X128818Y1512014I1J-202D01*
G01Y1510888D01*
G03X128846Y1510785I200J-1D01*
G02Y1508823I-1642J-981D01*
G03X128818Y1508720I172J-102D01*
G01Y1505769D01*
G03X128846Y1505666I200J-1D01*
G02Y1503704I-1642J-981D01*
G03X128818Y1503601I172J-102D01*
G01Y1502476D01*
G02X128615Y1502274I-203J1D01*
G01X125795D01*
G02X125592Y1502476I-1J202D01*
G01Y1503601D01*
G03X125564Y1503704I-200J1D01*
G02Y1505666I1642J981D01*
G03X125592Y1505769I-172J102D01*
G01Y1508720D01*
G03X125564Y1508823I-200J1D01*
G02Y1510785I1642J981D01*
G03X125592Y1510888I-172J102D01*
G37*
G36*
G01X142916D02*
Y1512014D01*
G02X143118Y1512216I202J0D01*
G01X145938D01*
G02X146140Y1512014I0J-202D01*
G01Y1510888D01*
G03X146168Y1510785I200J-1D01*
G02X146440Y1509804I-1640J-983D01*
G02X146168Y1508823I-1912J2D01*
G03X146140Y1508720I172J-102D01*
G01Y1505769D01*
G03X146168Y1505666I200J-1D01*
G02X146440Y1504685I-1640J-983D01*
G02X146168Y1503704I-1912J2D01*
G03X146140Y1503601I172J-102D01*
G01Y1502476D01*
G02X145938Y1502274I-202J0D01*
G01X143118D01*
G02X142916Y1502476I0J202D01*
G01Y1503601D01*
G03X142888Y1503704I-200J1D01*
G02X142616Y1504685I1640J983D01*
G02X142888Y1505666I1912J-2D01*
G03X142916Y1505769I-172J102D01*
G01Y1508720D01*
G03X142888Y1508823I-200J1D01*
G02X142616Y1509804I1640J983D01*
G02X142888Y1510785I1912J-2D01*
G03X142916Y1510888I-172J102D01*
G37*
G36*
G01X160238D02*
Y1512014D01*
G02X160440Y1512216I202J0D01*
G01X163260D01*
G02X163462Y1512014I0J-202D01*
G01Y1510888D01*
G03X163490Y1510785I200J-1D01*
G02X163762Y1509804I-1640J-983D01*
G02X163490Y1508823I-1912J2D01*
G03X163462Y1508720I172J-102D01*
G01Y1505769D01*
G03X163490Y1505666I200J-1D01*
G02X163762Y1504685I-1640J-983D01*
G02X163490Y1503704I-1912J2D01*
G03X163462Y1503601I172J-102D01*
G01Y1502476D01*
G02X163260Y1502274I-202J0D01*
G01X160440D01*
G02X160238Y1502476I0J202D01*
G01Y1503601D01*
G03X160210Y1503704I-200J1D01*
G02X159938Y1504685I1640J983D01*
G02X160210Y1505666I1912J-2D01*
G03X160238Y1505769I-172J102D01*
G01Y1508720D01*
G03X160210Y1508823I-200J1D01*
G02X159938Y1509804I1640J983D01*
G02X160210Y1510785I1912J-2D01*
G03X160238Y1510888I-172J102D01*
G37*
G36*
G01X177560D02*
Y1512014D01*
G02X177763Y1512216I203J-1D01*
G01X180583D01*
G02X180786Y1512014I1J-202D01*
G01Y1510888D01*
G03X180814Y1510785I200J-1D01*
G02Y1508823I-1642J-981D01*
G03X180786Y1508720I172J-102D01*
G01Y1505769D01*
G03X180814Y1505666I200J-1D01*
G02Y1503704I-1642J-981D01*
G03X180786Y1503601I172J-102D01*
G01Y1502476D01*
G02X180583Y1502274I-203J1D01*
G01X177763D01*
G02X177560Y1502476I-1J202D01*
G01Y1503601D01*
G03X177532Y1503704I-200J1D01*
G02Y1505666I1642J981D01*
G03X177560Y1505769I-172J102D01*
G01Y1508720D01*
G03X177532Y1508823I-200J1D01*
G02Y1510785I1642J981D01*
G03X177560Y1510888I-172J102D01*
G37*
G36*
G01X298820D02*
Y1512014D01*
G02X299023Y1512216I203J-1D01*
G01X301843D01*
G02X302046Y1512014I1J-202D01*
G01Y1510888D01*
G03X302074Y1510785I200J-1D01*
G02Y1508823I-1642J-981D01*
G03X302046Y1508720I172J-102D01*
G01Y1505769D01*
G03X302074Y1505666I200J-1D01*
G02Y1503704I-1642J-981D01*
G03X302046Y1503601I172J-102D01*
G01Y1502476D01*
G02X301843Y1502274I-203J1D01*
G01X299023D01*
G02X298820Y1502476I-1J202D01*
G01Y1503601D01*
G03X298792Y1503704I-200J1D01*
G02Y1505666I1642J981D01*
G03X298820Y1505769I-172J102D01*
G01Y1508720D01*
G03X298792Y1508823I-200J1D01*
G02Y1510785I1642J981D01*
G03X298820Y1510888I-172J102D01*
G37*
G36*
G01X316144D02*
Y1512014D01*
G02X316346Y1512216I202J0D01*
G01X319166D01*
G02X319368Y1512014I0J-202D01*
G01Y1510888D01*
G03X319396Y1510785I200J-1D01*
G02X319668Y1509804I-1640J-983D01*
G02X319396Y1508823I-1912J2D01*
G03X319368Y1508720I172J-102D01*
G01Y1505769D01*
G03X319396Y1505666I200J-1D01*
G02X319668Y1504685I-1640J-983D01*
G02X319396Y1503704I-1912J2D01*
G03X319368Y1503601I172J-102D01*
G01Y1502476D01*
G02X319166Y1502274I-202J0D01*
G01X316346D01*
G02X316144Y1502476I0J202D01*
G01Y1503601D01*
G03X316116Y1503704I-200J1D01*
G02X315844Y1504685I1640J983D01*
G02X316116Y1505666I1912J-2D01*
G03X316144Y1505769I-172J102D01*
G01Y1508720D01*
G03X316116Y1508823I-200J1D01*
G02X315844Y1509804I1640J983D01*
G02X316116Y1510785I1912J-2D01*
G03X316144Y1510888I-172J102D01*
G37*
G36*
G01X333466D02*
Y1512014D01*
G02X333668Y1512216I202J0D01*
G01X336488D01*
G02X336690Y1512014I0J-202D01*
G01Y1510888D01*
G03X336718Y1510785I200J-1D01*
G02X336990Y1509804I-1640J-983D01*
G02X336718Y1508823I-1912J2D01*
G03X336690Y1508720I172J-102D01*
G01Y1505769D01*
G03X336718Y1505666I200J-1D01*
G02X336990Y1504685I-1640J-983D01*
G02X336718Y1503704I-1912J2D01*
G03X336690Y1503601I172J-102D01*
G01Y1502476D01*
G02X336488Y1502274I-202J0D01*
G01X333668D01*
G02X333466Y1502476I0J202D01*
G01Y1503601D01*
G03X333438Y1503704I-200J1D01*
G02X333166Y1504685I1640J983D01*
G02X333438Y1505666I1912J-2D01*
G03X333466Y1505769I-172J102D01*
G01Y1508720D01*
G03X333438Y1508823I-200J1D01*
G02X333166Y1509804I1640J983D01*
G02X333438Y1510785I1912J-2D01*
G03X333466Y1510888I-172J102D01*
G37*
G36*
G01X350788D02*
Y1512014D01*
G02X350991Y1512216I203J-1D01*
G01X353811D01*
G02X354014Y1512014I1J-202D01*
G01Y1510888D01*
G03X354042Y1510785I200J-1D01*
G02Y1508823I-1642J-981D01*
G03X354014Y1508720I172J-102D01*
G01Y1505769D01*
G03X354042Y1505666I200J-1D01*
G02Y1503704I-1642J-981D01*
G03X354014Y1503601I172J-102D01*
G01Y1502476D01*
G02X353811Y1502274I-203J1D01*
G01X350991D01*
G02X350788Y1502476I-1J202D01*
G01Y1503601D01*
G03X350760Y1503704I-200J1D01*
G02Y1505666I1642J981D01*
G03X350788Y1505769I-172J102D01*
G01Y1508720D01*
G03X350760Y1508823I-200J1D01*
G02Y1510785I1642J981D01*
G03X350788Y1510888I-172J102D01*
G37*
G36*
G01X116930Y1515218D02*
Y1516344D01*
G02X117133Y1516546I203J-1D01*
G01X119953D01*
G02X120156Y1516344I1J-202D01*
G01Y1515218D01*
G03X120184Y1515115I200J-1D01*
G02Y1513153I-1642J-981D01*
G03X120156Y1513050I172J-102D01*
G01Y1510100D01*
G03X120184Y1509997I200J-1D01*
G02Y1508035I-1642J-981D01*
G03X120156Y1507932I172J-102D01*
G01Y1506806D01*
G02X119953Y1506604I-203J1D01*
G01X117133D01*
G02X116930Y1506806I-1J202D01*
G01Y1507932D01*
G03X116902Y1508035I-200J1D01*
G02Y1509997I1642J981D01*
G03X116930Y1510100I-172J102D01*
G01Y1513050D01*
G03X116902Y1513153I-200J1D01*
G02Y1515115I1642J981D01*
G03X116930Y1515218I-172J102D01*
G37*
G36*
G01X134254D02*
Y1516344D01*
G02X134456Y1516546I202J0D01*
G01X137276D01*
G02X137478Y1516344I0J-202D01*
G01Y1515218D01*
G03X137506Y1515115I200J-1D01*
G02X137778Y1514134I-1640J-983D01*
G02X137506Y1513153I-1912J2D01*
G03X137478Y1513050I172J-102D01*
G01Y1510100D01*
G03X137506Y1509997I200J-1D01*
G02X137778Y1509016I-1640J-983D01*
G02X137506Y1508035I-1912J2D01*
G03X137478Y1507932I172J-102D01*
G01Y1506806D01*
G02X137276Y1506604I-202J0D01*
G01X134456D01*
G02X134254Y1506806I0J202D01*
G01Y1507932D01*
G03X134226Y1508035I-200J1D01*
G02X133954Y1509016I1640J983D01*
G02X134226Y1509997I1912J-2D01*
G03X134254Y1510100I-172J102D01*
G01Y1513050D01*
G03X134226Y1513153I-200J1D01*
G02X133954Y1514134I1640J983D01*
G02X134226Y1515115I1912J-2D01*
G03X134254Y1515218I-172J102D01*
G37*
G36*
G01X151576D02*
Y1516344D01*
G02X151779Y1516546I203J-1D01*
G01X154599D01*
G02X154802Y1516344I1J-202D01*
G01Y1515218D01*
G03X154830Y1515115I200J-1D01*
G02Y1513153I-1642J-981D01*
G03X154802Y1513050I172J-102D01*
G01Y1510100D01*
G03X154830Y1509997I200J-1D01*
G02Y1508035I-1642J-981D01*
G03X154802Y1507932I172J-102D01*
G01Y1506806D01*
G02X154599Y1506604I-203J1D01*
G01X151779D01*
G02X151576Y1506806I-1J202D01*
G01Y1507932D01*
G03X151548Y1508035I-200J1D01*
G02Y1509997I1642J981D01*
G03X151576Y1510100I-172J102D01*
G01Y1513050D01*
G03X151548Y1513153I-200J1D01*
G02Y1515115I1642J981D01*
G03X151576Y1515218I-172J102D01*
G37*
G36*
G01X168900D02*
Y1516344D01*
G02X169102Y1516546I202J0D01*
G01X171922D01*
G02X172124Y1516344I0J-202D01*
G01Y1515218D01*
G03X172152Y1515115I200J-1D01*
G02X172424Y1514134I-1640J-983D01*
G02X172152Y1513153I-1912J2D01*
G03X172124Y1513050I172J-102D01*
G01Y1510100D01*
G03X172152Y1509997I200J-1D01*
G02X172424Y1509016I-1640J-983D01*
G02X172152Y1508035I-1912J2D01*
G03X172124Y1507932I172J-102D01*
G01Y1506806D01*
G02X171922Y1506604I-202J0D01*
G01X169102D01*
G02X168900Y1506806I0J202D01*
G01Y1507932D01*
G03X168872Y1508035I-200J1D01*
G02X168600Y1509016I1640J983D01*
G02X168872Y1509997I1912J-2D01*
G03X168900Y1510100I-172J102D01*
G01Y1513050D01*
G03X168872Y1513153I-200J1D01*
G02X168600Y1514134I1640J983D01*
G02X168872Y1515115I1912J-2D01*
G03X168900Y1515218I-172J102D01*
G37*
G36*
G01X186222D02*
Y1516344D01*
G02X186425Y1516546I203J-1D01*
G01X189245D01*
G02X189448Y1516344I1J-202D01*
G01Y1515218D01*
G03X189476Y1515115I200J-1D01*
G02Y1513153I-1642J-981D01*
G03X189448Y1513050I172J-102D01*
G01Y1510100D01*
G03X189476Y1509997I200J-1D01*
G02Y1508035I-1642J-981D01*
G03X189448Y1507932I172J-102D01*
G01Y1506806D01*
G02X189245Y1506604I-203J1D01*
G01X186425D01*
G02X186222Y1506806I-1J202D01*
G01Y1507932D01*
G03X186194Y1508035I-200J1D01*
G02Y1509997I1642J981D01*
G03X186222Y1510100I-172J102D01*
G01Y1513050D01*
G03X186194Y1513153I-200J1D01*
G02Y1515115I1642J981D01*
G03X186222Y1515218I-172J102D01*
G37*
G36*
G01X290158D02*
Y1516344D01*
G02X290361Y1516546I203J-1D01*
G01X293181D01*
G02X293384Y1516344I1J-202D01*
G01Y1515218D01*
G03X293412Y1515115I200J-1D01*
G02Y1513153I-1642J-981D01*
G03X293384Y1513050I172J-102D01*
G01Y1510100D01*
G03X293412Y1509997I200J-1D01*
G02Y1508035I-1642J-981D01*
G03X293384Y1507932I172J-102D01*
G01Y1506806D01*
G02X293181Y1506604I-203J1D01*
G01X290361D01*
G02X290158Y1506806I-1J202D01*
G01Y1507932D01*
G03X290130Y1508035I-200J1D01*
G02Y1509997I1642J981D01*
G03X290158Y1510100I-172J102D01*
G01Y1513050D01*
G03X290130Y1513153I-200J1D01*
G02Y1515115I1642J981D01*
G03X290158Y1515218I-172J102D01*
G37*
G36*
G01X307482D02*
Y1516344D01*
G02X307684Y1516546I202J0D01*
G01X310504D01*
G02X310706Y1516344I0J-202D01*
G01Y1515218D01*
G03X310734Y1515115I200J-1D01*
G02X311006Y1514134I-1640J-983D01*
G02X310734Y1513153I-1912J2D01*
G03X310706Y1513050I172J-102D01*
G01Y1510100D01*
G03X310734Y1509997I200J-1D01*
G02X311006Y1509016I-1640J-983D01*
G02X310734Y1508035I-1912J2D01*
G03X310706Y1507932I172J-102D01*
G01Y1506806D01*
G02X310504Y1506604I-202J0D01*
G01X307684D01*
G02X307482Y1506806I0J202D01*
G01Y1507932D01*
G03X307454Y1508035I-200J1D01*
G02X307182Y1509016I1640J983D01*
G02X307454Y1509997I1912J-2D01*
G03X307482Y1510100I-172J102D01*
G01Y1513050D01*
G03X307454Y1513153I-200J1D01*
G02X307182Y1514134I1640J983D01*
G02X307454Y1515115I1912J-2D01*
G03X307482Y1515218I-172J102D01*
G37*
G36*
G01X324804D02*
Y1516344D01*
G02X325007Y1516546I203J-1D01*
G01X327827D01*
G02X328030Y1516344I1J-202D01*
G01Y1515218D01*
G03X328058Y1515115I200J-1D01*
G02Y1513153I-1642J-981D01*
G03X328030Y1513050I172J-102D01*
G01Y1510100D01*
G03X328058Y1509997I200J-1D01*
G02Y1508035I-1642J-981D01*
G03X328030Y1507932I172J-102D01*
G01Y1506806D01*
G02X327827Y1506604I-203J1D01*
G01X325007D01*
G02X324804Y1506806I-1J202D01*
G01Y1507932D01*
G03X324776Y1508035I-200J1D01*
G02Y1509997I1642J981D01*
G03X324804Y1510100I-172J102D01*
G01Y1513050D01*
G03X324776Y1513153I-200J1D01*
G02Y1515115I1642J981D01*
G03X324804Y1515218I-172J102D01*
G37*
G36*
G01X342128D02*
Y1516344D01*
G02X342330Y1516546I202J0D01*
G01X345150D01*
G02X345352Y1516344I0J-202D01*
G01Y1515218D01*
G03X345380Y1515115I200J-1D01*
G02X345652Y1514134I-1640J-983D01*
G02X345380Y1513153I-1912J2D01*
G03X345352Y1513050I172J-102D01*
G01Y1510100D01*
G03X345380Y1509997I200J-1D01*
G02X345652Y1509016I-1640J-983D01*
G02X345380Y1508035I-1912J2D01*
G03X345352Y1507932I172J-102D01*
G01Y1506806D01*
G02X345150Y1506604I-202J0D01*
G01X342330D01*
G02X342128Y1506806I0J202D01*
G01Y1507932D01*
G03X342100Y1508035I-200J1D01*
G02X341828Y1509016I1640J983D01*
G02X342100Y1509997I1912J-2D01*
G03X342128Y1510100I-172J102D01*
G01Y1513050D01*
G03X342100Y1513153I-200J1D01*
G02X341828Y1514134I1640J983D01*
G02X342100Y1515115I1912J-2D01*
G03X342128Y1515218I-172J102D01*
G37*
G36*
G01X359450D02*
Y1516344D01*
G02X359653Y1516546I203J-1D01*
G01X362473D01*
G02X362676Y1516344I1J-202D01*
G01Y1515218D01*
G03X362704Y1515115I200J-1D01*
G02Y1513153I-1642J-981D01*
G03X362676Y1513050I172J-102D01*
G01Y1510100D01*
G03X362704Y1509997I200J-1D01*
G02Y1508035I-1642J-981D01*
G03X362676Y1507932I172J-102D01*
G01Y1506806D01*
G02X362473Y1506604I-203J1D01*
G01X359653D01*
G02X359450Y1506806I-1J202D01*
G01Y1507932D01*
G03X359422Y1508035I-200J1D01*
G02Y1509997I1642J981D01*
G03X359450Y1510100I-172J102D01*
G01Y1513050D01*
G03X359422Y1513153I-200J1D01*
G02Y1515115I1642J981D01*
G03X359450Y1515218I-172J102D01*
G37*
G36*
G01X570930Y1521462D02*
G02X573934I1502J0D01*
G02X573606Y1520525I-1502J0D01*
G01X573605Y1520524D01*
G03X573564Y1520370I157J-124D01*
G01X573614Y1520037D01*
X573658Y1519968D01*
X573693Y1519944D01*
G02X574351Y1518702I-843J-1242D01*
G02X571347I-1502J0D01*
G02X571675Y1519639I1502J0D01*
G01X571676Y1519640D01*
G03X571717Y1519794I-157J124D01*
G01X571667Y1520127D01*
X571623Y1520196D01*
X571588Y1520220D01*
G02X570930Y1521462I843J1242D01*
G37*
G36*
G01X392889Y1537786D02*
G02X395893I1502J0D01*
G02X395523Y1536799I-1501J0D01*
G01Y1536798D01*
X395522D01*
G03X395474Y1536668I152J-130D01*
G01Y1536404D01*
G03X395522Y1536274I200J0D01*
G01X395523Y1536273D01*
G02X395893Y1535286I-1131J-987D01*
G02X392889I-1502J0D01*
G02X393259Y1536273I1501J0D01*
G01Y1536274D01*
X393260D01*
G03X393308Y1536404I-152J130D01*
G01Y1536668D01*
G03X393260Y1536798I-200J0D01*
G01X393259Y1536799D01*
G02X392889Y1537786I1131J987D01*
G37*
G36*
G01X186222Y1571518D02*
Y1572644D01*
G02X186425Y1572846I203J-1D01*
G01X189245D01*
G02X189448Y1572644I1J-202D01*
G01Y1571518D01*
G03X189476Y1571415I200J-1D01*
G02Y1569453I-1642J-981D01*
G03X189448Y1569350I172J-102D01*
G01Y1566399D01*
G03X189476Y1566296I200J-1D01*
G02Y1564334I-1642J-981D01*
G03X189448Y1564231I172J-102D01*
G01Y1563106D01*
G02X189245Y1562904I-203J1D01*
G01X186425D01*
G02X186222Y1563106I-1J202D01*
G01Y1564231D01*
G03X186194Y1564334I-200J1D01*
G02Y1566296I1642J981D01*
G03X186222Y1566399I-172J102D01*
G01Y1569350D01*
G03X186194Y1569453I-200J1D01*
G02Y1571415I1642J981D01*
G03X186222Y1571518I-172J102D01*
G37*
G36*
G01X359450D02*
Y1572644D01*
G02X359653Y1572846I203J-1D01*
G01X362473D01*
G02X362676Y1572644I1J-202D01*
G01Y1571518D01*
G03X362704Y1571415I200J-1D01*
G02Y1569453I-1642J-981D01*
G03X362676Y1569350I172J-102D01*
G01Y1566399D01*
G03X362704Y1566296I200J-1D01*
G02Y1564334I-1642J-981D01*
G03X362676Y1564231I172J-102D01*
G01Y1563106D01*
G02X362473Y1562904I-203J1D01*
G01X359653D01*
G02X359450Y1563106I-1J202D01*
G01Y1564231D01*
G03X359422Y1564334I-200J1D01*
G02Y1566296I1642J981D01*
G03X359450Y1566399I-172J102D01*
G01Y1569350D01*
G03X359422Y1569453I-200J1D01*
G02Y1571415I1642J981D01*
G03X359450Y1571518I-172J102D01*
G37*
G36*
G01X627954Y1582541D02*
Y1583667D01*
G02X628157Y1583870I203J0D01*
G01X630977D01*
G02X631180Y1583667I0J-203D01*
G01Y1582541D01*
G03X631208Y1582438I200J-1D01*
G02Y1580476I-1642J-981D01*
G03X631180Y1580373I172J-102D01*
G01Y1577423D01*
G03X631208Y1577320I200J-1D01*
G02Y1575358I-1642J-981D01*
G03X631180Y1575255I172J-102D01*
G01Y1574129D01*
G02X630977Y1573926I-203J0D01*
G01X628157D01*
G02X627954Y1574129I0J203D01*
G01Y1575255D01*
G03X627926Y1575358I-200J1D01*
G02Y1577320I1642J981D01*
G03X627954Y1577423I-172J102D01*
G01Y1580373D01*
G03X627926Y1580476I-200J1D01*
G02Y1582438I1642J981D01*
G03X627954Y1582541I-172J102D01*
G37*
G36*
G01X645278D02*
Y1583667D01*
G02X645480Y1583870I202J1D01*
G01X648300D01*
G02X648502Y1583667I-1J-203D01*
G01Y1582541D01*
G03X648530Y1582438I200J-1D01*
G02X648802Y1581457I-1640J-983D01*
G02X648530Y1580476I-1912J2D01*
G03X648502Y1580373I172J-102D01*
G01Y1577423D01*
G03X648530Y1577320I200J-1D01*
G02X648802Y1576339I-1640J-983D01*
G02X648530Y1575358I-1912J2D01*
G03X648502Y1575255I172J-102D01*
G01Y1574129D01*
G02X648300Y1573926I-202J-1D01*
G01X645480D01*
G02X645278Y1574129I1J203D01*
G01Y1575255D01*
G03X645250Y1575358I-200J1D01*
G02X644978Y1576339I1640J983D01*
G02X645250Y1577320I1912J-2D01*
G03X645278Y1577423I-172J102D01*
G01Y1580373D01*
G03X645250Y1580476I-200J1D01*
G02X644978Y1581457I1640J983D01*
G02X645250Y1582438I1912J-2D01*
G03X645278Y1582541I-172J102D01*
G37*
G36*
G01X662600D02*
Y1583667D01*
G02X662803Y1583870I203J0D01*
G01X665623D01*
G02X665826Y1583667I0J-203D01*
G01Y1582541D01*
G03X665854Y1582438I200J-1D01*
G02Y1580476I-1642J-981D01*
G03X665826Y1580373I172J-102D01*
G01Y1577423D01*
G03X665854Y1577320I200J-1D01*
G02Y1575358I-1642J-981D01*
G03X665826Y1575255I172J-102D01*
G01Y1574129D01*
G02X665623Y1573926I-203J0D01*
G01X662803D01*
G02X662600Y1574129I0J203D01*
G01Y1575255D01*
G03X662572Y1575358I-200J1D01*
G02Y1577320I1642J981D01*
G03X662600Y1577423I-172J102D01*
G01Y1580373D01*
G03X662572Y1580476I-200J1D01*
G02Y1582438I1642J981D01*
G03X662600Y1582541I-172J102D01*
G37*
G36*
G01X679922D02*
Y1583667D01*
G02X680125Y1583870I203J0D01*
G01X682945D01*
G02X683148Y1583667I0J-203D01*
G01Y1582541D01*
G03X683176Y1582438I200J-1D01*
G02Y1580476I-1642J-981D01*
G03X683148Y1580373I172J-102D01*
G01Y1577423D01*
G03X683176Y1577320I200J-1D01*
G02Y1575358I-1642J-981D01*
G03X683148Y1575255I172J-102D01*
G01Y1574129D01*
G02X682945Y1573926I-203J0D01*
G01X680125D01*
G02X679922Y1574129I0J203D01*
G01Y1575255D01*
G03X679894Y1575358I-200J1D01*
G02Y1577320I1642J981D01*
G03X679922Y1577423I-172J102D01*
G01Y1580373D01*
G03X679894Y1580476I-200J1D01*
G02Y1582438I1642J981D01*
G03X679922Y1582541I-172J102D01*
G37*
G36*
G01X56517Y1584436D02*
X56811D01*
G03X56958Y1584501I-1J200D01*
G02X59170I1106J-1017D01*
G03X59317Y1584436I148J135D01*
G01X59611D01*
G03X59758Y1584501I-1J200D01*
G02X60864Y1584986I1106J-1019D01*
G02Y1581982I0J-1502D01*
G02X59758Y1582467I0J1504D01*
G03X59611Y1582532I-148J-135D01*
G01X59317D01*
G03X59170Y1582467I1J-200D01*
G02X56958I-1106J1017D01*
G03X56811Y1582532I-148J-135D01*
G01X56517D01*
G03X56370Y1582467I1J-200D01*
G02X55264Y1581982I-1106J1019D01*
G02Y1584986I0J1502D01*
G02X56370Y1584501I0J-1504D01*
G03X56517Y1584436I148J135D01*
G37*
G36*
G01X636616Y1586872D02*
Y1587998D01*
G02X636818Y1588200I202J0D01*
G01X639638D01*
G02X639840Y1587998I0J-202D01*
G01Y1586872D01*
G03X639868Y1586769I200J-1D01*
G02X640140Y1585788I-1640J-983D01*
G02X639868Y1584807I-1912J2D01*
G03X639840Y1584704I172J-102D01*
G01Y1581754D01*
G03X639868Y1581651I200J-1D01*
G02X640140Y1580670I-1640J-983D01*
G02X639868Y1579689I-1912J2D01*
G03X639840Y1579586I172J-102D01*
G01Y1578460D01*
G02X639638Y1578258I-202J0D01*
G01X636818D01*
G02X636616Y1578460I0J202D01*
G01Y1579586D01*
G03X636588Y1579689I-200J1D01*
G02X636316Y1580670I1640J983D01*
G02X636588Y1581651I1912J-2D01*
G03X636616Y1581754I-172J102D01*
G01Y1584704D01*
G03X636588Y1584807I-200J1D01*
G02X636316Y1585788I1640J983D01*
G02X636588Y1586769I1912J-2D01*
G03X636616Y1586872I-172J102D01*
G37*
G36*
G01X653938D02*
Y1587998D01*
G02X654141Y1588200I203J-1D01*
G01X656961D01*
G02X657164Y1587998I1J-202D01*
G01Y1586872D01*
G03X657192Y1586769I200J-1D01*
G02Y1584807I-1642J-981D01*
G03X657164Y1584704I172J-102D01*
G01Y1581754D01*
G03X657192Y1581651I200J-1D01*
G02Y1579689I-1642J-981D01*
G03X657164Y1579586I172J-102D01*
G01Y1578460D01*
G02X656961Y1578258I-203J1D01*
G01X654141D01*
G02X653938Y1578460I-1J202D01*
G01Y1579586D01*
G03X653910Y1579689I-200J1D01*
G02Y1581651I1642J981D01*
G03X653938Y1581754I-172J102D01*
G01Y1584704D01*
G03X653910Y1584807I-200J1D01*
G02Y1586769I1642J981D01*
G03X653938Y1586872I-172J102D01*
G37*
G36*
G01X671262D02*
Y1587998D01*
G02X671464Y1588200I202J0D01*
G01X674284D01*
G02X674486Y1587998I0J-202D01*
G01Y1586872D01*
G03X674514Y1586769I200J-1D01*
G02X674786Y1585788I-1640J-983D01*
G02X674514Y1584807I-1912J2D01*
G03X674486Y1584704I172J-102D01*
G01Y1581754D01*
G03X674514Y1581651I200J-1D01*
G02X674786Y1580670I-1640J-983D01*
G02X674514Y1579689I-1912J2D01*
G03X674486Y1579586I172J-102D01*
G01Y1578460D01*
G02X674284Y1578258I-202J0D01*
G01X671464D01*
G02X671262Y1578460I0J202D01*
G01Y1579586D01*
G03X671234Y1579689I-200J1D01*
G02X670962Y1580670I1640J983D01*
G02X671234Y1581651I1912J-2D01*
G03X671262Y1581754I-172J102D01*
G01Y1584704D01*
G03X671234Y1584807I-200J1D01*
G02X670962Y1585788I1640J983D01*
G02X671234Y1586769I1912J-2D01*
G03X671262Y1586872I-172J102D01*
G37*
G36*
G01X688584D02*
Y1587998D01*
G02X688787Y1588200I203J-1D01*
G01X691607D01*
G02X691810Y1587998I1J-202D01*
G01Y1586872D01*
G03X691838Y1586769I200J-1D01*
G02Y1584807I-1642J-981D01*
G03X691810Y1584704I172J-102D01*
G01Y1581754D01*
G03X691838Y1581651I200J-1D01*
G02Y1579689I-1642J-981D01*
G03X691810Y1579586I172J-102D01*
G01Y1578460D01*
G02X691607Y1578258I-203J1D01*
G01X688787D01*
G02X688584Y1578460I-1J202D01*
G01Y1579586D01*
G03X688556Y1579689I-200J1D01*
G02Y1581651I1642J981D01*
G03X688584Y1581754I-172J102D01*
G01Y1584704D01*
G03X688556Y1584807I-200J1D01*
G02Y1586769I1642J981D01*
G03X688584Y1586872I-172J102D01*
G37*
G36*
G01X108270Y1597895D02*
Y1599021D01*
G02X108472Y1599224I202J1D01*
G01X111292D01*
G02X111494Y1599021I-1J-203D01*
G01Y1597895D01*
G03X111522Y1597792I200J-1D01*
G02X111794Y1596811I-1640J-983D01*
G02X111522Y1595830I-1912J2D01*
G03X111494Y1595727I172J-102D01*
G01Y1592777D01*
G03X111522Y1592674I200J-1D01*
G02X111794Y1591693I-1640J-983D01*
G02X111522Y1590712I-1912J2D01*
G03X111494Y1590609I172J-102D01*
G01Y1589483D01*
G02X111292Y1589280I-202J-1D01*
G01X108472D01*
G02X108270Y1589483I1J203D01*
G01Y1590609D01*
G03X108242Y1590712I-200J1D01*
G02X107970Y1591693I1640J983D01*
G02X108242Y1592674I1912J-2D01*
G03X108270Y1592777I-172J102D01*
G01Y1595727D01*
G03X108242Y1595830I-200J1D01*
G02X107970Y1596811I1640J983D01*
G02X108242Y1597792I1912J-2D01*
G03X108270Y1597895I-172J102D01*
G37*
G36*
G01X125592D02*
Y1599021D01*
G02X125795Y1599224I203J0D01*
G01X128615D01*
G02X128818Y1599021I0J-203D01*
G01Y1597895D01*
G03X128846Y1597792I200J-1D01*
G02Y1595830I-1642J-981D01*
G03X128818Y1595727I172J-102D01*
G01Y1592777D01*
G03X128846Y1592674I200J-1D01*
G02Y1590712I-1642J-981D01*
G03X128818Y1590609I172J-102D01*
G01Y1589483D01*
G02X128615Y1589280I-203J0D01*
G01X125795D01*
G02X125592Y1589483I0J203D01*
G01Y1590609D01*
G03X125564Y1590712I-200J1D01*
G02Y1592674I1642J981D01*
G03X125592Y1592777I-172J102D01*
G01Y1595727D01*
G03X125564Y1595830I-200J1D01*
G02Y1597792I1642J981D01*
G03X125592Y1597895I-172J102D01*
G37*
G36*
G01X142916D02*
Y1599021D01*
G02X143118Y1599224I202J1D01*
G01X145938D01*
G02X146140Y1599021I-1J-203D01*
G01Y1597895D01*
G03X146168Y1597792I200J-1D01*
G02X146440Y1596811I-1640J-983D01*
G02X146168Y1595830I-1912J2D01*
G03X146140Y1595727I172J-102D01*
G01Y1592777D01*
G03X146168Y1592674I200J-1D01*
G02X146440Y1591693I-1640J-983D01*
G02X146168Y1590712I-1912J2D01*
G03X146140Y1590609I172J-102D01*
G01Y1589483D01*
G02X145938Y1589280I-202J-1D01*
G01X143118D01*
G02X142916Y1589483I1J203D01*
G01Y1590609D01*
G03X142888Y1590712I-200J1D01*
G02X142616Y1591693I1640J983D01*
G02X142888Y1592674I1912J-2D01*
G03X142916Y1592777I-172J102D01*
G01Y1595727D01*
G03X142888Y1595830I-200J1D01*
G02X142616Y1596811I1640J983D01*
G02X142888Y1597792I1912J-2D01*
G03X142916Y1597895I-172J102D01*
G37*
G36*
G01X160238D02*
Y1599021D01*
G02X160440Y1599224I202J1D01*
G01X163260D01*
G02X163462Y1599021I-1J-203D01*
G01Y1597895D01*
G03X163490Y1597792I200J-1D01*
G02X163762Y1596811I-1640J-983D01*
G02X163490Y1595830I-1912J2D01*
G03X163462Y1595727I172J-102D01*
G01Y1592777D01*
G03X163490Y1592674I200J-1D01*
G02X163762Y1591693I-1640J-983D01*
G02X163490Y1590712I-1912J2D01*
G03X163462Y1590609I172J-102D01*
G01Y1589483D01*
G02X163260Y1589280I-202J-1D01*
G01X160440D01*
G02X160238Y1589483I1J203D01*
G01Y1590609D01*
G03X160210Y1590712I-200J1D01*
G02X159938Y1591693I1640J983D01*
G02X160210Y1592674I1912J-2D01*
G03X160238Y1592777I-172J102D01*
G01Y1595727D01*
G03X160210Y1595830I-200J1D01*
G02X159938Y1596811I1640J983D01*
G02X160210Y1597792I1912J-2D01*
G03X160238Y1597895I-172J102D01*
G37*
G36*
G01X627954D02*
Y1599021D01*
G02X628157Y1599224I203J0D01*
G01X630977D01*
G02X631180Y1599021I0J-203D01*
G01Y1597895D01*
G03X631208Y1597792I200J-1D01*
G02Y1595830I-1642J-981D01*
G03X631180Y1595727I172J-102D01*
G01Y1592777D01*
G03X631208Y1592674I200J-1D01*
G02Y1590712I-1642J-981D01*
G03X631180Y1590609I172J-102D01*
G01Y1589483D01*
G02X630977Y1589280I-203J0D01*
G01X628157D01*
G02X627954Y1589483I0J203D01*
G01Y1590609D01*
G03X627926Y1590712I-200J1D01*
G02Y1592674I1642J981D01*
G03X627954Y1592777I-172J102D01*
G01Y1595727D01*
G03X627926Y1595830I-200J1D01*
G02Y1597792I1642J981D01*
G03X627954Y1597895I-172J102D01*
G37*
G36*
G01X645278D02*
Y1599021D01*
G02X645480Y1599224I202J1D01*
G01X648300D01*
G02X648502Y1599021I-1J-203D01*
G01Y1597895D01*
G03X648530Y1597792I200J-1D01*
G02X648802Y1596811I-1640J-983D01*
G02X648530Y1595830I-1912J2D01*
G03X648502Y1595727I172J-102D01*
G01Y1592777D01*
G03X648530Y1592674I200J-1D01*
G02X648802Y1591693I-1640J-983D01*
G02X648530Y1590712I-1912J2D01*
G03X648502Y1590609I172J-102D01*
G01Y1589483D01*
G02X648300Y1589280I-202J-1D01*
G01X645480D01*
G02X645278Y1589483I1J203D01*
G01Y1590609D01*
G03X645250Y1590712I-200J1D01*
G02X644978Y1591693I1640J983D01*
G02X645250Y1592674I1912J-2D01*
G03X645278Y1592777I-172J102D01*
G01Y1595727D01*
G03X645250Y1595830I-200J1D01*
G02X644978Y1596811I1640J983D01*
G02X645250Y1597792I1912J-2D01*
G03X645278Y1597895I-172J102D01*
G37*
G36*
G01X662600D02*
Y1599021D01*
G02X662803Y1599224I203J0D01*
G01X665623D01*
G02X665826Y1599021I0J-203D01*
G01Y1597895D01*
G03X665854Y1597792I200J-1D01*
G02Y1595830I-1642J-981D01*
G03X665826Y1595727I172J-102D01*
G01Y1592777D01*
G03X665854Y1592674I200J-1D01*
G02Y1590712I-1642J-981D01*
G03X665826Y1590609I172J-102D01*
G01Y1589483D01*
G02X665623Y1589280I-203J0D01*
G01X662803D01*
G02X662600Y1589483I0J203D01*
G01Y1590609D01*
G03X662572Y1590712I-200J1D01*
G02Y1592674I1642J981D01*
G03X662600Y1592777I-172J102D01*
G01Y1595727D01*
G03X662572Y1595830I-200J1D01*
G02Y1597792I1642J981D01*
G03X662600Y1597895I-172J102D01*
G37*
G36*
G01X679922D02*
Y1599021D01*
G02X680125Y1599224I203J0D01*
G01X682945D01*
G02X683148Y1599021I0J-203D01*
G01Y1597895D01*
G03X683176Y1597792I200J-1D01*
G02Y1595830I-1642J-981D01*
G03X683148Y1595727I172J-102D01*
G01Y1592777D01*
G03X683176Y1592674I200J-1D01*
G02Y1590712I-1642J-981D01*
G03X683148Y1590609I172J-102D01*
G01Y1589483D01*
G02X682945Y1589280I-203J0D01*
G01X680125D01*
G02X679922Y1589483I0J203D01*
G01Y1590609D01*
G03X679894Y1590712I-200J1D01*
G02Y1592674I1642J981D01*
G03X679922Y1592777I-172J102D01*
G01Y1595727D01*
G03X679894Y1595830I-200J1D01*
G02Y1597792I1642J981D01*
G03X679922Y1597895I-172J102D01*
G37*
G36*
G01X116930Y1602226D02*
Y1603352D01*
G02X117133Y1603554I203J-1D01*
G01X119953D01*
G02X120156Y1603352I1J-202D01*
G01Y1602226D01*
G03X120184Y1602123I200J-1D01*
G02Y1600161I-1642J-981D01*
G03X120156Y1600058I172J-102D01*
G01Y1597108D01*
G03X120184Y1597005I200J-1D01*
G02Y1595043I-1642J-981D01*
G03X120156Y1594940I172J-102D01*
G01Y1593814D01*
G02X119953Y1593612I-203J1D01*
G01X117133D01*
G02X116930Y1593814I-1J202D01*
G01Y1594940D01*
G03X116902Y1595043I-200J1D01*
G02Y1597005I1642J981D01*
G03X116930Y1597108I-172J102D01*
G01Y1600058D01*
G03X116902Y1600161I-200J1D01*
G02Y1602123I1642J981D01*
G03X116930Y1602226I-172J102D01*
G37*
G36*
G01X134254D02*
Y1603352D01*
G02X134456Y1603554I202J0D01*
G01X137276D01*
G02X137478Y1603352I0J-202D01*
G01Y1602226D01*
G03X137506Y1602123I200J-1D01*
G02X137778Y1601142I-1640J-983D01*
G02X137506Y1600161I-1912J2D01*
G03X137478Y1600058I172J-102D01*
G01Y1597108D01*
G03X137506Y1597005I200J-1D01*
G02X137778Y1596024I-1640J-983D01*
G02X137506Y1595043I-1912J2D01*
G03X137478Y1594940I172J-102D01*
G01Y1593814D01*
G02X137276Y1593612I-202J0D01*
G01X134456D01*
G02X134254Y1593814I0J202D01*
G01Y1594940D01*
G03X134226Y1595043I-200J1D01*
G02X133954Y1596024I1640J983D01*
G02X134226Y1597005I1912J-2D01*
G03X134254Y1597108I-172J102D01*
G01Y1600058D01*
G03X134226Y1600161I-200J1D01*
G02X133954Y1601142I1640J983D01*
G02X134226Y1602123I1912J-2D01*
G03X134254Y1602226I-172J102D01*
G37*
G36*
G01X151576D02*
Y1603352D01*
G02X151779Y1603554I203J-1D01*
G01X154599D01*
G02X154802Y1603352I1J-202D01*
G01Y1602226D01*
G03X154830Y1602123I200J-1D01*
G02Y1600161I-1642J-981D01*
G03X154802Y1600058I172J-102D01*
G01Y1597108D01*
G03X154830Y1597005I200J-1D01*
G02Y1595043I-1642J-981D01*
G03X154802Y1594940I172J-102D01*
G01Y1593814D01*
G02X154599Y1593612I-203J1D01*
G01X151779D01*
G02X151576Y1593814I-1J202D01*
G01Y1594940D01*
G03X151548Y1595043I-200J1D01*
G02Y1597005I1642J981D01*
G03X151576Y1597108I-172J102D01*
G01Y1600058D01*
G03X151548Y1600161I-200J1D01*
G02Y1602123I1642J981D01*
G03X151576Y1602226I-172J102D01*
G37*
G36*
G01X168900D02*
Y1603352D01*
G02X169102Y1603554I202J0D01*
G01X171922D01*
G02X172124Y1603352I0J-202D01*
G01Y1602226D01*
G03X172152Y1602123I200J-1D01*
G02X172424Y1601142I-1640J-983D01*
G02X172152Y1600161I-1912J2D01*
G03X172124Y1600058I172J-102D01*
G01Y1597108D01*
G03X172152Y1597005I200J-1D01*
G02X172424Y1596024I-1640J-983D01*
G02X172152Y1595043I-1912J2D01*
G03X172124Y1594940I172J-102D01*
G01Y1593814D01*
G02X171922Y1593612I-202J0D01*
G01X169102D01*
G02X168900Y1593814I0J202D01*
G01Y1594940D01*
G03X168872Y1595043I-200J1D01*
G02X168600Y1596024I1640J983D01*
G02X168872Y1597005I1912J-2D01*
G03X168900Y1597108I-172J102D01*
G01Y1600058D01*
G03X168872Y1600161I-200J1D01*
G02X168600Y1601142I1640J983D01*
G02X168872Y1602123I1912J-2D01*
G03X168900Y1602226I-172J102D01*
G37*
G36*
G01X186222D02*
Y1603352D01*
G02X186425Y1603554I203J-1D01*
G01X189245D01*
G02X189448Y1603352I1J-202D01*
G01Y1602226D01*
G03X189476Y1602123I200J-1D01*
G02Y1600161I-1642J-981D01*
G03X189448Y1600058I172J-102D01*
G01Y1597108D01*
G03X189476Y1597005I200J-1D01*
G02Y1595043I-1642J-981D01*
G03X189448Y1594940I172J-102D01*
G01Y1593814D01*
G02X189245Y1593612I-203J1D01*
G01X186425D01*
G02X186222Y1593814I-1J202D01*
G01Y1594940D01*
G03X186194Y1595043I-200J1D01*
G02Y1597005I1642J981D01*
G03X186222Y1597108I-172J102D01*
G01Y1600058D01*
G03X186194Y1600161I-200J1D01*
G02Y1602123I1642J981D01*
G03X186222Y1602226I-172J102D01*
G37*
G36*
G01X359450D02*
Y1603352D01*
G02X359653Y1603554I203J-1D01*
G01X362473D01*
G02X362676Y1603352I1J-202D01*
G01Y1602226D01*
G03X362704Y1602123I200J-1D01*
G02Y1600161I-1642J-981D01*
G03X362676Y1600058I172J-102D01*
G01Y1597108D01*
G03X362704Y1597005I200J-1D01*
G02Y1595043I-1642J-981D01*
G03X362676Y1594940I172J-102D01*
G01Y1593814D01*
G02X362473Y1593612I-203J1D01*
G01X359653D01*
G02X359450Y1593814I-1J202D01*
G01Y1594940D01*
G03X359422Y1595043I-200J1D01*
G02Y1597005I1642J981D01*
G03X359450Y1597108I-172J102D01*
G01Y1600058D01*
G03X359422Y1600161I-200J1D01*
G02Y1602123I1642J981D01*
G03X359450Y1602226I-172J102D01*
G37*
G36*
G01X636616D02*
Y1603352D01*
G02X636818Y1603554I202J0D01*
G01X639638D01*
G02X639840Y1603352I0J-202D01*
G01Y1602226D01*
G03X639868Y1602123I200J-1D01*
G02X640140Y1601142I-1640J-983D01*
G02X639868Y1600161I-1912J2D01*
G03X639840Y1600058I172J-102D01*
G01Y1597108D01*
G03X639868Y1597005I200J-1D01*
G02X640140Y1596024I-1640J-983D01*
G02X639868Y1595043I-1912J2D01*
G03X639840Y1594940I172J-102D01*
G01Y1593814D01*
G02X639638Y1593612I-202J0D01*
G01X636818D01*
G02X636616Y1593814I0J202D01*
G01Y1594940D01*
G03X636588Y1595043I-200J1D01*
G02X636316Y1596024I1640J983D01*
G02X636588Y1597005I1912J-2D01*
G03X636616Y1597108I-172J102D01*
G01Y1600058D01*
G03X636588Y1600161I-200J1D01*
G02X636316Y1601142I1640J983D01*
G02X636588Y1602123I1912J-2D01*
G03X636616Y1602226I-172J102D01*
G37*
G36*
G01X653938D02*
Y1603352D01*
G02X654141Y1603554I203J-1D01*
G01X656961D01*
G02X657164Y1603352I1J-202D01*
G01Y1602226D01*
G03X657192Y1602123I200J-1D01*
G02Y1600161I-1642J-981D01*
G03X657164Y1600058I172J-102D01*
G01Y1597108D01*
G03X657192Y1597005I200J-1D01*
G02Y1595043I-1642J-981D01*
G03X657164Y1594940I172J-102D01*
G01Y1593814D01*
G02X656961Y1593612I-203J1D01*
G01X654141D01*
G02X653938Y1593814I-1J202D01*
G01Y1594940D01*
G03X653910Y1595043I-200J1D01*
G02Y1597005I1642J981D01*
G03X653938Y1597108I-172J102D01*
G01Y1600058D01*
G03X653910Y1600161I-200J1D01*
G02Y1602123I1642J981D01*
G03X653938Y1602226I-172J102D01*
G37*
G36*
G01X671262D02*
Y1603352D01*
G02X671464Y1603554I202J0D01*
G01X674284D01*
G02X674486Y1603352I0J-202D01*
G01Y1602226D01*
G03X674514Y1602123I200J-1D01*
G02X674786Y1601142I-1640J-983D01*
G02X674514Y1600161I-1912J2D01*
G03X674486Y1600058I172J-102D01*
G01Y1597108D01*
G03X674514Y1597005I200J-1D01*
G02X674786Y1596024I-1640J-983D01*
G02X674514Y1595043I-1912J2D01*
G03X674486Y1594940I172J-102D01*
G01Y1593814D01*
G02X674284Y1593612I-202J0D01*
G01X671464D01*
G02X671262Y1593814I0J202D01*
G01Y1594940D01*
G03X671234Y1595043I-200J1D01*
G02X670962Y1596024I1640J983D01*
G02X671234Y1597005I1912J-2D01*
G03X671262Y1597108I-172J102D01*
G01Y1600058D01*
G03X671234Y1600161I-200J1D01*
G02X670962Y1601142I1640J983D01*
G02X671234Y1602123I1912J-2D01*
G03X671262Y1602226I-172J102D01*
G37*
G36*
G01X688584D02*
Y1603352D01*
G02X688787Y1603554I203J-1D01*
G01X691607D01*
G02X691810Y1603352I1J-202D01*
G01Y1602226D01*
G03X691838Y1602123I200J-1D01*
G02Y1600161I-1642J-981D01*
G03X691810Y1600058I172J-102D01*
G01Y1597108D01*
G03X691838Y1597005I200J-1D01*
G02Y1595043I-1642J-981D01*
G03X691810Y1594940I172J-102D01*
G01Y1593814D01*
G02X691607Y1593612I-203J1D01*
G01X688787D01*
G02X688584Y1593814I-1J202D01*
G01Y1594940D01*
G03X688556Y1595043I-200J1D01*
G02Y1597005I1642J981D01*
G03X688584Y1597108I-172J102D01*
G01Y1600058D01*
G03X688556Y1600161I-200J1D01*
G02Y1602123I1642J981D01*
G03X688584Y1602226I-172J102D01*
G37*
G36*
G01X108270Y1613250D02*
Y1614376D01*
G02X108472Y1614578I202J0D01*
G01X111292D01*
G02X111494Y1614376I0J-202D01*
G01Y1613250D01*
G03X111522Y1613147I200J-1D01*
G02X111794Y1612166I-1640J-983D01*
G02X111522Y1611185I-1912J2D01*
G03X111494Y1611082I172J-102D01*
G01Y1608132D01*
G03X111522Y1608029I200J-1D01*
G02X111794Y1607048I-1640J-983D01*
G02X111522Y1606067I-1912J2D01*
G03X111494Y1605964I172J-102D01*
G01Y1604838D01*
G02X111292Y1604636I-202J0D01*
G01X108472D01*
G02X108270Y1604838I0J202D01*
G01Y1605964D01*
G03X108242Y1606067I-200J1D01*
G02X107970Y1607048I1640J983D01*
G02X108242Y1608029I1912J-2D01*
G03X108270Y1608132I-172J102D01*
G01Y1611082D01*
G03X108242Y1611185I-200J1D01*
G02X107970Y1612166I1640J983D01*
G02X108242Y1613147I1912J-2D01*
G03X108270Y1613250I-172J102D01*
G37*
G36*
G01X125592D02*
Y1614376D01*
G02X125795Y1614578I203J-1D01*
G01X128615D01*
G02X128818Y1614376I1J-202D01*
G01Y1613250D01*
G03X128846Y1613147I200J-1D01*
G02Y1611185I-1642J-981D01*
G03X128818Y1611082I172J-102D01*
G01Y1608132D01*
G03X128846Y1608029I200J-1D01*
G02Y1606067I-1642J-981D01*
G03X128818Y1605964I172J-102D01*
G01Y1604838D01*
G02X128615Y1604636I-203J1D01*
G01X125795D01*
G02X125592Y1604838I-1J202D01*
G01Y1605964D01*
G03X125564Y1606067I-200J1D01*
G02Y1608029I1642J981D01*
G03X125592Y1608132I-172J102D01*
G01Y1611082D01*
G03X125564Y1611185I-200J1D01*
G02Y1613147I1642J981D01*
G03X125592Y1613250I-172J102D01*
G37*
G36*
G01X142916D02*
Y1614376D01*
G02X143118Y1614578I202J0D01*
G01X145938D01*
G02X146140Y1614376I0J-202D01*
G01Y1613250D01*
G03X146168Y1613147I200J-1D01*
G02X146440Y1612166I-1640J-983D01*
G02X146168Y1611185I-1912J2D01*
G03X146140Y1611082I172J-102D01*
G01Y1608132D01*
G03X146168Y1608029I200J-1D01*
G02X146440Y1607048I-1640J-983D01*
G02X146168Y1606067I-1912J2D01*
G03X146140Y1605964I172J-102D01*
G01Y1604838D01*
G02X145938Y1604636I-202J0D01*
G01X143118D01*
G02X142916Y1604838I0J202D01*
G01Y1605964D01*
G03X142888Y1606067I-200J1D01*
G02X142616Y1607048I1640J983D01*
G02X142888Y1608029I1912J-2D01*
G03X142916Y1608132I-172J102D01*
G01Y1611082D01*
G03X142888Y1611185I-200J1D01*
G02X142616Y1612166I1640J983D01*
G02X142888Y1613147I1912J-2D01*
G03X142916Y1613250I-172J102D01*
G37*
G36*
G01X160238D02*
Y1614376D01*
G02X160440Y1614578I202J0D01*
G01X163260D01*
G02X163462Y1614376I0J-202D01*
G01Y1613250D01*
G03X163490Y1613147I200J-1D01*
G02X163762Y1612166I-1640J-983D01*
G02X163490Y1611185I-1912J2D01*
G03X163462Y1611082I172J-102D01*
G01Y1608132D01*
G03X163490Y1608029I200J-1D01*
G02X163762Y1607048I-1640J-983D01*
G02X163490Y1606067I-1912J2D01*
G03X163462Y1605964I172J-102D01*
G01Y1604838D01*
G02X163260Y1604636I-202J0D01*
G01X160440D01*
G02X160238Y1604838I0J202D01*
G01Y1605964D01*
G03X160210Y1606067I-200J1D01*
G02X159938Y1607048I1640J983D01*
G02X160210Y1608029I1912J-2D01*
G03X160238Y1608132I-172J102D01*
G01Y1611082D01*
G03X160210Y1611185I-200J1D01*
G02X159938Y1612166I1640J983D01*
G02X160210Y1613147I1912J-2D01*
G03X160238Y1613250I-172J102D01*
G37*
G36*
G01X281498D02*
Y1614376D01*
G02X281700Y1614578I202J0D01*
G01X284520D01*
G02X284722Y1614376I0J-202D01*
G01Y1613250D01*
G03X284750Y1613147I200J-1D01*
G02X285022Y1612166I-1640J-983D01*
G02X284750Y1611185I-1912J2D01*
G03X284722Y1611082I172J-102D01*
G01Y1608132D01*
G03X284750Y1608029I200J-1D01*
G02X285022Y1607048I-1640J-983D01*
G02X284750Y1606067I-1912J2D01*
G03X284722Y1605964I172J-102D01*
G01Y1604838D01*
G02X284520Y1604636I-202J0D01*
G01X281700D01*
G02X281498Y1604838I0J202D01*
G01Y1605964D01*
G03X281470Y1606067I-200J1D01*
G02X281198Y1607048I1640J983D01*
G02X281470Y1608029I1912J-2D01*
G03X281498Y1608132I-172J102D01*
G01Y1611082D01*
G03X281470Y1611185I-200J1D01*
G02X281198Y1612166I1640J983D01*
G02X281470Y1613147I1912J-2D01*
G03X281498Y1613250I-172J102D01*
G37*
G36*
G01X298820D02*
Y1614376D01*
G02X299023Y1614578I203J-1D01*
G01X301843D01*
G02X302046Y1614376I1J-202D01*
G01Y1613250D01*
G03X302074Y1613147I200J-1D01*
G02Y1611185I-1642J-981D01*
G03X302046Y1611082I172J-102D01*
G01Y1608132D01*
G03X302074Y1608029I200J-1D01*
G02Y1606067I-1642J-981D01*
G03X302046Y1605964I172J-102D01*
G01Y1604838D01*
G02X301843Y1604636I-203J1D01*
G01X299023D01*
G02X298820Y1604838I-1J202D01*
G01Y1605964D01*
G03X298792Y1606067I-200J1D01*
G02Y1608029I1642J981D01*
G03X298820Y1608132I-172J102D01*
G01Y1611082D01*
G03X298792Y1611185I-200J1D01*
G02Y1613147I1642J981D01*
G03X298820Y1613250I-172J102D01*
G37*
G36*
G01X316144D02*
Y1614376D01*
G02X316346Y1614578I202J0D01*
G01X319166D01*
G02X319368Y1614376I0J-202D01*
G01Y1613250D01*
G03X319396Y1613147I200J-1D01*
G02X319668Y1612166I-1640J-983D01*
G02X319396Y1611185I-1912J2D01*
G03X319368Y1611082I172J-102D01*
G01Y1608132D01*
G03X319396Y1608029I200J-1D01*
G02X319668Y1607048I-1640J-983D01*
G02X319396Y1606067I-1912J2D01*
G03X319368Y1605964I172J-102D01*
G01Y1604838D01*
G02X319166Y1604636I-202J0D01*
G01X316346D01*
G02X316144Y1604838I0J202D01*
G01Y1605964D01*
G03X316116Y1606067I-200J1D01*
G02X315844Y1607048I1640J983D01*
G02X316116Y1608029I1912J-2D01*
G03X316144Y1608132I-172J102D01*
G01Y1611082D01*
G03X316116Y1611185I-200J1D01*
G02X315844Y1612166I1640J983D01*
G02X316116Y1613147I1912J-2D01*
G03X316144Y1613250I-172J102D01*
G37*
G36*
G01X333466D02*
Y1614376D01*
G02X333668Y1614578I202J0D01*
G01X336488D01*
G02X336690Y1614376I0J-202D01*
G01Y1613250D01*
G03X336718Y1613147I200J-1D01*
G02X336990Y1612166I-1640J-983D01*
G02X336718Y1611185I-1912J2D01*
G03X336690Y1611082I172J-102D01*
G01Y1608132D01*
G03X336718Y1608029I200J-1D01*
G02X336990Y1607048I-1640J-983D01*
G02X336718Y1606067I-1912J2D01*
G03X336690Y1605964I172J-102D01*
G01Y1604838D01*
G02X336488Y1604636I-202J0D01*
G01X333668D01*
G02X333466Y1604838I0J202D01*
G01Y1605964D01*
G03X333438Y1606067I-200J1D01*
G02X333166Y1607048I1640J983D01*
G02X333438Y1608029I1912J-2D01*
G03X333466Y1608132I-172J102D01*
G01Y1611082D01*
G03X333438Y1611185I-200J1D01*
G02X333166Y1612166I1640J983D01*
G02X333438Y1613147I1912J-2D01*
G03X333466Y1613250I-172J102D01*
G37*
G36*
G01X454726D02*
Y1614376D01*
G02X454929Y1614578I203J-1D01*
G01X457749D01*
G02X457952Y1614376I1J-202D01*
G01Y1613250D01*
G03X457980Y1613147I200J-1D01*
G02Y1611185I-1642J-981D01*
G03X457952Y1611082I172J-102D01*
G01Y1608132D01*
G03X457980Y1608029I200J-1D01*
G02Y1606067I-1642J-981D01*
G03X457952Y1605964I172J-102D01*
G01Y1604838D01*
G02X457749Y1604636I-203J1D01*
G01X454929D01*
G02X454726Y1604838I-1J202D01*
G01Y1605964D01*
G03X454698Y1606067I-200J1D01*
G02Y1608029I1642J981D01*
G03X454726Y1608132I-172J102D01*
G01Y1611082D01*
G03X454698Y1611185I-200J1D01*
G02Y1613147I1642J981D01*
G03X454726Y1613250I-172J102D01*
G37*
G36*
G01X472050D02*
Y1614376D01*
G02X472252Y1614578I202J0D01*
G01X475072D01*
G02X475274Y1614376I0J-202D01*
G01Y1613250D01*
G03X475302Y1613147I200J-1D01*
G02X475574Y1612166I-1640J-983D01*
G02X475302Y1611185I-1912J2D01*
G03X475274Y1611082I172J-102D01*
G01Y1608132D01*
G03X475302Y1608029I200J-1D01*
G02X475574Y1607048I-1640J-983D01*
G02X475302Y1606067I-1912J2D01*
G03X475274Y1605964I172J-102D01*
G01Y1604838D01*
G02X475072Y1604636I-202J0D01*
G01X472252D01*
G02X472050Y1604838I0J202D01*
G01Y1605964D01*
G03X472022Y1606067I-200J1D01*
G02X471750Y1607048I1640J983D01*
G02X472022Y1608029I1912J-2D01*
G03X472050Y1608132I-172J102D01*
G01Y1611082D01*
G03X472022Y1611185I-200J1D01*
G02X471750Y1612166I1640J983D01*
G02X472022Y1613147I1912J-2D01*
G03X472050Y1613250I-172J102D01*
G37*
G36*
G01X489372D02*
Y1614376D01*
G02X489575Y1614578I203J-1D01*
G01X492395D01*
G02X492598Y1614376I1J-202D01*
G01Y1613250D01*
G03X492626Y1613147I200J-1D01*
G02Y1611185I-1642J-981D01*
G03X492598Y1611082I172J-102D01*
G01Y1608132D01*
G03X492626Y1608029I200J-1D01*
G02Y1606067I-1642J-981D01*
G03X492598Y1605964I172J-102D01*
G01Y1604838D01*
G02X492395Y1604636I-203J1D01*
G01X489575D01*
G02X489372Y1604838I-1J202D01*
G01Y1605964D01*
G03X489344Y1606067I-200J1D01*
G02Y1608029I1642J981D01*
G03X489372Y1608132I-172J102D01*
G01Y1611082D01*
G03X489344Y1611185I-200J1D01*
G02Y1613147I1642J981D01*
G03X489372Y1613250I-172J102D01*
G37*
G36*
G01X506694D02*
Y1614376D01*
G02X506897Y1614578I203J-1D01*
G01X509717D01*
G02X509920Y1614376I1J-202D01*
G01Y1613250D01*
G03X509948Y1613147I200J-1D01*
G02Y1611185I-1642J-981D01*
G03X509920Y1611082I172J-102D01*
G01Y1608132D01*
G03X509948Y1608029I200J-1D01*
G02Y1606067I-1642J-981D01*
G03X509920Y1605964I172J-102D01*
G01Y1604838D01*
G02X509717Y1604636I-203J1D01*
G01X506897D01*
G02X506694Y1604838I-1J202D01*
G01Y1605964D01*
G03X506666Y1606067I-200J1D01*
G02Y1608029I1642J981D01*
G03X506694Y1608132I-172J102D01*
G01Y1611082D01*
G03X506666Y1611185I-200J1D01*
G02Y1613147I1642J981D01*
G03X506694Y1613250I-172J102D01*
G37*
G36*
G01X627954D02*
Y1614376D01*
G02X628157Y1614578I203J-1D01*
G01X630977D01*
G02X631180Y1614376I1J-202D01*
G01Y1613250D01*
G03X631208Y1613147I200J-1D01*
G02Y1611185I-1642J-981D01*
G03X631180Y1611082I172J-102D01*
G01Y1608132D01*
G03X631208Y1608029I200J-1D01*
G02Y1606067I-1642J-981D01*
G03X631180Y1605964I172J-102D01*
G01Y1604838D01*
G02X630977Y1604636I-203J1D01*
G01X628157D01*
G02X627954Y1604838I-1J202D01*
G01Y1605964D01*
G03X627926Y1606067I-200J1D01*
G02Y1608029I1642J981D01*
G03X627954Y1608132I-172J102D01*
G01Y1611082D01*
G03X627926Y1611185I-200J1D01*
G02Y1613147I1642J981D01*
G03X627954Y1613250I-172J102D01*
G37*
G36*
G01X645278D02*
Y1614376D01*
G02X645480Y1614578I202J0D01*
G01X648300D01*
G02X648502Y1614376I0J-202D01*
G01Y1613250D01*
G03X648530Y1613147I200J-1D01*
G02X648802Y1612166I-1640J-983D01*
G02X648530Y1611185I-1912J2D01*
G03X648502Y1611082I172J-102D01*
G01Y1608132D01*
G03X648530Y1608029I200J-1D01*
G02X648802Y1607048I-1640J-983D01*
G02X648530Y1606067I-1912J2D01*
G03X648502Y1605964I172J-102D01*
G01Y1604838D01*
G02X648300Y1604636I-202J0D01*
G01X645480D01*
G02X645278Y1604838I0J202D01*
G01Y1605964D01*
G03X645250Y1606067I-200J1D01*
G02X644978Y1607048I1640J983D01*
G02X645250Y1608029I1912J-2D01*
G03X645278Y1608132I-172J102D01*
G01Y1611082D01*
G03X645250Y1611185I-200J1D01*
G02X644978Y1612166I1640J983D01*
G02X645250Y1613147I1912J-2D01*
G03X645278Y1613250I-172J102D01*
G37*
G36*
G01X662600D02*
Y1614376D01*
G02X662803Y1614578I203J-1D01*
G01X665623D01*
G02X665826Y1614376I1J-202D01*
G01Y1613250D01*
G03X665854Y1613147I200J-1D01*
G02Y1611185I-1642J-981D01*
G03X665826Y1611082I172J-102D01*
G01Y1608132D01*
G03X665854Y1608029I200J-1D01*
G02Y1606067I-1642J-981D01*
G03X665826Y1605964I172J-102D01*
G01Y1604838D01*
G02X665623Y1604636I-203J1D01*
G01X662803D01*
G02X662600Y1604838I-1J202D01*
G01Y1605964D01*
G03X662572Y1606067I-200J1D01*
G02Y1608029I1642J981D01*
G03X662600Y1608132I-172J102D01*
G01Y1611082D01*
G03X662572Y1611185I-200J1D01*
G02Y1613147I1642J981D01*
G03X662600Y1613250I-172J102D01*
G37*
G36*
G01X679922D02*
Y1614376D01*
G02X680125Y1614578I203J-1D01*
G01X682945D01*
G02X683148Y1614376I1J-202D01*
G01Y1613250D01*
G03X683176Y1613147I200J-1D01*
G02Y1611185I-1642J-981D01*
G03X683148Y1611082I172J-102D01*
G01Y1608132D01*
G03X683176Y1608029I200J-1D01*
G02Y1606067I-1642J-981D01*
G03X683148Y1605964I172J-102D01*
G01Y1604838D01*
G02X682945Y1604636I-203J1D01*
G01X680125D01*
G02X679922Y1604838I-1J202D01*
G01Y1605964D01*
G03X679894Y1606067I-200J1D01*
G02Y1608029I1642J981D01*
G03X679922Y1608132I-172J102D01*
G01Y1611082D01*
G03X679894Y1611185I-200J1D01*
G02Y1613147I1642J981D01*
G03X679922Y1613250I-172J102D01*
G37*
G36*
G01X116930Y1617580D02*
Y1618706D01*
G02X117133Y1618908I203J-1D01*
G01X119953D01*
G02X120156Y1618706I1J-202D01*
G01Y1617580D01*
G03X120184Y1617477I200J-1D01*
G02Y1615515I-1642J-981D01*
G03X120156Y1615412I172J-102D01*
G01Y1612462D01*
G03X120184Y1612359I200J-1D01*
G02Y1610397I-1642J-981D01*
G03X120156Y1610294I172J-102D01*
G01Y1609168D01*
G02X119953Y1608966I-203J1D01*
G01X117133D01*
G02X116930Y1609168I-1J202D01*
G01Y1610294D01*
G03X116902Y1610397I-200J1D01*
G02Y1612359I1642J981D01*
G03X116930Y1612462I-172J102D01*
G01Y1615412D01*
G03X116902Y1615515I-200J1D01*
G02Y1617477I1642J981D01*
G03X116930Y1617580I-172J102D01*
G37*
G36*
G01X134254D02*
Y1618706D01*
G02X134456Y1618908I202J0D01*
G01X137276D01*
G02X137478Y1618706I0J-202D01*
G01Y1617580D01*
G03X137506Y1617477I200J-1D01*
G02X137778Y1616496I-1640J-983D01*
G02X137506Y1615515I-1912J2D01*
G03X137478Y1615412I172J-102D01*
G01Y1612462D01*
G03X137506Y1612359I200J-1D01*
G02X137778Y1611378I-1640J-983D01*
G02X137506Y1610397I-1912J2D01*
G03X137478Y1610294I172J-102D01*
G01Y1609168D01*
G02X137276Y1608966I-202J0D01*
G01X134456D01*
G02X134254Y1609168I0J202D01*
G01Y1610294D01*
G03X134226Y1610397I-200J1D01*
G02X133954Y1611378I1640J983D01*
G02X134226Y1612359I1912J-2D01*
G03X134254Y1612462I-172J102D01*
G01Y1615412D01*
G03X134226Y1615515I-200J1D01*
G02X133954Y1616496I1640J983D01*
G02X134226Y1617477I1912J-2D01*
G03X134254Y1617580I-172J102D01*
G37*
G36*
G01X151576D02*
Y1618706D01*
G02X151779Y1618908I203J-1D01*
G01X154599D01*
G02X154802Y1618706I1J-202D01*
G01Y1617580D01*
G03X154830Y1617477I200J-1D01*
G02Y1615515I-1642J-981D01*
G03X154802Y1615412I172J-102D01*
G01Y1612462D01*
G03X154830Y1612359I200J-1D01*
G02Y1610397I-1642J-981D01*
G03X154802Y1610294I172J-102D01*
G01Y1609168D01*
G02X154599Y1608966I-203J1D01*
G01X151779D01*
G02X151576Y1609168I-1J202D01*
G01Y1610294D01*
G03X151548Y1610397I-200J1D01*
G02Y1612359I1642J981D01*
G03X151576Y1612462I-172J102D01*
G01Y1615412D01*
G03X151548Y1615515I-200J1D01*
G02Y1617477I1642J981D01*
G03X151576Y1617580I-172J102D01*
G37*
G36*
G01X168900D02*
Y1618706D01*
G02X169102Y1618908I202J0D01*
G01X171922D01*
G02X172124Y1618706I0J-202D01*
G01Y1617580D01*
G03X172152Y1617477I200J-1D01*
G02X172424Y1616496I-1640J-983D01*
G02X172152Y1615515I-1912J2D01*
G03X172124Y1615412I172J-102D01*
G01Y1612462D01*
G03X172152Y1612359I200J-1D01*
G02X172424Y1611378I-1640J-983D01*
G02X172152Y1610397I-1912J2D01*
G03X172124Y1610294I172J-102D01*
G01Y1609168D01*
G02X171922Y1608966I-202J0D01*
G01X169102D01*
G02X168900Y1609168I0J202D01*
G01Y1610294D01*
G03X168872Y1610397I-200J1D01*
G02X168600Y1611378I1640J983D01*
G02X168872Y1612359I1912J-2D01*
G03X168900Y1612462I-172J102D01*
G01Y1615412D01*
G03X168872Y1615515I-200J1D01*
G02X168600Y1616496I1640J983D01*
G02X168872Y1617477I1912J-2D01*
G03X168900Y1617580I-172J102D01*
G37*
G36*
G01X186222D02*
Y1618706D01*
G02X186425Y1618908I203J-1D01*
G01X189245D01*
G02X189448Y1618706I1J-202D01*
G01Y1617580D01*
G03X189476Y1617477I200J-1D01*
G02Y1615515I-1642J-981D01*
G03X189448Y1615412I172J-102D01*
G01Y1612462D01*
G03X189476Y1612359I200J-1D01*
G02Y1610397I-1642J-981D01*
G03X189448Y1610294I172J-102D01*
G01Y1609168D01*
G02X189245Y1608966I-203J1D01*
G01X186425D01*
G02X186222Y1609168I-1J202D01*
G01Y1610294D01*
G03X186194Y1610397I-200J1D01*
G02Y1612359I1642J981D01*
G03X186222Y1612462I-172J102D01*
G01Y1615412D01*
G03X186194Y1615515I-200J1D01*
G02Y1617477I1642J981D01*
G03X186222Y1617580I-172J102D01*
G37*
G36*
G01X290158D02*
Y1618706D01*
G02X290361Y1618908I203J-1D01*
G01X293181D01*
G02X293384Y1618706I1J-202D01*
G01Y1617580D01*
G03X293412Y1617477I200J-1D01*
G02Y1615515I-1642J-981D01*
G03X293384Y1615412I172J-102D01*
G01Y1612462D01*
G03X293412Y1612359I200J-1D01*
G02Y1610397I-1642J-981D01*
G03X293384Y1610294I172J-102D01*
G01Y1609168D01*
G02X293181Y1608966I-203J1D01*
G01X290361D01*
G02X290158Y1609168I-1J202D01*
G01Y1610294D01*
G03X290130Y1610397I-200J1D01*
G02Y1612359I1642J981D01*
G03X290158Y1612462I-172J102D01*
G01Y1615412D01*
G03X290130Y1615515I-200J1D01*
G02Y1617477I1642J981D01*
G03X290158Y1617580I-172J102D01*
G37*
G36*
G01X307482D02*
Y1618706D01*
G02X307684Y1618908I202J0D01*
G01X310504D01*
G02X310706Y1618706I0J-202D01*
G01Y1617580D01*
G03X310734Y1617477I200J-1D01*
G02X311006Y1616496I-1640J-983D01*
G02X310734Y1615515I-1912J2D01*
G03X310706Y1615412I172J-102D01*
G01Y1612462D01*
G03X310734Y1612359I200J-1D01*
G02X311006Y1611378I-1640J-983D01*
G02X310734Y1610397I-1912J2D01*
G03X310706Y1610294I172J-102D01*
G01Y1609168D01*
G02X310504Y1608966I-202J0D01*
G01X307684D01*
G02X307482Y1609168I0J202D01*
G01Y1610294D01*
G03X307454Y1610397I-200J1D01*
G02X307182Y1611378I1640J983D01*
G02X307454Y1612359I1912J-2D01*
G03X307482Y1612462I-172J102D01*
G01Y1615412D01*
G03X307454Y1615515I-200J1D01*
G02X307182Y1616496I1640J983D01*
G02X307454Y1617477I1912J-2D01*
G03X307482Y1617580I-172J102D01*
G37*
G36*
G01X324804D02*
Y1618706D01*
G02X325007Y1618908I203J-1D01*
G01X327827D01*
G02X328030Y1618706I1J-202D01*
G01Y1617580D01*
G03X328058Y1617477I200J-1D01*
G02Y1615515I-1642J-981D01*
G03X328030Y1615412I172J-102D01*
G01Y1612462D01*
G03X328058Y1612359I200J-1D01*
G02Y1610397I-1642J-981D01*
G03X328030Y1610294I172J-102D01*
G01Y1609168D01*
G02X327827Y1608966I-203J1D01*
G01X325007D01*
G02X324804Y1609168I-1J202D01*
G01Y1610294D01*
G03X324776Y1610397I-200J1D01*
G02Y1612359I1642J981D01*
G03X324804Y1612462I-172J102D01*
G01Y1615412D01*
G03X324776Y1615515I-200J1D01*
G02Y1617477I1642J981D01*
G03X324804Y1617580I-172J102D01*
G37*
G36*
G01X342128D02*
Y1618706D01*
G02X342330Y1618908I202J0D01*
G01X345150D01*
G02X345352Y1618706I0J-202D01*
G01Y1617580D01*
G03X345380Y1617477I200J-1D01*
G02X345652Y1616496I-1640J-983D01*
G02X345380Y1615515I-1912J2D01*
G03X345352Y1615412I172J-102D01*
G01Y1612462D01*
G03X345380Y1612359I200J-1D01*
G02X345652Y1611378I-1640J-983D01*
G02X345380Y1610397I-1912J2D01*
G03X345352Y1610294I172J-102D01*
G01Y1609168D01*
G02X345150Y1608966I-202J0D01*
G01X342330D01*
G02X342128Y1609168I0J202D01*
G01Y1610294D01*
G03X342100Y1610397I-200J1D01*
G02X341828Y1611378I1640J983D01*
G02X342100Y1612359I1912J-2D01*
G03X342128Y1612462I-172J102D01*
G01Y1615412D01*
G03X342100Y1615515I-200J1D01*
G02X341828Y1616496I1640J983D01*
G02X342100Y1617477I1912J-2D01*
G03X342128Y1617580I-172J102D01*
G37*
G36*
G01X359450D02*
Y1618706D01*
G02X359653Y1618908I203J-1D01*
G01X362473D01*
G02X362676Y1618706I1J-202D01*
G01Y1617580D01*
G03X362704Y1617477I200J-1D01*
G02Y1615515I-1642J-981D01*
G03X362676Y1615412I172J-102D01*
G01Y1612462D01*
G03X362704Y1612359I200J-1D01*
G02Y1610397I-1642J-981D01*
G03X362676Y1610294I172J-102D01*
G01Y1609168D01*
G02X362473Y1608966I-203J1D01*
G01X359653D01*
G02X359450Y1609168I-1J202D01*
G01Y1610294D01*
G03X359422Y1610397I-200J1D01*
G02Y1612359I1642J981D01*
G03X359450Y1612462I-172J102D01*
G01Y1615412D01*
G03X359422Y1615515I-200J1D01*
G02Y1617477I1642J981D01*
G03X359450Y1617580I-172J102D01*
G37*
G36*
G01X463388D02*
Y1618706D01*
G02X463590Y1618908I202J0D01*
G01X466410D01*
G02X466612Y1618706I0J-202D01*
G01Y1617580D01*
G03X466640Y1617477I200J-1D01*
G02X466912Y1616496I-1640J-983D01*
G02X466640Y1615515I-1912J2D01*
G03X466612Y1615412I172J-102D01*
G01Y1612462D01*
G03X466640Y1612359I200J-1D01*
G02X466912Y1611378I-1640J-983D01*
G02X466640Y1610397I-1912J2D01*
G03X466612Y1610294I172J-102D01*
G01Y1609168D01*
G02X466410Y1608966I-202J0D01*
G01X463590D01*
G02X463388Y1609168I0J202D01*
G01Y1610294D01*
G03X463360Y1610397I-200J1D01*
G02X463088Y1611378I1640J983D01*
G02X463360Y1612359I1912J-2D01*
G03X463388Y1612462I-172J102D01*
G01Y1615412D01*
G03X463360Y1615515I-200J1D01*
G02X463088Y1616496I1640J983D01*
G02X463360Y1617477I1912J-2D01*
G03X463388Y1617580I-172J102D01*
G37*
G36*
G01X480710D02*
Y1618706D01*
G02X480913Y1618908I203J-1D01*
G01X483733D01*
G02X483936Y1618706I1J-202D01*
G01Y1617580D01*
G03X483964Y1617477I200J-1D01*
G02Y1615515I-1642J-981D01*
G03X483936Y1615412I172J-102D01*
G01Y1612462D01*
G03X483964Y1612359I200J-1D01*
G02Y1610397I-1642J-981D01*
G03X483936Y1610294I172J-102D01*
G01Y1609168D01*
G02X483733Y1608966I-203J1D01*
G01X480913D01*
G02X480710Y1609168I-1J202D01*
G01Y1610294D01*
G03X480682Y1610397I-200J1D01*
G02Y1612359I1642J981D01*
G03X480710Y1612462I-172J102D01*
G01Y1615412D01*
G03X480682Y1615515I-200J1D01*
G02Y1617477I1642J981D01*
G03X480710Y1617580I-172J102D01*
G37*
G36*
G01X498034D02*
Y1618706D01*
G02X498236Y1618908I202J0D01*
G01X501056D01*
G02X501258Y1618706I0J-202D01*
G01Y1617580D01*
G03X501286Y1617477I200J-1D01*
G02X501558Y1616496I-1640J-983D01*
G02X501286Y1615515I-1912J2D01*
G03X501258Y1615412I172J-102D01*
G01Y1612462D01*
G03X501286Y1612359I200J-1D01*
G02X501558Y1611378I-1640J-983D01*
G02X501286Y1610397I-1912J2D01*
G03X501258Y1610294I172J-102D01*
G01Y1609168D01*
G02X501056Y1608966I-202J0D01*
G01X498236D01*
G02X498034Y1609168I0J202D01*
G01Y1610294D01*
G03X498006Y1610397I-200J1D01*
G02X497734Y1611378I1640J983D01*
G02X498006Y1612359I1912J-2D01*
G03X498034Y1612462I-172J102D01*
G01Y1615412D01*
G03X498006Y1615515I-200J1D01*
G02X497734Y1616496I1640J983D01*
G02X498006Y1617477I1912J-2D01*
G03X498034Y1617580I-172J102D01*
G37*
G36*
G01X515356D02*
Y1618706D01*
G02X515559Y1618908I203J-1D01*
G01X518379D01*
G02X518582Y1618706I1J-202D01*
G01Y1617580D01*
G03X518610Y1617477I200J-1D01*
G02Y1615515I-1642J-981D01*
G03X518582Y1615412I172J-102D01*
G01Y1612462D01*
G03X518610Y1612359I200J-1D01*
G02Y1610397I-1642J-981D01*
G03X518582Y1610294I172J-102D01*
G01Y1609168D01*
G02X518379Y1608966I-203J1D01*
G01X515559D01*
G02X515356Y1609168I-1J202D01*
G01Y1610294D01*
G03X515328Y1610397I-200J1D01*
G02Y1612359I1642J981D01*
G03X515356Y1612462I-172J102D01*
G01Y1615412D01*
G03X515328Y1615515I-200J1D01*
G02Y1617477I1642J981D01*
G03X515356Y1617580I-172J102D01*
G37*
G36*
G01X636616D02*
Y1618706D01*
G02X636818Y1618908I202J0D01*
G01X639638D01*
G02X639840Y1618706I0J-202D01*
G01Y1617580D01*
G03X639868Y1617477I200J-1D01*
G02X640140Y1616496I-1640J-983D01*
G02X639868Y1615515I-1912J2D01*
G03X639840Y1615412I172J-102D01*
G01Y1612462D01*
G03X639868Y1612359I200J-1D01*
G02X640140Y1611378I-1640J-983D01*
G02X639868Y1610397I-1912J2D01*
G03X639840Y1610294I172J-102D01*
G01Y1609168D01*
G02X639638Y1608966I-202J0D01*
G01X636818D01*
G02X636616Y1609168I0J202D01*
G01Y1610294D01*
G03X636588Y1610397I-200J1D01*
G02X636316Y1611378I1640J983D01*
G02X636588Y1612359I1912J-2D01*
G03X636616Y1612462I-172J102D01*
G01Y1615412D01*
G03X636588Y1615515I-200J1D01*
G02X636316Y1616496I1640J983D01*
G02X636588Y1617477I1912J-2D01*
G03X636616Y1617580I-172J102D01*
G37*
G36*
G01X653938D02*
Y1618706D01*
G02X654141Y1618908I203J-1D01*
G01X656961D01*
G02X657164Y1618706I1J-202D01*
G01Y1617580D01*
G03X657192Y1617477I200J-1D01*
G02Y1615515I-1642J-981D01*
G03X657164Y1615412I172J-102D01*
G01Y1612462D01*
G03X657192Y1612359I200J-1D01*
G02Y1610397I-1642J-981D01*
G03X657164Y1610294I172J-102D01*
G01Y1609168D01*
G02X656961Y1608966I-203J1D01*
G01X654141D01*
G02X653938Y1609168I-1J202D01*
G01Y1610294D01*
G03X653910Y1610397I-200J1D01*
G02Y1612359I1642J981D01*
G03X653938Y1612462I-172J102D01*
G01Y1615412D01*
G03X653910Y1615515I-200J1D01*
G02Y1617477I1642J981D01*
G03X653938Y1617580I-172J102D01*
G37*
G36*
G01X671262D02*
Y1618706D01*
G02X671464Y1618908I202J0D01*
G01X674284D01*
G02X674486Y1618706I0J-202D01*
G01Y1617580D01*
G03X674514Y1617477I200J-1D01*
G02X674786Y1616496I-1640J-983D01*
G02X674514Y1615515I-1912J2D01*
G03X674486Y1615412I172J-102D01*
G01Y1612462D01*
G03X674514Y1612359I200J-1D01*
G02X674786Y1611378I-1640J-983D01*
G02X674514Y1610397I-1912J2D01*
G03X674486Y1610294I172J-102D01*
G01Y1609168D01*
G02X674284Y1608966I-202J0D01*
G01X671464D01*
G02X671262Y1609168I0J202D01*
G01Y1610294D01*
G03X671234Y1610397I-200J1D01*
G02X670962Y1611378I1640J983D01*
G02X671234Y1612359I1912J-2D01*
G03X671262Y1612462I-172J102D01*
G01Y1615412D01*
G03X671234Y1615515I-200J1D01*
G02X670962Y1616496I1640J983D01*
G02X671234Y1617477I1912J-2D01*
G03X671262Y1617580I-172J102D01*
G37*
G36*
G01X688584D02*
Y1618706D01*
G02X688787Y1618908I203J-1D01*
G01X691607D01*
G02X691810Y1618706I1J-202D01*
G01Y1617580D01*
G03X691838Y1617477I200J-1D01*
G02Y1615515I-1642J-981D01*
G03X691810Y1615412I172J-102D01*
G01Y1612462D01*
G03X691838Y1612359I200J-1D01*
G02Y1610397I-1642J-981D01*
G03X691810Y1610294I172J-102D01*
G01Y1609168D01*
G02X691607Y1608966I-203J1D01*
G01X688787D01*
G02X688584Y1609168I-1J202D01*
G01Y1610294D01*
G03X688556Y1610397I-200J1D01*
G02Y1612359I1642J981D01*
G03X688584Y1612462I-172J102D01*
G01Y1615412D01*
G03X688556Y1615515I-200J1D01*
G02Y1617477I1642J981D01*
G03X688584Y1617580I-172J102D01*
G37*
G36*
G01X421227Y1400490D02*
G02X424231I1502J0D01*
G02X423814Y1399451I-1503J0D01*
G03X423760Y1399281I144J-139D01*
G01X423810Y1398967D01*
G03X423913Y1398822I197J31D01*
G02X424702Y1397500I-713J-1322D01*
G02X424197Y1396377I-1501J0D01*
G01X424162Y1396346D01*
X424127Y1396261D01*
X424152Y1395898D01*
G03X424239Y1395746I199J13D01*
G02X424902Y1394500I-839J-1246D01*
G02X421898I-1502J0D01*
G02X422403Y1395623I1501J0D01*
G01X422438Y1395654D01*
X422473Y1395739D01*
X422448Y1396102D01*
G03X422361Y1396254I-199J-13D01*
G02X421698Y1397500I839J1246D01*
G02X422115Y1398539I1503J0D01*
G03X422169Y1398709I-144J139D01*
G01X422119Y1399023D01*
G03X422016Y1399168I-197J-31D01*
G02X421227Y1400490I713J1322D01*
G37*
G36*
G01X418350Y1400899D02*
G02X417598Y1402200I749J1301D01*
G02X420602I1502J0D01*
G02X419807Y1400875I-1502J0D01*
G03X419795Y1400175I188J-353D01*
G02X420547Y1398874I-749J-1301D01*
G02X417543I-1502J0D01*
G02X418338Y1400199I1502J0D01*
G03X418350Y1400899I-188J353D01*
G37*
G36*
G01X29030Y1440464D02*
G02X28378Y1441702I849J1238D01*
G02X31382I1502J0D01*
G02X30714Y1440453I-1502J0D01*
G03X30710Y1439790I222J-333D01*
G02X31362Y1438552I-849J-1238D01*
G02X28358I-1502J0D01*
G02X29026Y1439801I1502J0D01*
G03X29030Y1440464I-222J333D01*
G37*
G36*
G01X394483Y1449492D02*
G02X394386Y1450022I1405J531D01*
G02X395888Y1448520I1502J0D01*
G02X395764Y1448525I-2J1502D01*
G03X395356Y1447985I-34J-399D01*
G02X395453Y1447455I-1405J-531D01*
G02X393951Y1448957I-1502J0D01*
G02X394075Y1448952I2J-1502D01*
G03X394483Y1449492I34J399D01*
G37*
G36*
G01X409513Y1451212D02*
G02X411000Y1452502I1487J-212D01*
G02Y1449498I0J-1502D01*
G02X410094Y1449802I0J1502D01*
G03X409457Y1449539I-241J-319D01*
G02X407970Y1448249I-1487J212D01*
G02Y1451253I0J1502D01*
G02X408876Y1450949I0J-1502D01*
G03X409513Y1451212I241J319D01*
G37*
G36*
G01X396691Y1500306D02*
G02X395370Y1499520I-1321J717D01*
G02Y1502524I0J1502D01*
G02X396716Y1501688I0J-1502D01*
G03X397426Y1501675I358J177D01*
G02X398747Y1502461I1321J-717D01*
G02Y1499457I0J-1502D01*
G02X397401Y1500293I0J1502D01*
G03X396691Y1500306I-358J-177D01*
G37*
G36*
G01X657994Y652426D02*
X658064D01*
G02X660370Y650119I-1J-2307D01*
G01Y650118D01*
G02X659828Y648633I-2306J0D01*
G03X659781Y648496I153J-129D01*
G01X659795Y648186D01*
X659826Y648118D01*
X659853Y648091D01*
G02X660540Y646449I-1619J-1642D01*
G01Y620091D01*
G03X660716Y619892I200J0D01*
G01X660717D01*
G02Y616908I-171J-1492D01*
G01X660716D01*
G03X660540Y616709I24J-199D01*
G01Y614490D01*
G03X660594Y614353I200J0D01*
G01X660783Y614153D01*
G03X660916Y614091I145J138D01*
G02Y611093I-89J-1499D01*
G01X660877Y611091D01*
X660810Y611059D01*
X660594Y610831D01*
G03X660540Y610694I146J-137D01*
G01Y608701D01*
G03X660592Y608567I200J1D01*
G01X660670Y608481D01*
G03X660791Y608417I148J134D01*
G02Y605441I-205J-1488D01*
G03X660670Y605377I27J-198D01*
G01X660592Y605291D01*
G03X660540Y605157I148J-135D01*
G01Y603866D01*
G03X660696Y603670I200J-1D01*
G02Y600740I-330J-1465D01*
G03X660540Y600544I44J-195D01*
G01Y596779D01*
G03X660696Y596583I200J-1D01*
G02Y593653I-330J-1465D01*
G03X660540Y593457I44J-195D01*
G01Y593446D01*
G03X660599Y593304I200J0D01*
G01X668456Y585447D01*
G02X669132Y583816I-1631J-1632D01*
G01Y556748D01*
G02X668456Y555117I-2307J1D01*
G01X663391Y550052D01*
G02X661760Y549376I-1632J1631D01*
G02X659454Y551683I1J2307D01*
G01Y551684D01*
G02X660129Y553314I2306J0D01*
G01X664459Y557644D01*
G03X664518Y557786I-141J142D01*
G01Y582778D01*
G03X664459Y582920I-200J0D01*
G01X658397Y588982D01*
G03X658179Y589026I-142J-141D01*
G01X658123Y589003D01*
X658056Y588903D01*
Y582316D01*
G02X657380Y580685I-2307J1D01*
G01X652780Y576085D01*
G02X651149Y575410I-1630J1631D01*
G02X648842Y577716I-1J2306D01*
G02X649518Y579347I2307J-1D01*
G01X653383Y583212D01*
G03X653442Y583354I-141J142D01*
G01Y647874D01*
G02X654118Y649505I2307J-1D01*
G01X656363Y651750D01*
G02X657994Y652426I1632J-1631D01*
G37*
G36*
G01X1115081D02*
X1115151D01*
G02X1117458Y650119I0J-2307D01*
G02X1116915Y648633I-2307J1D01*
G03X1116868Y648496I153J-129D01*
G01X1116882Y648186D01*
X1116913Y648118D01*
X1116940Y648091D01*
G02X1117626Y646451I-1620J-1641D01*
G01Y620091D01*
G03X1117803Y619892I200J0D01*
G01X1117804D01*
G02Y616908I-171J-1492D01*
G01X1117803D01*
G03X1117626Y616709I23J-199D01*
G01Y614491D01*
G03X1117681Y614353I200J0D01*
G01X1117870Y614153D01*
G03X1118003Y614091I145J138D01*
G02Y611093I-89J-1499D01*
G03X1117870Y611031I12J-200D01*
G01X1117681Y610831D01*
G03X1117626Y610693I145J-138D01*
G01Y608702D01*
G03X1117678Y608567I200J0D01*
G01X1117758Y608480D01*
G03X1117878Y608417I147J135D01*
G02Y605441I-205J-1488D01*
G03X1117758Y605378I27J-198D01*
G01X1117678Y605291D01*
G03X1117626Y605156I148J-135D01*
G01Y603866D01*
G03X1117782Y603670I200J-1D01*
G02Y600740I-329J-1465D01*
G03X1117626Y600544I44J-195D01*
G01Y596779D01*
G03X1117782Y596583I200J-1D01*
G02Y593653I-329J-1465D01*
G03X1117626Y593457I44J-195D01*
G01Y593446D01*
G03X1117685Y593304I200J0D01*
G01X1121444Y589546D01*
X1121607Y589544D01*
X1121666Y589600D01*
G02X1121686Y589618I1015J-1107D01*
G01Y589828D01*
G03X1121629Y589967I-200J-1D01*
G02X1121203Y591015I1076J1048D01*
G02X1124207I1502J0D01*
G02X1123837Y590028I-1501J0D01*
G01Y590027D01*
X1123836D01*
G03X1123788Y589897I152J-130D01*
G01Y589633D01*
G03X1123836Y589503I200J0D01*
G01X1123837Y589502D01*
G02X1124207Y588515I-1131J-987D01*
G02X1123790Y587476I-1503J0D01*
G01X1123734Y587417D01*
X1123736Y587254D01*
X1125543Y585447D01*
G02X1126218Y583817I-1631J-1630D01*
G01Y556747D01*
G02X1125543Y555117I-2306J0D01*
G01X1120478Y550052D01*
G02X1118847Y549376I-1632J1631D01*
G02X1116540Y551683I0J2307D01*
G02X1117216Y553314I2307J-1D01*
G01X1121547Y557644D01*
G03X1121606Y557786I-141J142D01*
G01Y582778D01*
G03X1121547Y582920I-200J0D01*
G01X1115483Y588983D01*
G03X1115266Y589026I-141J-142D01*
G01X1115209Y589003D01*
X1115142Y588902D01*
Y582315D01*
G02X1114467Y580685I-2306J0D01*
G01X1109867Y576085D01*
G02X1108237Y575410I-1630J1631D01*
G01X1108236D01*
G02X1105930Y577716I0J2306D01*
G01Y577717D01*
G02X1106605Y579347I2306J0D01*
G01X1110471Y583212D01*
G03X1110530Y583354I-141J142D01*
G01Y647875D01*
G02X1111205Y649505I2306J0D01*
G01X1113450Y651750D01*
G02X1115081Y652426I1632J-1631D01*
G37*
G36*
G01X983197Y604330D02*
X982647D01*
G03X982556Y604308I0J-200D01*
G02X981857Y604135I-700J1329D01*
G02Y607139I0J1502D01*
G02X982511Y606989I0J-1501D01*
G01X982603Y606944D01*
X982656D01*
X986226Y610515D01*
G02X987150Y610898I924J-923D01*
G01X997556D01*
G03X997698Y610957I0J200D01*
G01X1009625Y622884D01*
G03X1009684Y623026I-141J142D01*
G01Y641675D01*
G03X1009625Y641817I-200J0D01*
G01X994855Y656587D01*
G03X994713Y656646I-142J-141D01*
G01X963244D01*
G02X962320Y657029I0J1306D01*
G01X954161Y665188D01*
G03X954081Y665237I-142J-141D01*
G01X954080D01*
G02X953024Y666671I446J1434D01*
G02X954526Y668173I1502J0D01*
G02X955960Y667118I0J-1502D01*
G01Y667116D01*
G03X956009Y667036I190J62D01*
G01X963726Y659319D01*
G03X963868Y659260I142J141D01*
G01X995337D01*
G02X996261Y658877I0J-1306D01*
G01X1011915Y643223D01*
G02X1012298Y642299I-923J-924D01*
G01Y622402D01*
G02X1011915Y621478I-1306J0D01*
G01X999104Y608667D01*
G02X998180Y608284I-924J923D01*
G01X987774D01*
G03X987632Y608225I0J-200D01*
G01X984154Y604747D01*
G03X984150Y604743I139J-143D01*
G02X983197Y604330I-954J894D01*
G37*
G36*
G01X1320605Y360172D02*
X1325263D01*
G02X1326678Y359586I0J-2001D01*
G01X1327904Y358360D01*
G02X1328490Y356945I-1415J-1415D01*
G02X1326489Y354944I-2001J0D01*
G02X1325074Y355530I0J2001D01*
G01X1324493Y356111D01*
G03X1324351Y356170I-142J-141D01*
G01X1321517D01*
G03X1321375Y356111I0J-200D01*
G01X1316306Y351042D01*
G02X1314891Y350456I-1415J1415D01*
G01X1313272D01*
G03X1313130Y350397I0J-200D01*
G01X1309427Y346694D01*
G02X1308012Y346108I-1415J1415D01*
G01X1308010D01*
G02X1306010Y348109I1J2001D01*
G02X1306597Y349524I2002J-1D01*
G01X1310945Y353872D01*
G02X1312360Y354458I1415J-1415D01*
G01X1313979D01*
G03X1314121Y354517I0J200D01*
G01X1319190Y359586D01*
G02X1320605Y360172I1415J-1415D01*
G37*
G36*
G01X970197Y665850D02*
X966797D01*
G02Y669456I0J1803D01*
G01X970197D01*
G02Y665850I0J-1803D01*
G37*
G36*
G01X501495Y772260D02*
X504895D01*
G02Y768654I0J-1803D01*
G01X501495D01*
G02Y772260I0J1803D01*
G37*
G36*
G01X534264Y663358D02*
X537664D01*
G02Y659754I0J-1802D01*
G01X534264D01*
G02Y663358I0J1802D01*
G37*
G36*
G01X538985Y734790D02*
X535585D01*
G02Y738396I0J1803D01*
G01X538985D01*
G02Y734790I0J-1803D01*
G37*
G36*
G01X530985Y739790D02*
X527585D01*
G02Y743396I0J1803D01*
G01X530985D01*
G02Y739790I0J-1803D01*
G37*
G36*
G01X517731Y742874D02*
X521131D01*
G02Y739268I0J-1803D01*
G01X517731D01*
G02Y742874I0J1803D01*
G37*
G36*
G01X511724Y739232D02*
X508324D01*
G02Y742838I0J1803D01*
G01X511724D01*
G02Y739232I0J-1803D01*
G37*
G36*
G01X415777Y306272D02*
X419177D01*
G02Y302668I0J-1802D01*
G01X415777D01*
G02Y306272I0J1802D01*
G37*
G36*
G01X423651Y309272D02*
X427051D01*
G02Y305668I0J-1802D01*
G01X423651D01*
G02Y309272I0J1802D01*
G37*
G36*
G01X431525Y306272D02*
X434925D01*
G02Y302668I0J-1802D01*
G01X431525D01*
G02Y306272I0J1802D01*
G37*
G36*
G01X919628Y334530D02*
X916228D01*
G02Y338136I0J1803D01*
G01X919628D01*
G02Y334530I0J-1803D01*
G37*
G36*
G01X942730Y322242D02*
X939330D01*
G02Y325846I0J1802D01*
G01X942730D01*
G02Y322242I0J-1802D01*
G37*
G36*
G01X389015Y794228D02*
X392415D01*
G02Y791222I0J-1503D01*
G01X389015D01*
G02Y794228I0J1503D01*
G37*
G36*
G01X1811364Y970492D02*
Y958328D01*
G02X1811305Y958186I-200J0D01*
G01X1809837Y956717D01*
G02X1809695Y956658I-142J141D01*
G01X1801031D01*
G02X1800889Y956717I0J200D01*
G01X1799421Y958186D01*
G02X1799362Y958328I141J142D01*
G01Y971492D01*
G02X1799421Y971634I200J0D01*
G01X1800389Y972603D01*
G02X1800531Y972662I142J-141D01*
G01X1809195D01*
G02X1809337Y972603I0J-200D01*
G01X1811305Y970634D01*
G02X1811364Y970492I-141J-142D01*
G37*
G36*
G01X78050Y828550D02*
Y816386D01*
G02X77991Y816244I-200J0D01*
G01X76523Y814775D01*
G02X76381Y814716I-142J141D01*
G01X67717D01*
G02X67575Y814775I0J200D01*
G01X66107Y816244D01*
G02X66048Y816386I141J142D01*
G01Y829550D01*
G02X66107Y829692I200J0D01*
G01X67075Y830661D01*
G02X67217Y830720I142J-141D01*
G01X75881D01*
G02X76023Y830661I0J-200D01*
G01X77991Y828692D01*
G02X78050Y828550I-141J-142D01*
G37*
G36*
G01X942699Y344560D02*
X939299D01*
G02Y348166I0J1803D01*
G01X942699D01*
G02Y344560I0J-1803D01*
G37*
G36*
G01X919353Y342348D02*
X915953D01*
G02Y345952I0J1802D01*
G01X919353D01*
G02Y342348I0J-1802D01*
G37*
G36*
G01X1318363Y312364D02*
X1321763D01*
G02Y308760I0J-1802D01*
G01X1318363D01*
G02Y312364I0J1802D01*
G37*
G36*
G01X1337508Y371598D02*
X1334108D01*
G02Y375204I0J1803D01*
G01X1337508D01*
G02Y371598I0J-1803D01*
G37*
G36*
G01X1326237Y309364D02*
X1329637D01*
G02Y305760I0J-1802D01*
G01X1326237D01*
G02Y309364I0J1802D01*
G37*
G36*
G01X1334111Y312364D02*
X1337511D01*
G02Y308760I0J-1802D01*
G01X1334111D01*
G02Y312364I0J1802D01*
G37*
G36*
G01X927963Y342238D02*
X924563D01*
G02Y345844I0J1803D01*
G01X927963D01*
G02Y342238I0J-1803D01*
G37*
G36*
G01X1769063Y921922D02*
X1765663D01*
G02Y925526I0J1802D01*
G01X1769063D01*
G02Y921922I0J-1802D01*
G37*
G36*
G01X205848Y59011D02*
G02Y62015I0J1502D01*
G02X207005Y61471I0J-1502D01*
G01X207032Y61439D01*
X207106Y61402D01*
X207442Y61384D01*
G03X207593Y61441I11J200D01*
G02X208645Y61871I1052J-1072D01*
G02Y58867I0J-1502D01*
G02X207488Y59411I0J1502D01*
G01X207461Y59443D01*
X207387Y59480D01*
X207051Y59498D01*
G03X206900Y59441I-11J-200D01*
G02X205848Y59011I-1052J1072D01*
G37*
G36*
G01X560573D02*
G02Y62015I0J1502D01*
G02X561728Y61473I0J-1502D01*
G01X561756Y61439D01*
X561833Y61402D01*
X562179Y61393D01*
G03X562329Y61456I4J200D01*
G01X562330Y61457D01*
G02X563433Y61940I1103J-1018D01*
G02Y58936I0J-1502D01*
G02X562278Y59478I0J1502D01*
G01X562250Y59512D01*
X562173Y59549D01*
X561827Y59558D01*
G03X561677Y59495I-4J-200D01*
G01X561676Y59494D01*
G02X560573Y59011I-1103J1018D01*
G37*
G36*
G01X662935D02*
G02Y62015I0J1502D01*
G02X664090Y61473I0J-1502D01*
G01X664118Y61439D01*
X664195Y61402D01*
X664541Y61393D01*
G03X664691Y61456I4J200D01*
G01X664692Y61457D01*
G02X665795Y61940I1103J-1018D01*
G02Y58936I0J-1502D01*
G02X664640Y59478I0J1502D01*
G01X664612Y59512D01*
X664535Y59549D01*
X664189Y59558D01*
G03X664039Y59495I-4J-200D01*
G01X664038Y59494D01*
G02X662935Y59011I-1103J1018D01*
G37*
G36*
G01X765297D02*
G02Y62015I0J1502D01*
G02X766452Y61473I0J-1502D01*
G01X766480Y61439D01*
X766557Y61402D01*
X766903Y61393D01*
G03X767053Y61456I4J200D01*
G01X767054Y61457D01*
G02X768157Y61940I1103J-1018D01*
G02Y58936I0J-1502D01*
G02X767002Y59478I0J1502D01*
G01X766974Y59512D01*
X766897Y59549D01*
X766551Y59558D01*
G03X766401Y59495I-4J-200D01*
G01X766400Y59494D01*
G02X765297Y59011I-1103J1018D01*
G37*
G36*
G01X867659D02*
G02Y62015I0J1502D01*
G02X868814Y61473I0J-1502D01*
G01X868842Y61439D01*
X868919Y61402D01*
X869265Y61393D01*
G03X869415Y61456I4J200D01*
G01X869416Y61457D01*
G02X870519Y61940I1103J-1018D01*
G02Y58936I0J-1502D01*
G02X869364Y59478I0J1502D01*
G01X869336Y59512D01*
X869259Y59549D01*
X868913Y59558D01*
G03X868763Y59495I-4J-200D01*
G01X868762Y59494D01*
G02X867659Y59011I-1103J1018D01*
G37*
G36*
G01X1017659D02*
G02Y62015I0J1502D01*
G02X1018814Y61473I0J-1502D01*
G01X1018842Y61439D01*
X1018919Y61402D01*
X1019265Y61393D01*
G03X1019415Y61456I4J200D01*
G01X1019416Y61457D01*
G02X1020519Y61940I1103J-1018D01*
G02Y58936I0J-1502D01*
G02X1019364Y59478I0J1502D01*
G01X1019336Y59512D01*
X1019259Y59549D01*
X1018913Y59558D01*
G03X1018763Y59495I-4J-200D01*
G01X1018762Y59494D01*
G02X1017659Y59011I-1103J1018D01*
G37*
G36*
G01X1120021D02*
G02Y62015I0J1502D01*
G02X1121176Y61473I0J-1502D01*
G01X1121204Y61439D01*
X1121281Y61402D01*
X1121627Y61393D01*
G03X1121777Y61456I4J200D01*
G01X1121778Y61457D01*
G02X1122881Y61940I1103J-1018D01*
G02Y58936I0J-1502D01*
G02X1121726Y59478I0J1502D01*
G01X1121698Y59512D01*
X1121621Y59549D01*
X1121275Y59558D01*
G03X1121125Y59495I-4J-200D01*
G01X1121124Y59494D01*
G02X1120021Y59011I-1103J1018D01*
G37*
G36*
G01X1222383D02*
G02Y62015I0J1502D01*
G02X1223538Y61473I0J-1502D01*
G01X1223566Y61439D01*
X1223643Y61402D01*
X1223989Y61393D01*
G03X1224139Y61456I4J200D01*
G01X1224140Y61457D01*
G02X1225243Y61940I1103J-1018D01*
G02Y58936I0J-1502D01*
G02X1224088Y59478I0J1502D01*
G01X1224060Y59512D01*
X1223983Y59549D01*
X1223637Y59558D01*
G03X1223487Y59495I-4J-200D01*
G01X1223486Y59494D01*
G02X1222383Y59011I-1103J1018D01*
G37*
G36*
G01X1474746D02*
G02Y62015I0J1502D01*
G02X1475901Y61473I0J-1502D01*
G01X1475929Y61439D01*
X1476006Y61402D01*
X1476352Y61393D01*
G03X1476502Y61456I4J200D01*
G01X1476503Y61457D01*
G02X1477606Y61940I1103J-1018D01*
G02Y58936I0J-1502D01*
G02X1476451Y59478I0J1502D01*
G01X1476423Y59512D01*
X1476346Y59549D01*
X1476000Y59558D01*
G03X1475850Y59495I-4J-200D01*
G01X1475849Y59494D01*
G02X1474746Y59011I-1103J1018D01*
G37*
G36*
G01X1577108D02*
G02Y62015I0J1502D01*
G02X1578263Y61473I0J-1502D01*
G01X1578291Y61439D01*
X1578368Y61402D01*
X1578714Y61393D01*
G03X1578864Y61456I4J200D01*
G01X1578865Y61457D01*
G02X1579968Y61940I1103J-1018D01*
G02Y58936I0J-1502D01*
G02X1578813Y59478I0J1502D01*
G01X1578785Y59512D01*
X1578708Y59549D01*
X1578362Y59558D01*
G03X1578212Y59495I-4J-200D01*
G01X1578211Y59494D01*
G02X1577108Y59011I-1103J1018D01*
G37*
G36*
G01X1679470D02*
G02Y62015I0J1502D01*
G02X1680625Y61473I0J-1502D01*
G01X1680653Y61439D01*
X1680730Y61402D01*
X1681076Y61393D01*
G03X1681226Y61456I4J200D01*
G01X1681227Y61457D01*
G02X1682330Y61940I1103J-1018D01*
G02Y58936I0J-1502D01*
G02X1681175Y59478I0J1502D01*
G01X1681147Y59512D01*
X1681070Y59549D01*
X1680724Y59558D01*
G03X1680574Y59495I-4J-200D01*
G01X1680573Y59494D01*
G02X1679470Y59011I-1103J1018D01*
G37*
G36*
G01X307916Y59027D02*
G02Y62031I0J1502D01*
G02X309107Y61444I0J-1502D01*
G01X309134Y61409D01*
X309211Y61369D01*
X309606Y61350D01*
X309687Y61383D01*
X309717Y61416D01*
G02X310817Y61895I1100J-1024D01*
G02Y58891I0J-1502D01*
G02X309626Y59478I0J1502D01*
G01X309599Y59513D01*
X309522Y59553D01*
X309127Y59572D01*
X309046Y59539D01*
X309016Y59506D01*
G02X307916Y59027I-1100J1024D01*
G37*
G36*
G01X63283Y85193D02*
G02X66287I1502J0D01*
G02X65881Y84166I-1502J0D01*
G01X65855Y84139D01*
X65827Y84068D01*
Y83718D01*
X65855Y83647D01*
X65881Y83620D01*
G02Y81566I-1096J-1027D01*
G01X65855Y81539D01*
X65827Y81468D01*
Y81118D01*
X65855Y81047D01*
X65881Y81020D01*
G02Y78966I-1096J-1027D01*
G01X65855Y78939D01*
X65827Y78868D01*
Y78518D01*
X65855Y78447D01*
X65881Y78420D01*
G02Y76366I-1096J-1027D01*
G01X65855Y76339D01*
X65827Y76268D01*
Y75918D01*
X65855Y75847D01*
X65881Y75820D01*
G02X66287Y74793I-1096J-1027D01*
G02X63283I-1502J0D01*
G02X63689Y75820I1502J0D01*
G01X63715Y75847D01*
X63743Y75918D01*
Y76268D01*
X63715Y76339D01*
X63689Y76366D01*
G02Y78420I1096J1027D01*
G01X63715Y78447D01*
X63743Y78518D01*
Y78868D01*
X63715Y78939D01*
X63689Y78966D01*
G02Y81020I1096J1027D01*
G01X63715Y81047D01*
X63743Y81118D01*
Y81468D01*
X63715Y81539D01*
X63689Y81566D01*
G02Y83620I1096J1027D01*
G01X63715Y83647D01*
X63743Y83718D01*
Y84068D01*
X63715Y84139D01*
X63689Y84166D01*
G02X63283Y85193I1096J1027D01*
G37*
G36*
G01X165645D02*
G02X168649I1502J0D01*
G02X168243Y84166I-1502J0D01*
G01X168217Y84139D01*
X168189Y84068D01*
Y83718D01*
X168217Y83647D01*
X168243Y83620D01*
G02Y81566I-1096J-1027D01*
G01X168217Y81539D01*
X168189Y81468D01*
Y81118D01*
X168217Y81047D01*
X168243Y81020D01*
G02Y78966I-1096J-1027D01*
G01X168217Y78939D01*
X168189Y78868D01*
Y78518D01*
X168217Y78447D01*
X168243Y78420D01*
G02Y76366I-1096J-1027D01*
G01X168217Y76339D01*
X168189Y76268D01*
Y75918D01*
X168217Y75847D01*
X168243Y75820D01*
G02X168649Y74793I-1096J-1027D01*
G02X165645I-1502J0D01*
G02X166051Y75820I1502J0D01*
G01X166077Y75847D01*
X166105Y75918D01*
Y76268D01*
X166077Y76339D01*
X166051Y76366D01*
G02Y78420I1096J1027D01*
G01X166077Y78447D01*
X166105Y78518D01*
Y78868D01*
X166077Y78939D01*
X166051Y78966D01*
G02Y81020I1096J1027D01*
G01X166077Y81047D01*
X166105Y81118D01*
Y81468D01*
X166077Y81539D01*
X166051Y81566D01*
G02Y83620I1096J1027D01*
G01X166077Y83647D01*
X166105Y83718D01*
Y84068D01*
X166077Y84139D01*
X166051Y84166D01*
G02X165645Y85193I1096J1027D01*
G37*
G36*
G01X268007D02*
G02X271011I1502J0D01*
G02X270605Y84166I-1502J0D01*
G01X270579Y84139D01*
X270551Y84068D01*
Y83718D01*
X270579Y83647D01*
X270605Y83620D01*
G02Y81566I-1096J-1027D01*
G01X270579Y81539D01*
X270551Y81468D01*
Y81118D01*
X270579Y81047D01*
X270605Y81020D01*
G02Y78966I-1096J-1027D01*
G01X270579Y78939D01*
X270551Y78868D01*
Y78518D01*
X270579Y78447D01*
X270605Y78420D01*
G02Y76366I-1096J-1027D01*
G01X270579Y76339D01*
X270551Y76268D01*
Y75918D01*
X270579Y75847D01*
X270605Y75820D01*
G02X271011Y74793I-1096J-1027D01*
G02X268007I-1502J0D01*
G02X268413Y75820I1502J0D01*
G01X268439Y75847D01*
X268467Y75918D01*
Y76268D01*
X268439Y76339D01*
X268413Y76366D01*
G02Y78420I1096J1027D01*
G01X268439Y78447D01*
X268467Y78518D01*
Y78868D01*
X268439Y78939D01*
X268413Y78966D01*
G02Y81020I1096J1027D01*
G01X268439Y81047D01*
X268467Y81118D01*
Y81468D01*
X268439Y81539D01*
X268413Y81566D01*
G02Y83620I1096J1027D01*
G01X268439Y83647D01*
X268467Y83718D01*
Y84068D01*
X268439Y84139D01*
X268413Y84166D01*
G02X268007Y85193I1096J1027D01*
G37*
G36*
G01X370369D02*
G02X373373I1502J0D01*
G02X372967Y84166I-1502J0D01*
G01X372941Y84139D01*
X372913Y84068D01*
Y83718D01*
X372941Y83647D01*
X372967Y83620D01*
G02Y81566I-1096J-1027D01*
G01X372941Y81539D01*
X372913Y81468D01*
Y81118D01*
X372941Y81047D01*
X372967Y81020D01*
G02Y78966I-1096J-1027D01*
G01X372941Y78939D01*
X372913Y78868D01*
Y78518D01*
X372941Y78447D01*
X372967Y78420D01*
G02Y76366I-1096J-1027D01*
G01X372941Y76339D01*
X372913Y76268D01*
Y75918D01*
X372941Y75847D01*
X372967Y75820D01*
G02X373373Y74793I-1096J-1027D01*
G02X370369I-1502J0D01*
G02X370775Y75820I1502J0D01*
G01X370801Y75847D01*
X370829Y75918D01*
Y76268D01*
X370801Y76339D01*
X370775Y76366D01*
G02Y78420I1096J1027D01*
G01X370801Y78447D01*
X370829Y78518D01*
Y78868D01*
X370801Y78939D01*
X370775Y78966D01*
G02Y81020I1096J1027D01*
G01X370801Y81047D01*
X370829Y81118D01*
Y81468D01*
X370801Y81539D01*
X370775Y81566D01*
G02Y83620I1096J1027D01*
G01X370801Y83647D01*
X370829Y83718D01*
Y84068D01*
X370801Y84139D01*
X370775Y84166D01*
G02X370369Y85193I1096J1027D01*
G37*
G36*
G01X520370D02*
G02X523374I1502J0D01*
G02X522968Y84166I-1502J0D01*
G01X522942Y84139D01*
X522914Y84068D01*
Y83718D01*
X522942Y83647D01*
X522968Y83620D01*
G02Y81566I-1096J-1027D01*
G01X522942Y81539D01*
X522914Y81468D01*
Y81118D01*
X522942Y81047D01*
X522968Y81020D01*
G02Y78966I-1096J-1027D01*
G01X522942Y78939D01*
X522914Y78868D01*
Y78518D01*
X522942Y78447D01*
X522968Y78420D01*
G02Y76366I-1096J-1027D01*
G01X522942Y76339D01*
X522914Y76268D01*
Y75918D01*
X522942Y75847D01*
X522968Y75820D01*
G02X523374Y74793I-1096J-1027D01*
G02X520370I-1502J0D01*
G02X520776Y75820I1502J0D01*
G01X520802Y75847D01*
X520830Y75918D01*
Y76268D01*
X520802Y76339D01*
X520776Y76366D01*
G02Y78420I1096J1027D01*
G01X520802Y78447D01*
X520830Y78518D01*
Y78868D01*
X520802Y78939D01*
X520776Y78966D01*
G02Y81020I1096J1027D01*
G01X520802Y81047D01*
X520830Y81118D01*
Y81468D01*
X520802Y81539D01*
X520776Y81566D01*
G02Y83620I1096J1027D01*
G01X520802Y83647D01*
X520830Y83718D01*
Y84068D01*
X520802Y84139D01*
X520776Y84166D01*
G02X520370Y85193I1096J1027D01*
G37*
G36*
G01X622732D02*
G02X625736I1502J0D01*
G02X625330Y84166I-1502J0D01*
G01X625304Y84139D01*
X625276Y84068D01*
Y83718D01*
X625304Y83647D01*
X625330Y83620D01*
G02Y81566I-1096J-1027D01*
G01X625304Y81539D01*
X625276Y81468D01*
Y81118D01*
X625304Y81047D01*
X625330Y81020D01*
G02Y78966I-1096J-1027D01*
G01X625304Y78939D01*
X625276Y78868D01*
Y78518D01*
X625304Y78447D01*
X625330Y78420D01*
G02Y76366I-1096J-1027D01*
G01X625304Y76339D01*
X625276Y76268D01*
Y75918D01*
X625304Y75847D01*
X625330Y75820D01*
G02X625736Y74793I-1096J-1027D01*
G02X622732I-1502J0D01*
G02X623138Y75820I1502J0D01*
G01X623164Y75847D01*
X623192Y75918D01*
Y76268D01*
X623164Y76339D01*
X623138Y76366D01*
G02Y78420I1096J1027D01*
G01X623164Y78447D01*
X623192Y78518D01*
Y78868D01*
X623164Y78939D01*
X623138Y78966D01*
G02Y81020I1096J1027D01*
G01X623164Y81047D01*
X623192Y81118D01*
Y81468D01*
X623164Y81539D01*
X623138Y81566D01*
G02Y83620I1096J1027D01*
G01X623164Y83647D01*
X623192Y83718D01*
Y84068D01*
X623164Y84139D01*
X623138Y84166D01*
G02X622732Y85193I1096J1027D01*
G37*
G36*
G01X725094D02*
G02X728098I1502J0D01*
G02X727692Y84166I-1502J0D01*
G01X727666Y84139D01*
X727638Y84068D01*
Y83718D01*
X727666Y83647D01*
X727692Y83620D01*
G02Y81566I-1096J-1027D01*
G01X727666Y81539D01*
X727638Y81468D01*
Y81118D01*
X727666Y81047D01*
X727692Y81020D01*
G02Y78966I-1096J-1027D01*
G01X727666Y78939D01*
X727638Y78868D01*
Y78518D01*
X727666Y78447D01*
X727692Y78420D01*
G02Y76366I-1096J-1027D01*
G01X727666Y76339D01*
X727638Y76268D01*
Y75918D01*
X727666Y75847D01*
X727692Y75820D01*
G02X728098Y74793I-1096J-1027D01*
G02X725094I-1502J0D01*
G02X725500Y75820I1502J0D01*
G01X725526Y75847D01*
X725554Y75918D01*
Y76268D01*
X725526Y76339D01*
X725500Y76366D01*
G02Y78420I1096J1027D01*
G01X725526Y78447D01*
X725554Y78518D01*
Y78868D01*
X725526Y78939D01*
X725500Y78966D01*
G02Y81020I1096J1027D01*
G01X725526Y81047D01*
X725554Y81118D01*
Y81468D01*
X725526Y81539D01*
X725500Y81566D01*
G02Y83620I1096J1027D01*
G01X725526Y83647D01*
X725554Y83718D01*
Y84068D01*
X725526Y84139D01*
X725500Y84166D01*
G02X725094Y85193I1096J1027D01*
G37*
G36*
G01X827456D02*
G02X830460I1502J0D01*
G02X830054Y84166I-1502J0D01*
G01X830028Y84139D01*
X830000Y84068D01*
Y83718D01*
X830028Y83647D01*
X830054Y83620D01*
G02Y81566I-1096J-1027D01*
G01X830028Y81539D01*
X830000Y81468D01*
Y81118D01*
X830028Y81047D01*
X830054Y81020D01*
G02Y78966I-1096J-1027D01*
G01X830028Y78939D01*
X830000Y78868D01*
Y78518D01*
X830028Y78447D01*
X830054Y78420D01*
G02Y76366I-1096J-1027D01*
G01X830028Y76339D01*
X830000Y76268D01*
Y75918D01*
X830028Y75847D01*
X830054Y75820D01*
G02X830460Y74793I-1096J-1027D01*
G02X827456I-1502J0D01*
G02X827862Y75820I1502J0D01*
G01X827888Y75847D01*
X827916Y75918D01*
Y76268D01*
X827888Y76339D01*
X827862Y76366D01*
G02Y78420I1096J1027D01*
G01X827888Y78447D01*
X827916Y78518D01*
Y78868D01*
X827888Y78939D01*
X827862Y78966D01*
G02Y81020I1096J1027D01*
G01X827888Y81047D01*
X827916Y81118D01*
Y81468D01*
X827888Y81539D01*
X827862Y81566D01*
G02Y83620I1096J1027D01*
G01X827888Y83647D01*
X827916Y83718D01*
Y84068D01*
X827888Y84139D01*
X827862Y84166D01*
G02X827456Y85193I1096J1027D01*
G37*
G36*
G01X977456D02*
G02X980460I1502J0D01*
G02X980054Y84166I-1502J0D01*
G01X980028Y84139D01*
X980000Y84068D01*
Y83718D01*
X980028Y83647D01*
X980054Y83620D01*
G02Y81566I-1096J-1027D01*
G01X980028Y81539D01*
X980000Y81468D01*
Y81118D01*
X980028Y81047D01*
X980054Y81020D01*
G02Y78966I-1096J-1027D01*
G01X980028Y78939D01*
X980000Y78868D01*
Y78518D01*
X980028Y78447D01*
X980054Y78420D01*
G02Y76366I-1096J-1027D01*
G01X980028Y76339D01*
X980000Y76268D01*
Y75918D01*
X980028Y75847D01*
X980054Y75820D01*
G02X980460Y74793I-1096J-1027D01*
G02X977456I-1502J0D01*
G02X977862Y75820I1502J0D01*
G01X977888Y75847D01*
X977916Y75918D01*
Y76268D01*
X977888Y76339D01*
X977862Y76366D01*
G02Y78420I1096J1027D01*
G01X977888Y78447D01*
X977916Y78518D01*
Y78868D01*
X977888Y78939D01*
X977862Y78966D01*
G02Y81020I1096J1027D01*
G01X977888Y81047D01*
X977916Y81118D01*
Y81468D01*
X977888Y81539D01*
X977862Y81566D01*
G02Y83620I1096J1027D01*
G01X977888Y83647D01*
X977916Y83718D01*
Y84068D01*
X977888Y84139D01*
X977862Y84166D01*
G02X977456Y85193I1096J1027D01*
G37*
G36*
G01X1079818D02*
G02X1082822I1502J0D01*
G02X1082416Y84166I-1502J0D01*
G01X1082390Y84139D01*
X1082362Y84068D01*
Y83718D01*
X1082390Y83647D01*
X1082416Y83620D01*
G02Y81566I-1096J-1027D01*
G01X1082390Y81539D01*
X1082362Y81468D01*
Y81118D01*
X1082390Y81047D01*
X1082416Y81020D01*
G02Y78966I-1096J-1027D01*
G01X1082390Y78939D01*
X1082362Y78868D01*
Y78518D01*
X1082390Y78447D01*
X1082416Y78420D01*
G02Y76366I-1096J-1027D01*
G01X1082390Y76339D01*
X1082362Y76268D01*
Y75918D01*
X1082390Y75847D01*
X1082416Y75820D01*
G02X1082822Y74793I-1096J-1027D01*
G02X1079818I-1502J0D01*
G02X1080224Y75820I1502J0D01*
G01X1080250Y75847D01*
X1080278Y75918D01*
Y76268D01*
X1080250Y76339D01*
X1080224Y76366D01*
G02Y78420I1096J1027D01*
G01X1080250Y78447D01*
X1080278Y78518D01*
Y78868D01*
X1080250Y78939D01*
X1080224Y78966D01*
G02Y81020I1096J1027D01*
G01X1080250Y81047D01*
X1080278Y81118D01*
Y81468D01*
X1080250Y81539D01*
X1080224Y81566D01*
G02Y83620I1096J1027D01*
G01X1080250Y83647D01*
X1080278Y83718D01*
Y84068D01*
X1080250Y84139D01*
X1080224Y84166D01*
G02X1079818Y85193I1096J1027D01*
G37*
G36*
G01X1182180D02*
G02X1185184I1502J0D01*
G02X1184778Y84166I-1502J0D01*
G01X1184752Y84139D01*
X1184724Y84068D01*
Y83718D01*
X1184752Y83647D01*
X1184778Y83620D01*
G02Y81566I-1096J-1027D01*
G01X1184752Y81539D01*
X1184724Y81468D01*
Y81118D01*
X1184752Y81047D01*
X1184778Y81020D01*
G02Y78966I-1096J-1027D01*
G01X1184752Y78939D01*
X1184724Y78868D01*
Y78518D01*
X1184752Y78447D01*
X1184778Y78420D01*
G02Y76366I-1096J-1027D01*
G01X1184752Y76339D01*
X1184724Y76268D01*
Y75918D01*
X1184752Y75847D01*
X1184778Y75820D01*
G02X1185184Y74793I-1096J-1027D01*
G02X1182180I-1502J0D01*
G02X1182586Y75820I1502J0D01*
G01X1182612Y75847D01*
X1182640Y75918D01*
Y76268D01*
X1182612Y76339D01*
X1182586Y76366D01*
G02Y78420I1096J1027D01*
G01X1182612Y78447D01*
X1182640Y78518D01*
Y78868D01*
X1182612Y78939D01*
X1182586Y78966D01*
G02Y81020I1096J1027D01*
G01X1182612Y81047D01*
X1182640Y81118D01*
Y81468D01*
X1182612Y81539D01*
X1182586Y81566D01*
G02Y83620I1096J1027D01*
G01X1182612Y83647D01*
X1182640Y83718D01*
Y84068D01*
X1182612Y84139D01*
X1182586Y84166D01*
G02X1182180Y85193I1096J1027D01*
G37*
G36*
G01X1434543D02*
G02X1437547I1502J0D01*
G02X1437141Y84166I-1502J0D01*
G01X1437115Y84139D01*
X1437087Y84068D01*
Y83718D01*
X1437115Y83647D01*
X1437141Y83620D01*
G02Y81566I-1096J-1027D01*
G01X1437115Y81539D01*
X1437087Y81468D01*
Y81118D01*
X1437115Y81047D01*
X1437141Y81020D01*
G02Y78966I-1096J-1027D01*
G01X1437115Y78939D01*
X1437087Y78868D01*
Y78518D01*
X1437115Y78447D01*
X1437141Y78420D01*
G02Y76366I-1096J-1027D01*
G01X1437115Y76339D01*
X1437087Y76268D01*
Y75918D01*
X1437115Y75847D01*
X1437141Y75820D01*
G02X1437547Y74793I-1096J-1027D01*
G02X1434543I-1502J0D01*
G02X1434949Y75820I1502J0D01*
G01X1434975Y75847D01*
X1435003Y75918D01*
Y76268D01*
X1434975Y76339D01*
X1434949Y76366D01*
G02Y78420I1096J1027D01*
G01X1434975Y78447D01*
X1435003Y78518D01*
Y78868D01*
X1434975Y78939D01*
X1434949Y78966D01*
G02Y81020I1096J1027D01*
G01X1434975Y81047D01*
X1435003Y81118D01*
Y81468D01*
X1434975Y81539D01*
X1434949Y81566D01*
G02Y83620I1096J1027D01*
G01X1434975Y83647D01*
X1435003Y83718D01*
Y84068D01*
X1434975Y84139D01*
X1434949Y84166D01*
G02X1434543Y85193I1096J1027D01*
G37*
G36*
G01X1284542Y85539D02*
G02X1287546I1502J0D01*
G02X1287140Y84512I-1502J0D01*
G01X1287114Y84485D01*
X1287086Y84414D01*
Y84064D01*
X1287114Y83993D01*
X1287140Y83966D01*
G02Y81912I-1096J-1027D01*
G01X1287114Y81885D01*
X1287086Y81814D01*
Y81464D01*
X1287114Y81393D01*
X1287140Y81366D01*
G02Y79312I-1096J-1027D01*
G01X1287114Y79285D01*
X1287086Y79214D01*
Y78864D01*
X1287114Y78793D01*
X1287140Y78766D01*
G02Y76712I-1096J-1027D01*
G01X1287114Y76685D01*
X1287086Y76614D01*
Y76264D01*
X1287114Y76193D01*
X1287140Y76166D01*
G02X1287546Y75139I-1096J-1027D01*
G02X1284542I-1502J0D01*
G02X1284948Y76166I1502J0D01*
G01X1284974Y76193D01*
X1285002Y76264D01*
Y76614D01*
X1284974Y76685D01*
X1284948Y76712D01*
G02Y78766I1096J1027D01*
G01X1284974Y78793D01*
X1285002Y78864D01*
Y79214D01*
X1284974Y79285D01*
X1284948Y79312D01*
G02Y81366I1096J1027D01*
G01X1284974Y81393D01*
X1285002Y81464D01*
Y81814D01*
X1284974Y81885D01*
X1284948Y81912D01*
G02Y83966I1096J1027D01*
G01X1284974Y83993D01*
X1285002Y84064D01*
Y84414D01*
X1284974Y84485D01*
X1284948Y84512D01*
G02X1284542Y85539I1096J1027D01*
G37*
G36*
G01X1536905D02*
G02X1539909I1502J0D01*
G02X1539503Y84512I-1502J0D01*
G01X1539477Y84485D01*
X1539449Y84414D01*
Y84064D01*
X1539477Y83993D01*
X1539503Y83966D01*
G02Y81912I-1096J-1027D01*
G01X1539477Y81885D01*
X1539449Y81814D01*
Y81464D01*
X1539477Y81393D01*
X1539503Y81366D01*
G02Y79312I-1096J-1027D01*
G01X1539477Y79285D01*
X1539449Y79214D01*
Y78864D01*
X1539477Y78793D01*
X1539503Y78766D01*
G02Y76712I-1096J-1027D01*
G01X1539477Y76685D01*
X1539449Y76614D01*
Y76264D01*
X1539477Y76193D01*
X1539503Y76166D01*
G02X1539909Y75139I-1096J-1027D01*
G02X1536905I-1502J0D01*
G02X1537311Y76166I1502J0D01*
G01X1537337Y76193D01*
X1537365Y76264D01*
Y76614D01*
X1537337Y76685D01*
X1537311Y76712D01*
G02Y78766I1096J1027D01*
G01X1537337Y78793D01*
X1537365Y78864D01*
Y79214D01*
X1537337Y79285D01*
X1537311Y79312D01*
G02Y81366I1096J1027D01*
G01X1537337Y81393D01*
X1537365Y81464D01*
Y81814D01*
X1537337Y81885D01*
X1537311Y81912D01*
G02Y83966I1096J1027D01*
G01X1537337Y83993D01*
X1537365Y84064D01*
Y84414D01*
X1537337Y84485D01*
X1537311Y84512D01*
G02X1536905Y85539I1096J1027D01*
G37*
G36*
G01X1639267D02*
G02X1642271I1502J0D01*
G02X1641865Y84512I-1502J0D01*
G01X1641839Y84485D01*
X1641811Y84414D01*
Y84064D01*
X1641839Y83993D01*
X1641865Y83966D01*
G02Y81912I-1096J-1027D01*
G01X1641839Y81885D01*
X1641811Y81814D01*
Y81464D01*
X1641839Y81393D01*
X1641865Y81366D01*
G02Y79312I-1096J-1027D01*
G01X1641839Y79285D01*
X1641811Y79214D01*
Y78864D01*
X1641839Y78793D01*
X1641865Y78766D01*
G02Y76712I-1096J-1027D01*
G01X1641839Y76685D01*
X1641811Y76614D01*
Y76264D01*
X1641839Y76193D01*
X1641865Y76166D01*
G02X1642271Y75139I-1096J-1027D01*
G02X1639267I-1502J0D01*
G02X1639673Y76166I1502J0D01*
G01X1639699Y76193D01*
X1639727Y76264D01*
Y76614D01*
X1639699Y76685D01*
X1639673Y76712D01*
G02Y78766I1096J1027D01*
G01X1639699Y78793D01*
X1639727Y78864D01*
Y79214D01*
X1639699Y79285D01*
X1639673Y79312D01*
G02Y81366I1096J1027D01*
G01X1639699Y81393D01*
X1639727Y81464D01*
Y81814D01*
X1639699Y81885D01*
X1639673Y81912D01*
G02Y83966I1096J1027D01*
G01X1639699Y83993D01*
X1639727Y84064D01*
Y84414D01*
X1639699Y84485D01*
X1639673Y84512D01*
G02X1639267Y85539I1096J1027D01*
G37*
G36*
G01X1741629D02*
G02X1744633I1502J0D01*
G02X1744227Y84512I-1502J0D01*
G01X1744201Y84485D01*
X1744173Y84414D01*
Y84064D01*
X1744201Y83993D01*
X1744227Y83966D01*
G02Y81912I-1096J-1027D01*
G01X1744201Y81885D01*
X1744173Y81814D01*
Y81464D01*
X1744201Y81393D01*
X1744227Y81366D01*
G02Y79312I-1096J-1027D01*
G01X1744201Y79285D01*
X1744173Y79214D01*
Y78864D01*
X1744201Y78793D01*
X1744227Y78766D01*
G02Y76712I-1096J-1027D01*
G01X1744201Y76685D01*
X1744173Y76614D01*
Y76264D01*
X1744201Y76193D01*
X1744227Y76166D01*
G02X1744633Y75139I-1096J-1027D01*
G02X1741629I-1502J0D01*
G02X1742035Y76166I1502J0D01*
G01X1742061Y76193D01*
X1742089Y76264D01*
Y76614D01*
X1742061Y76685D01*
X1742035Y76712D01*
G02Y78766I1096J1027D01*
G01X1742061Y78793D01*
X1742089Y78864D01*
Y79214D01*
X1742061Y79285D01*
X1742035Y79312D01*
G02Y81366I1096J1027D01*
G01X1742061Y81393D01*
X1742089Y81464D01*
Y81814D01*
X1742061Y81885D01*
X1742035Y81912D01*
G02Y83966I1096J1027D01*
G01X1742061Y83993D01*
X1742089Y84064D01*
Y84414D01*
X1742061Y84485D01*
X1742035Y84512D01*
G02X1741629Y85539I1096J1027D01*
G37*
G36*
G01X106518Y117937D02*
Y118251D01*
G03X106441Y118409I-200J0D01*
G02X105862Y119594I923J1185D01*
G02X108866I1502J0D01*
G02X108287Y118409I-1502J0D01*
G03X108210Y118251I123J-158D01*
G01Y117937D01*
G03X108287Y117779I200J0D01*
G02X108866Y116594I-923J-1185D01*
G02X105862I-1502J0D01*
G02X106441Y117779I1502J0D01*
G03X106518Y117937I-123J158D01*
G37*
G36*
G01X118487D02*
Y118251D01*
G03X118410Y118409I-200J0D01*
G02X117831Y119594I923J1185D01*
G02X120835I1502J0D01*
G02X120256Y118409I-1502J0D01*
G03X120179Y118251I123J-158D01*
G01Y117937D01*
G03X120256Y117779I200J0D01*
G02X120835Y116594I-923J-1185D01*
G02X117831I-1502J0D01*
G02X118410Y117779I1502J0D01*
G03X118487Y117937I-123J158D01*
G37*
G36*
G01X208880D02*
Y118251D01*
G03X208803Y118409I-200J0D01*
G02X208224Y119594I923J1185D01*
G02X211228I1502J0D01*
G02X210649Y118409I-1502J0D01*
G03X210572Y118251I123J-158D01*
G01Y117937D01*
G03X210649Y117779I200J0D01*
G02X211228Y116594I-923J-1185D01*
G02X208224I-1502J0D01*
G02X208803Y117779I1502J0D01*
G03X208880Y117937I-123J158D01*
G37*
G36*
G01X220849D02*
Y118251D01*
G03X220772Y118409I-200J0D01*
G02X220193Y119594I923J1185D01*
G02X223197I1502J0D01*
G02X222618Y118409I-1502J0D01*
G03X222541Y118251I123J-158D01*
G01Y117937D01*
G03X222618Y117779I200J0D01*
G02X223197Y116594I-923J-1185D01*
G02X220193I-1502J0D01*
G02X220772Y117779I1502J0D01*
G03X220849Y117937I-123J158D01*
G37*
G36*
G01X311242D02*
Y118251D01*
G03X311165Y118409I-200J0D01*
G02X310586Y119594I923J1185D01*
G02X313590I1502J0D01*
G02X313011Y118409I-1502J0D01*
G03X312934Y118251I123J-158D01*
G01Y117937D01*
G03X313011Y117779I200J0D01*
G02X313590Y116594I-923J-1185D01*
G02X310586I-1502J0D01*
G02X311165Y117779I1502J0D01*
G03X311242Y117937I-123J158D01*
G37*
G36*
G01X323211D02*
Y118251D01*
G03X323134Y118409I-200J0D01*
G02X322555Y119594I923J1185D01*
G02X325559I1502J0D01*
G02X324980Y118409I-1502J0D01*
G03X324903Y118251I123J-158D01*
G01Y117937D01*
G03X324980Y117779I200J0D01*
G02X325559Y116594I-923J-1185D01*
G02X322555I-1502J0D01*
G02X323134Y117779I1502J0D01*
G03X323211Y117937I-123J158D01*
G37*
G36*
G01X461243D02*
Y118251D01*
G03X461166Y118409I-200J0D01*
G02X460587Y119594I923J1185D01*
G02X463591I1502J0D01*
G02X463012Y118409I-1502J0D01*
G03X462935Y118251I123J-158D01*
G01Y117937D01*
G03X463012Y117779I200J0D01*
G02X463591Y116594I-923J-1185D01*
G02X460587I-1502J0D01*
G02X461166Y117779I1502J0D01*
G03X461243Y117937I-123J158D01*
G37*
G36*
G01X473212D02*
Y118251D01*
G03X473135Y118409I-200J0D01*
G02X472556Y119594I923J1185D01*
G02X475560I1502J0D01*
G02X474981Y118409I-1502J0D01*
G03X474904Y118251I123J-158D01*
G01Y117937D01*
G03X474981Y117779I200J0D01*
G02X475560Y116594I-923J-1185D01*
G02X472556I-1502J0D01*
G02X473135Y117779I1502J0D01*
G03X473212Y117937I-123J158D01*
G37*
G36*
G01X563605D02*
Y118251D01*
G03X563528Y118409I-200J0D01*
G02X562949Y119594I923J1185D01*
G02X565953I1502J0D01*
G02X565374Y118409I-1502J0D01*
G03X565297Y118251I123J-158D01*
G01Y117937D01*
G03X565374Y117779I200J0D01*
G02X565953Y116594I-923J-1185D01*
G02X562949I-1502J0D01*
G02X563528Y117779I1502J0D01*
G03X563605Y117937I-123J158D01*
G37*
G36*
G01X575574D02*
Y118251D01*
G03X575497Y118409I-200J0D01*
G02X574918Y119594I923J1185D01*
G02X577922I1502J0D01*
G02X577343Y118409I-1502J0D01*
G03X577266Y118251I123J-158D01*
G01Y117937D01*
G03X577343Y117779I200J0D01*
G02X577922Y116594I-923J-1185D01*
G02X574918I-1502J0D01*
G02X575497Y117779I1502J0D01*
G03X575574Y117937I-123J158D01*
G37*
G36*
G01X665967D02*
Y118251D01*
G03X665890Y118409I-200J0D01*
G02X665311Y119594I923J1185D01*
G02X668315I1502J0D01*
G02X667736Y118409I-1502J0D01*
G03X667659Y118251I123J-158D01*
G01Y117937D01*
G03X667736Y117779I200J0D01*
G02X668315Y116594I-923J-1185D01*
G02X665311I-1502J0D01*
G02X665890Y117779I1502J0D01*
G03X665967Y117937I-123J158D01*
G37*
G36*
G01X677936D02*
Y118251D01*
G03X677859Y118409I-200J0D01*
G02X677280Y119594I923J1185D01*
G02X680284I1502J0D01*
G02X679705Y118409I-1502J0D01*
G03X679628Y118251I123J-158D01*
G01Y117937D01*
G03X679705Y117779I200J0D01*
G02X680284Y116594I-923J-1185D01*
G02X677280I-1502J0D01*
G02X677859Y117779I1502J0D01*
G03X677936Y117937I-123J158D01*
G37*
G36*
G01X768329D02*
Y118251D01*
G03X768252Y118409I-200J0D01*
G02X767673Y119594I923J1185D01*
G02X770677I1502J0D01*
G02X770098Y118409I-1502J0D01*
G03X770021Y118251I123J-158D01*
G01Y117937D01*
G03X770098Y117779I200J0D01*
G02X770677Y116594I-923J-1185D01*
G02X767673I-1502J0D01*
G02X768252Y117779I1502J0D01*
G03X768329Y117937I-123J158D01*
G37*
G36*
G01X780298D02*
Y118251D01*
G03X780221Y118409I-200J0D01*
G02X779642Y119594I923J1185D01*
G02X782646I1502J0D01*
G02X782067Y118409I-1502J0D01*
G03X781990Y118251I123J-158D01*
G01Y117937D01*
G03X782067Y117779I200J0D01*
G02X782646Y116594I-923J-1185D01*
G02X779642I-1502J0D01*
G02X780221Y117779I1502J0D01*
G03X780298Y117937I-123J158D01*
G37*
G36*
G01X918329D02*
Y118251D01*
G03X918252Y118409I-200J0D01*
G02X917673Y119594I923J1185D01*
G02X920677I1502J0D01*
G02X920098Y118409I-1502J0D01*
G03X920021Y118251I123J-158D01*
G01Y117937D01*
G03X920098Y117779I200J0D01*
G02X920677Y116594I-923J-1185D01*
G02X917673I-1502J0D01*
G02X918252Y117779I1502J0D01*
G03X918329Y117937I-123J158D01*
G37*
G36*
G01X930298D02*
Y118251D01*
G03X930221Y118409I-200J0D01*
G02X929642Y119594I923J1185D01*
G02X932646I1502J0D01*
G02X932067Y118409I-1502J0D01*
G03X931990Y118251I123J-158D01*
G01Y117937D01*
G03X932067Y117779I200J0D01*
G02X932646Y116594I-923J-1185D01*
G02X929642I-1502J0D01*
G02X930221Y117779I1502J0D01*
G03X930298Y117937I-123J158D01*
G37*
G36*
G01X1020691D02*
Y118251D01*
G03X1020614Y118409I-200J0D01*
G02X1020035Y119594I923J1185D01*
G02X1023039I1502J0D01*
G02X1022460Y118409I-1502J0D01*
G03X1022383Y118251I123J-158D01*
G01Y117937D01*
G03X1022460Y117779I200J0D01*
G02X1023039Y116594I-923J-1185D01*
G02X1020035I-1502J0D01*
G02X1020614Y117779I1502J0D01*
G03X1020691Y117937I-123J158D01*
G37*
G36*
G01X1032660D02*
Y118251D01*
G03X1032583Y118409I-200J0D01*
G02X1032004Y119594I923J1185D01*
G02X1035008I1502J0D01*
G02X1034429Y118409I-1502J0D01*
G03X1034352Y118251I123J-158D01*
G01Y117937D01*
G03X1034429Y117779I200J0D01*
G02X1035008Y116594I-923J-1185D01*
G02X1032004I-1502J0D01*
G02X1032583Y117779I1502J0D01*
G03X1032660Y117937I-123J158D01*
G37*
G36*
G01X1123053D02*
Y118251D01*
G03X1122976Y118409I-200J0D01*
G02X1122397Y119594I923J1185D01*
G02X1125401I1502J0D01*
G02X1124822Y118409I-1502J0D01*
G03X1124745Y118251I123J-158D01*
G01Y117937D01*
G03X1124822Y117779I200J0D01*
G02X1125401Y116594I-923J-1185D01*
G02X1122397I-1502J0D01*
G02X1122976Y117779I1502J0D01*
G03X1123053Y117937I-123J158D01*
G37*
G36*
G01X1135022D02*
Y118251D01*
G03X1134945Y118409I-200J0D01*
G02X1134366Y119594I923J1185D01*
G02X1137370I1502J0D01*
G02X1136791Y118409I-1502J0D01*
G03X1136714Y118251I123J-158D01*
G01Y117937D01*
G03X1136791Y117779I200J0D01*
G02X1137370Y116594I-923J-1185D01*
G02X1134366I-1502J0D01*
G02X1134945Y117779I1502J0D01*
G03X1135022Y117937I-123J158D01*
G37*
G36*
G01X1225415D02*
Y118251D01*
G03X1225338Y118409I-200J0D01*
G02X1224759Y119594I923J1185D01*
G02X1227763I1502J0D01*
G02X1227184Y118409I-1502J0D01*
G03X1227107Y118251I123J-158D01*
G01Y117937D01*
G03X1227184Y117779I200J0D01*
G02X1227763Y116594I-923J-1185D01*
G02X1224759I-1502J0D01*
G02X1225338Y117779I1502J0D01*
G03X1225415Y117937I-123J158D01*
G37*
G36*
G01X1237384D02*
Y118251D01*
G03X1237307Y118409I-200J0D01*
G02X1236728Y119594I923J1185D01*
G02X1239732I1502J0D01*
G02X1239153Y118409I-1502J0D01*
G03X1239076Y118251I123J-158D01*
G01Y117937D01*
G03X1239153Y117779I200J0D01*
G02X1239732Y116594I-923J-1185D01*
G02X1236728I-1502J0D01*
G02X1237307Y117779I1502J0D01*
G03X1237384Y117937I-123J158D01*
G37*
G36*
G01X1375416D02*
Y118251D01*
G03X1375339Y118409I-200J0D01*
G02X1374760Y119594I923J1185D01*
G02X1377764I1502J0D01*
G02X1377185Y118409I-1502J0D01*
G03X1377108Y118251I123J-158D01*
G01Y117937D01*
G03X1377185Y117779I200J0D01*
G02X1377764Y116594I-923J-1185D01*
G02X1374760I-1502J0D01*
G02X1375339Y117779I1502J0D01*
G03X1375416Y117937I-123J158D01*
G37*
G36*
G01X1387385D02*
Y118251D01*
G03X1387308Y118409I-200J0D01*
G02X1386729Y119594I923J1185D01*
G02X1389733I1502J0D01*
G02X1389154Y118409I-1502J0D01*
G03X1389077Y118251I123J-158D01*
G01Y117937D01*
G03X1389154Y117779I200J0D01*
G02X1389733Y116594I-923J-1185D01*
G02X1386729I-1502J0D01*
G02X1387308Y117779I1502J0D01*
G03X1387385Y117937I-123J158D01*
G37*
G36*
G01X1477778D02*
Y118251D01*
G03X1477701Y118409I-200J0D01*
G02X1477122Y119594I923J1185D01*
G02X1480126I1502J0D01*
G02X1479547Y118409I-1502J0D01*
G03X1479470Y118251I123J-158D01*
G01Y117937D01*
G03X1479547Y117779I200J0D01*
G02X1480126Y116594I-923J-1185D01*
G02X1477122I-1502J0D01*
G02X1477701Y117779I1502J0D01*
G03X1477778Y117937I-123J158D01*
G37*
G36*
G01X1489747D02*
Y118251D01*
G03X1489670Y118409I-200J0D01*
G02X1489091Y119594I923J1185D01*
G02X1492095I1502J0D01*
G02X1491516Y118409I-1502J0D01*
G03X1491439Y118251I123J-158D01*
G01Y117937D01*
G03X1491516Y117779I200J0D01*
G02X1492095Y116594I-923J-1185D01*
G02X1489091I-1502J0D01*
G02X1489670Y117779I1502J0D01*
G03X1489747Y117937I-123J158D01*
G37*
G36*
G01X1580140D02*
Y118251D01*
G03X1580063Y118409I-200J0D01*
G02X1579484Y119594I923J1185D01*
G02X1582488I1502J0D01*
G02X1581909Y118409I-1502J0D01*
G03X1581832Y118251I123J-158D01*
G01Y117937D01*
G03X1581909Y117779I200J0D01*
G02X1582488Y116594I-923J-1185D01*
G02X1579484I-1502J0D01*
G02X1580063Y117779I1502J0D01*
G03X1580140Y117937I-123J158D01*
G37*
G36*
G01X1592109D02*
Y118251D01*
G03X1592032Y118409I-200J0D01*
G02X1591453Y119594I923J1185D01*
G02X1594457I1502J0D01*
G02X1593878Y118409I-1502J0D01*
G03X1593801Y118251I123J-158D01*
G01Y117937D01*
G03X1593878Y117779I200J0D01*
G02X1594457Y116594I-923J-1185D01*
G02X1591453I-1502J0D01*
G02X1592032Y117779I1502J0D01*
G03X1592109Y117937I-123J158D01*
G37*
G36*
G01X1682502D02*
Y118251D01*
G03X1682425Y118409I-200J0D01*
G02X1681846Y119594I923J1185D01*
G02X1684850I1502J0D01*
G02X1684271Y118409I-1502J0D01*
G03X1684194Y118251I123J-158D01*
G01Y117937D01*
G03X1684271Y117779I200J0D01*
G02X1684850Y116594I-923J-1185D01*
G02X1681846I-1502J0D01*
G02X1682425Y117779I1502J0D01*
G03X1682502Y117937I-123J158D01*
G37*
G36*
G01X1694471D02*
Y118251D01*
G03X1694394Y118409I-200J0D01*
G02X1693815Y119594I923J1185D01*
G02X1696819I1502J0D01*
G02X1696240Y118409I-1502J0D01*
G03X1696163Y118251I123J-158D01*
G01Y117937D01*
G03X1696240Y117779I200J0D01*
G02X1696819Y116594I-923J-1185D01*
G02X1693815I-1502J0D01*
G02X1694394Y117779I1502J0D01*
G03X1694471Y117937I-123J158D01*
G37*
G36*
G01X10120Y160416D02*
Y160730D01*
G03X10043Y160888I-200J0D01*
G02X9464Y162073I923J1185D01*
G02X12468I1502J0D01*
G02X11889Y160888I-1502J0D01*
G03X11812Y160730I123J-158D01*
G01Y160416D01*
G03X11889Y160258I200J0D01*
G02X12468Y159073I-923J-1185D01*
G02X9464I-1502J0D01*
G02X10043Y160258I1502J0D01*
G03X10120Y160416I-123J158D01*
G37*
G36*
G01X22089D02*
Y160730D01*
G03X22012Y160888I-200J0D01*
G02X21433Y162073I923J1185D01*
G02X24437I1502J0D01*
G02X23858Y160888I-1502J0D01*
G03X23781Y160730I123J-158D01*
G01Y160416D01*
G03X23858Y160258I200J0D01*
G02X24437Y159073I-923J-1185D01*
G02X21433I-1502J0D01*
G02X22012Y160258I1502J0D01*
G03X22089Y160416I-123J158D01*
G37*
G36*
G01X72076Y170493D02*
G02X75080I1502J0D01*
G02X74710Y169506I-1501J0D01*
G01Y169505D01*
X74709D01*
G03X74661Y169375I152J-130D01*
G01Y169111D01*
G03X74709Y168981I200J0D01*
G01X74710Y168980D01*
G02X75080Y167993I-1131J-987D01*
G02X74674Y166966I-1502J0D01*
G01X74648Y166939D01*
X74620Y166868D01*
Y166518D01*
X74648Y166447D01*
X74674Y166420D01*
G02Y164366I-1096J-1027D01*
G01X74648Y164339D01*
X74620Y164268D01*
Y163918D01*
X74648Y163847D01*
X74674Y163820D01*
G02X75080Y162793I-1096J-1027D01*
G02X72076I-1502J0D01*
G02X72482Y163820I1502J0D01*
G01X72508Y163847D01*
X72536Y163918D01*
Y164268D01*
X72508Y164339D01*
X72482Y164366D01*
G02Y166420I1096J1027D01*
G01X72508Y166447D01*
X72536Y166518D01*
Y166868D01*
X72508Y166939D01*
X72482Y166966D01*
G02X72076Y167993I1096J1027D01*
G02X72446Y168980I1501J0D01*
G01Y168981D01*
X72447D01*
G03X72495Y169111I-152J130D01*
G01Y169375D01*
G03X72447Y169505I-200J0D01*
G01X72446Y169506D01*
G02X72076Y170493I1131J987D01*
G37*
G36*
G01X174438D02*
G02X177442I1502J0D01*
G02X177072Y169506I-1501J0D01*
G01Y169505D01*
X177071D01*
G03X177023Y169375I152J-130D01*
G01Y169111D01*
G03X177071Y168981I200J0D01*
G01X177072Y168980D01*
G02X177442Y167993I-1131J-987D01*
G02X177036Y166966I-1502J0D01*
G01X177010Y166939D01*
X176982Y166868D01*
Y166518D01*
X177010Y166447D01*
X177036Y166420D01*
G02Y164366I-1096J-1027D01*
G01X177010Y164339D01*
X176982Y164268D01*
Y163918D01*
X177010Y163847D01*
X177036Y163820D01*
G02X177442Y162793I-1096J-1027D01*
G02X174438I-1502J0D01*
G02X174844Y163820I1502J0D01*
G01X174870Y163847D01*
X174898Y163918D01*
Y164268D01*
X174870Y164339D01*
X174844Y164366D01*
G02Y166420I1096J1027D01*
G01X174870Y166447D01*
X174898Y166518D01*
Y166868D01*
X174870Y166939D01*
X174844Y166966D01*
G02X174438Y167993I1096J1027D01*
G02X174808Y168980I1501J0D01*
G01Y168981D01*
X174809D01*
G03X174857Y169111I-152J130D01*
G01Y169375D01*
G03X174809Y169505I-200J0D01*
G01X174808Y169506D01*
G02X174438Y170493I1131J987D01*
G37*
G36*
G01X276800D02*
G02X279804I1502J0D01*
G02X279434Y169506I-1501J0D01*
G01Y169505D01*
X279433D01*
G03X279385Y169375I152J-130D01*
G01Y169111D01*
G03X279433Y168981I200J0D01*
G01X279434Y168980D01*
G02X279804Y167993I-1131J-987D01*
G02X279398Y166966I-1502J0D01*
G01X279372Y166939D01*
X279344Y166868D01*
Y166518D01*
X279372Y166447D01*
X279398Y166420D01*
G02Y164366I-1096J-1027D01*
G01X279372Y164339D01*
X279344Y164268D01*
Y163918D01*
X279372Y163847D01*
X279398Y163820D01*
G02X279804Y162793I-1096J-1027D01*
G02X276800I-1502J0D01*
G02X277206Y163820I1502J0D01*
G01X277232Y163847D01*
X277260Y163918D01*
Y164268D01*
X277232Y164339D01*
X277206Y164366D01*
G02Y166420I1096J1027D01*
G01X277232Y166447D01*
X277260Y166518D01*
Y166868D01*
X277232Y166939D01*
X277206Y166966D01*
G02X276800Y167993I1096J1027D01*
G02X277170Y168980I1501J0D01*
G01Y168981D01*
X277171D01*
G03X277219Y169111I-152J130D01*
G01Y169375D01*
G03X277171Y169505I-200J0D01*
G01X277170Y169506D01*
G02X276800Y170493I1131J987D01*
G37*
G36*
G01X379162D02*
G02X382166I1502J0D01*
G02X381796Y169506I-1501J0D01*
G01Y169505D01*
X381795D01*
G03X381747Y169375I152J-130D01*
G01Y169111D01*
G03X381795Y168981I200J0D01*
G01X381796Y168980D01*
G02X382166Y167993I-1131J-987D01*
G02X381760Y166966I-1502J0D01*
G01X381734Y166939D01*
X381706Y166868D01*
Y166518D01*
X381734Y166447D01*
X381760Y166420D01*
G02Y164366I-1096J-1027D01*
G01X381734Y164339D01*
X381706Y164268D01*
Y163918D01*
X381734Y163847D01*
X381760Y163820D01*
G02X382166Y162793I-1096J-1027D01*
G02X379162I-1502J0D01*
G02X379568Y163820I1502J0D01*
G01X379594Y163847D01*
X379622Y163918D01*
Y164268D01*
X379594Y164339D01*
X379568Y164366D01*
G02Y166420I1096J1027D01*
G01X379594Y166447D01*
X379622Y166518D01*
Y166868D01*
X379594Y166939D01*
X379568Y166966D01*
G02X379162Y167993I1096J1027D01*
G02X379532Y168980I1501J0D01*
G01Y168981D01*
X379533D01*
G03X379581Y169111I-152J130D01*
G01Y169375D01*
G03X379533Y169505I-200J0D01*
G01X379532Y169506D01*
G02X379162Y170493I1131J987D01*
G37*
G36*
G01X529163D02*
G02X532167I1502J0D01*
G02X531797Y169506I-1501J0D01*
G01Y169505D01*
X531796D01*
G03X531748Y169375I152J-130D01*
G01Y169111D01*
G03X531796Y168981I200J0D01*
G01X531797Y168980D01*
G02X532167Y167993I-1131J-987D01*
G02X531761Y166966I-1502J0D01*
G01X531735Y166939D01*
X531707Y166868D01*
Y166518D01*
X531735Y166447D01*
X531761Y166420D01*
G02Y164366I-1096J-1027D01*
G01X531735Y164339D01*
X531707Y164268D01*
Y163918D01*
X531735Y163847D01*
X531761Y163820D01*
G02X532167Y162793I-1096J-1027D01*
G02X529163I-1502J0D01*
G02X529569Y163820I1502J0D01*
G01X529595Y163847D01*
X529623Y163918D01*
Y164268D01*
X529595Y164339D01*
X529569Y164366D01*
G02Y166420I1096J1027D01*
G01X529595Y166447D01*
X529623Y166518D01*
Y166868D01*
X529595Y166939D01*
X529569Y166966D01*
G02X529163Y167993I1096J1027D01*
G02X529533Y168980I1501J0D01*
G01Y168981D01*
X529534D01*
G03X529582Y169111I-152J130D01*
G01Y169375D01*
G03X529534Y169505I-200J0D01*
G01X529533Y169506D01*
G02X529163Y170493I1131J987D01*
G37*
G36*
G01X631525D02*
G02X634529I1502J0D01*
G02X634159Y169506I-1501J0D01*
G01Y169505D01*
X634158D01*
G03X634110Y169375I152J-130D01*
G01Y169111D01*
G03X634158Y168981I200J0D01*
G01X634159Y168980D01*
G02X634529Y167993I-1131J-987D01*
G02X634123Y166966I-1502J0D01*
G01X634097Y166939D01*
X634069Y166868D01*
Y166518D01*
X634097Y166447D01*
X634123Y166420D01*
G02Y164366I-1096J-1027D01*
G01X634097Y164339D01*
X634069Y164268D01*
Y163918D01*
X634097Y163847D01*
X634123Y163820D01*
G02X634529Y162793I-1096J-1027D01*
G02X631525I-1502J0D01*
G02X631931Y163820I1502J0D01*
G01X631957Y163847D01*
X631985Y163918D01*
Y164268D01*
X631957Y164339D01*
X631931Y164366D01*
G02Y166420I1096J1027D01*
G01X631957Y166447D01*
X631985Y166518D01*
Y166868D01*
X631957Y166939D01*
X631931Y166966D01*
G02X631525Y167993I1096J1027D01*
G02X631895Y168980I1501J0D01*
G01Y168981D01*
X631896D01*
G03X631944Y169111I-152J130D01*
G01Y169375D01*
G03X631896Y169505I-200J0D01*
G01X631895Y169506D01*
G02X631525Y170493I1131J987D01*
G37*
G36*
G01X733887D02*
G02X736891I1502J0D01*
G02X736521Y169506I-1501J0D01*
G01Y169505D01*
X736520D01*
G03X736472Y169375I152J-130D01*
G01Y169111D01*
G03X736520Y168981I200J0D01*
G01X736521Y168980D01*
G02X736891Y167993I-1131J-987D01*
G02X736485Y166966I-1502J0D01*
G01X736459Y166939D01*
X736431Y166868D01*
Y166518D01*
X736459Y166447D01*
X736485Y166420D01*
G02Y164366I-1096J-1027D01*
G01X736459Y164339D01*
X736431Y164268D01*
Y163918D01*
X736459Y163847D01*
X736485Y163820D01*
G02X736891Y162793I-1096J-1027D01*
G02X733887I-1502J0D01*
G02X734293Y163820I1502J0D01*
G01X734319Y163847D01*
X734347Y163918D01*
Y164268D01*
X734319Y164339D01*
X734293Y164366D01*
G02Y166420I1096J1027D01*
G01X734319Y166447D01*
X734347Y166518D01*
Y166868D01*
X734319Y166939D01*
X734293Y166966D01*
G02X733887Y167993I1096J1027D01*
G02X734257Y168980I1501J0D01*
G01Y168981D01*
X734258D01*
G03X734306Y169111I-152J130D01*
G01Y169375D01*
G03X734258Y169505I-200J0D01*
G01X734257Y169506D01*
G02X733887Y170493I1131J987D01*
G37*
G36*
G01X836249D02*
G02X839253I1502J0D01*
G02X838883Y169506I-1501J0D01*
G01Y169505D01*
X838882D01*
G03X838834Y169375I152J-130D01*
G01Y169111D01*
G03X838882Y168981I200J0D01*
G01X838883Y168980D01*
G02X839253Y167993I-1131J-987D01*
G02X838847Y166966I-1502J0D01*
G01X838821Y166939D01*
X838793Y166868D01*
Y166518D01*
X838821Y166447D01*
X838847Y166420D01*
G02Y164366I-1096J-1027D01*
G01X838821Y164339D01*
X838793Y164268D01*
Y163918D01*
X838821Y163847D01*
X838847Y163820D01*
G02X839253Y162793I-1096J-1027D01*
G02X836249I-1502J0D01*
G02X836655Y163820I1502J0D01*
G01X836681Y163847D01*
X836709Y163918D01*
Y164268D01*
X836681Y164339D01*
X836655Y164366D01*
G02Y166420I1096J1027D01*
G01X836681Y166447D01*
X836709Y166518D01*
Y166868D01*
X836681Y166939D01*
X836655Y166966D01*
G02X836249Y167993I1096J1027D01*
G02X836619Y168980I1501J0D01*
G01Y168981D01*
X836620D01*
G03X836668Y169111I-152J130D01*
G01Y169375D01*
G03X836620Y169505I-200J0D01*
G01X836619Y169506D01*
G02X836249Y170493I1131J987D01*
G37*
G36*
G01X986249D02*
G02X989253I1502J0D01*
G02X988883Y169506I-1501J0D01*
G01Y169505D01*
X988882D01*
G03X988834Y169375I152J-130D01*
G01Y169111D01*
G03X988882Y168981I200J0D01*
G01X988883Y168980D01*
G02X989253Y167993I-1131J-987D01*
G02X988847Y166966I-1502J0D01*
G01X988821Y166939D01*
X988793Y166868D01*
Y166518D01*
X988821Y166447D01*
X988847Y166420D01*
G02Y164366I-1096J-1027D01*
G01X988821Y164339D01*
X988793Y164268D01*
Y163918D01*
X988821Y163847D01*
X988847Y163820D01*
G02X989253Y162793I-1096J-1027D01*
G02X986249I-1502J0D01*
G02X986655Y163820I1502J0D01*
G01X986681Y163847D01*
X986709Y163918D01*
Y164268D01*
X986681Y164339D01*
X986655Y164366D01*
G02Y166420I1096J1027D01*
G01X986681Y166447D01*
X986709Y166518D01*
Y166868D01*
X986681Y166939D01*
X986655Y166966D01*
G02X986249Y167993I1096J1027D01*
G02X986619Y168980I1501J0D01*
G01Y168981D01*
X986620D01*
G03X986668Y169111I-152J130D01*
G01Y169375D01*
G03X986620Y169505I-200J0D01*
G01X986619Y169506D01*
G02X986249Y170493I1131J987D01*
G37*
G36*
G01X1088611D02*
G02X1091615I1502J0D01*
G02X1091245Y169506I-1501J0D01*
G01Y169505D01*
X1091244D01*
G03X1091196Y169375I152J-130D01*
G01Y169111D01*
G03X1091244Y168981I200J0D01*
G01X1091245Y168980D01*
G02X1091615Y167993I-1131J-987D01*
G02X1091209Y166966I-1502J0D01*
G01X1091183Y166939D01*
X1091155Y166868D01*
Y166518D01*
X1091183Y166447D01*
X1091209Y166420D01*
G02Y164366I-1096J-1027D01*
G01X1091183Y164339D01*
X1091155Y164268D01*
Y163918D01*
X1091183Y163847D01*
X1091209Y163820D01*
G02X1091615Y162793I-1096J-1027D01*
G02X1088611I-1502J0D01*
G02X1089017Y163820I1502J0D01*
G01X1089043Y163847D01*
X1089071Y163918D01*
Y164268D01*
X1089043Y164339D01*
X1089017Y164366D01*
G02Y166420I1096J1027D01*
G01X1089043Y166447D01*
X1089071Y166518D01*
Y166868D01*
X1089043Y166939D01*
X1089017Y166966D01*
G02X1088611Y167993I1096J1027D01*
G02X1088981Y168980I1501J0D01*
G01Y168981D01*
X1088982D01*
G03X1089030Y169111I-152J130D01*
G01Y169375D01*
G03X1088982Y169505I-200J0D01*
G01X1088981Y169506D01*
G02X1088611Y170493I1131J987D01*
G37*
G36*
G01X1190973D02*
G02X1193977I1502J0D01*
G02X1193607Y169506I-1501J0D01*
G01Y169505D01*
X1193606D01*
G03X1193558Y169375I152J-130D01*
G01Y169111D01*
G03X1193606Y168981I200J0D01*
G01X1193607Y168980D01*
G02X1193977Y167993I-1131J-987D01*
G02X1193571Y166966I-1502J0D01*
G01X1193545Y166939D01*
X1193517Y166868D01*
Y166518D01*
X1193545Y166447D01*
X1193571Y166420D01*
G02Y164366I-1096J-1027D01*
G01X1193545Y164339D01*
X1193517Y164268D01*
Y163918D01*
X1193545Y163847D01*
X1193571Y163820D01*
G02X1193977Y162793I-1096J-1027D01*
G02X1190973I-1502J0D01*
G02X1191379Y163820I1502J0D01*
G01X1191405Y163847D01*
X1191433Y163918D01*
Y164268D01*
X1191405Y164339D01*
X1191379Y164366D01*
G02Y166420I1096J1027D01*
G01X1191405Y166447D01*
X1191433Y166518D01*
Y166868D01*
X1191405Y166939D01*
X1191379Y166966D01*
G02X1190973Y167993I1096J1027D01*
G02X1191343Y168980I1501J0D01*
G01Y168981D01*
X1191344D01*
G03X1191392Y169111I-152J130D01*
G01Y169375D01*
G03X1191344Y169505I-200J0D01*
G01X1191343Y169506D01*
G02X1190973Y170493I1131J987D01*
G37*
G36*
G01X1293335D02*
G02X1296339I1502J0D01*
G02X1295969Y169506I-1501J0D01*
G01Y169505D01*
X1295968D01*
G03X1295920Y169375I152J-130D01*
G01Y169111D01*
G03X1295968Y168981I200J0D01*
G01X1295969Y168980D01*
G02X1296339Y167993I-1131J-987D01*
G02X1295933Y166966I-1502J0D01*
G01X1295907Y166939D01*
X1295879Y166868D01*
Y166518D01*
X1295907Y166447D01*
X1295933Y166420D01*
G02Y164366I-1096J-1027D01*
G01X1295907Y164339D01*
X1295879Y164268D01*
Y163918D01*
X1295907Y163847D01*
X1295933Y163820D01*
G02X1296339Y162793I-1096J-1027D01*
G02X1293335I-1502J0D01*
G02X1293741Y163820I1502J0D01*
G01X1293767Y163847D01*
X1293795Y163918D01*
Y164268D01*
X1293767Y164339D01*
X1293741Y164366D01*
G02Y166420I1096J1027D01*
G01X1293767Y166447D01*
X1293795Y166518D01*
Y166868D01*
X1293767Y166939D01*
X1293741Y166966D01*
G02X1293335Y167993I1096J1027D01*
G02X1293705Y168980I1501J0D01*
G01Y168981D01*
X1293706D01*
G03X1293754Y169111I-152J130D01*
G01Y169375D01*
G03X1293706Y169505I-200J0D01*
G01X1293705Y169506D01*
G02X1293335Y170493I1131J987D01*
G37*
G36*
G01X1443336D02*
G02X1446340I1502J0D01*
G02X1445970Y169506I-1501J0D01*
G01Y169505D01*
X1445969D01*
G03X1445921Y169375I152J-130D01*
G01Y169111D01*
G03X1445969Y168981I200J0D01*
G01X1445970Y168980D01*
G02X1446340Y167993I-1131J-987D01*
G02X1445934Y166966I-1502J0D01*
G01X1445908Y166939D01*
X1445880Y166868D01*
Y166518D01*
X1445908Y166447D01*
X1445934Y166420D01*
G02Y164366I-1096J-1027D01*
G01X1445908Y164339D01*
X1445880Y164268D01*
Y163918D01*
X1445908Y163847D01*
X1445934Y163820D01*
G02X1446340Y162793I-1096J-1027D01*
G02X1443336I-1502J0D01*
G02X1443742Y163820I1502J0D01*
G01X1443768Y163847D01*
X1443796Y163918D01*
Y164268D01*
X1443768Y164339D01*
X1443742Y164366D01*
G02Y166420I1096J1027D01*
G01X1443768Y166447D01*
X1443796Y166518D01*
Y166868D01*
X1443768Y166939D01*
X1443742Y166966D01*
G02X1443336Y167993I1096J1027D01*
G02X1443706Y168980I1501J0D01*
G01Y168981D01*
X1443707D01*
G03X1443755Y169111I-152J130D01*
G01Y169375D01*
G03X1443707Y169505I-200J0D01*
G01X1443706Y169506D01*
G02X1443336Y170493I1131J987D01*
G37*
G36*
G01X1545698D02*
G02X1548702I1502J0D01*
G02X1548332Y169506I-1501J0D01*
G01Y169505D01*
X1548331D01*
G03X1548283Y169375I152J-130D01*
G01Y169111D01*
G03X1548331Y168981I200J0D01*
G01X1548332Y168980D01*
G02X1548702Y167993I-1131J-987D01*
G02X1548296Y166966I-1502J0D01*
G01X1548270Y166939D01*
X1548242Y166868D01*
Y166518D01*
X1548270Y166447D01*
X1548296Y166420D01*
G02Y164366I-1096J-1027D01*
G01X1548270Y164339D01*
X1548242Y164268D01*
Y163918D01*
X1548270Y163847D01*
X1548296Y163820D01*
G02X1548702Y162793I-1096J-1027D01*
G02X1545698I-1502J0D01*
G02X1546104Y163820I1502J0D01*
G01X1546130Y163847D01*
X1546158Y163918D01*
Y164268D01*
X1546130Y164339D01*
X1546104Y164366D01*
G02Y166420I1096J1027D01*
G01X1546130Y166447D01*
X1546158Y166518D01*
Y166868D01*
X1546130Y166939D01*
X1546104Y166966D01*
G02X1545698Y167993I1096J1027D01*
G02X1546068Y168980I1501J0D01*
G01Y168981D01*
X1546069D01*
G03X1546117Y169111I-152J130D01*
G01Y169375D01*
G03X1546069Y169505I-200J0D01*
G01X1546068Y169506D01*
G02X1545698Y170493I1131J987D01*
G37*
G36*
G01X1648060D02*
G02X1651064I1502J0D01*
G02X1650694Y169506I-1501J0D01*
G01Y169505D01*
X1650693D01*
G03X1650645Y169375I152J-130D01*
G01Y169111D01*
G03X1650693Y168981I200J0D01*
G01X1650694Y168980D01*
G02X1651064Y167993I-1131J-987D01*
G02X1650658Y166966I-1502J0D01*
G01X1650632Y166939D01*
X1650604Y166868D01*
Y166518D01*
X1650632Y166447D01*
X1650658Y166420D01*
G02Y164366I-1096J-1027D01*
G01X1650632Y164339D01*
X1650604Y164268D01*
Y163918D01*
X1650632Y163847D01*
X1650658Y163820D01*
G02X1651064Y162793I-1096J-1027D01*
G02X1648060I-1502J0D01*
G02X1648466Y163820I1502J0D01*
G01X1648492Y163847D01*
X1648520Y163918D01*
Y164268D01*
X1648492Y164339D01*
X1648466Y164366D01*
G02Y166420I1096J1027D01*
G01X1648492Y166447D01*
X1648520Y166518D01*
Y166868D01*
X1648492Y166939D01*
X1648466Y166966D01*
G02X1648060Y167993I1096J1027D01*
G02X1648430Y168980I1501J0D01*
G01Y168981D01*
X1648431D01*
G03X1648479Y169111I-152J130D01*
G01Y169375D01*
G03X1648431Y169505I-200J0D01*
G01X1648430Y169506D01*
G02X1648060Y170493I1131J987D01*
G37*
G36*
G01X1750422D02*
G02X1753426I1502J0D01*
G02X1753056Y169506I-1501J0D01*
G01Y169505D01*
X1753055D01*
G03X1753007Y169375I152J-130D01*
G01Y169111D01*
G03X1753055Y168981I200J0D01*
G01X1753056Y168980D01*
G02X1753426Y167993I-1131J-987D01*
G02X1753020Y166966I-1502J0D01*
G01X1752994Y166939D01*
X1752966Y166868D01*
Y166518D01*
X1752994Y166447D01*
X1753020Y166420D01*
G02Y164366I-1096J-1027D01*
G01X1752994Y164339D01*
X1752966Y164268D01*
Y163918D01*
X1752994Y163847D01*
X1753020Y163820D01*
G02X1753426Y162793I-1096J-1027D01*
G02X1750422I-1502J0D01*
G02X1750828Y163820I1502J0D01*
G01X1750854Y163847D01*
X1750882Y163918D01*
Y164268D01*
X1750854Y164339D01*
X1750828Y164366D01*
G02Y166420I1096J1027D01*
G01X1750854Y166447D01*
X1750882Y166518D01*
Y166868D01*
X1750854Y166939D01*
X1750828Y166966D01*
G02X1750422Y167993I1096J1027D01*
G02X1750792Y168980I1501J0D01*
G01Y168981D01*
X1750793D01*
G03X1750841Y169111I-152J130D01*
G01Y169375D01*
G03X1750793Y169505I-200J0D01*
G01X1750792Y169506D01*
G02X1750422Y170493I1131J987D01*
G37*
G36*
G01X98137Y186629D02*
G02X101141I1502J0D01*
G02X100138Y185212I-1502J0D01*
G01X100137D01*
G03X100015Y185090I67J-189D01*
G01X99912Y184796D01*
G03X99929Y184625I188J-68D01*
G01X99930Y184624D01*
G02X100155Y183834I-1277J-791D01*
G02X97151I-1502J0D01*
G02X98154Y185251I1502J0D01*
G01X98155D01*
G03X98277Y185373I-67J189D01*
G01X98380Y185667D01*
G03X98363Y185838I-188J68D01*
G01X98362Y185839D01*
G02X98137Y186629I1277J791D01*
G37*
G36*
G01X200499D02*
G02X203503I1502J0D01*
G02X202500Y185212I-1502J0D01*
G01X202499D01*
G03X202377Y185090I67J-189D01*
G01X202274Y184796D01*
G03X202291Y184625I188J-68D01*
G01X202292Y184624D01*
G02X202517Y183834I-1277J-791D01*
G02X199513I-1502J0D01*
G02X200516Y185251I1502J0D01*
G01X200517D01*
G03X200639Y185373I-67J189D01*
G01X200742Y185667D01*
G03X200725Y185838I-188J68D01*
G01X200724Y185839D01*
G02X200499Y186629I1277J791D01*
G37*
G36*
G01X302861D02*
G02X305865I1502J0D01*
G02X304862Y185212I-1502J0D01*
G01X304861D01*
G03X304739Y185090I67J-189D01*
G01X304636Y184796D01*
G03X304653Y184625I188J-68D01*
G01X304654Y184624D01*
G02X304879Y183834I-1277J-791D01*
G02X301875I-1502J0D01*
G02X302878Y185251I1502J0D01*
G01X302879D01*
G03X303001Y185373I-67J189D01*
G01X303104Y185667D01*
G03X303087Y185838I-188J68D01*
G01X303086Y185839D01*
G02X302861Y186629I1277J791D01*
G37*
G36*
G01X405223D02*
G02X408227I1502J0D01*
G02X407224Y185212I-1502J0D01*
G01X407223D01*
G03X407101Y185090I67J-189D01*
G01X406998Y184796D01*
G03X407015Y184625I188J-68D01*
G01X407016Y184624D01*
G02X407241Y183834I-1277J-791D01*
G02X404237I-1502J0D01*
G02X405240Y185251I1502J0D01*
G01X405241D01*
G03X405363Y185373I-67J189D01*
G01X405466Y185667D01*
G03X405449Y185838I-188J68D01*
G01X405448Y185839D01*
G02X405223Y186629I1277J791D01*
G37*
G36*
G01X555224D02*
G02X558228I1502J0D01*
G02X557225Y185212I-1502J0D01*
G01X557224D01*
G03X557102Y185090I67J-189D01*
G01X556999Y184796D01*
G03X557016Y184625I188J-68D01*
G01X557017Y184624D01*
G02X557242Y183834I-1277J-791D01*
G02X554238I-1502J0D01*
G02X555241Y185251I1502J0D01*
G01X555242D01*
G03X555364Y185373I-67J189D01*
G01X555467Y185667D01*
G03X555450Y185838I-188J68D01*
G01X555449Y185839D01*
G02X555224Y186629I1277J791D01*
G37*
G36*
G01X657586D02*
G02X660590I1502J0D01*
G02X659587Y185212I-1502J0D01*
G01X659586D01*
G03X659464Y185090I67J-189D01*
G01X659361Y184796D01*
G03X659378Y184625I188J-68D01*
G01X659379Y184624D01*
G02X659604Y183834I-1277J-791D01*
G02X656600I-1502J0D01*
G02X657603Y185251I1502J0D01*
G01X657604D01*
G03X657726Y185373I-67J189D01*
G01X657829Y185667D01*
G03X657812Y185838I-188J68D01*
G01X657811Y185839D01*
G02X657586Y186629I1277J791D01*
G37*
G36*
G01X759948D02*
G02X762952I1502J0D01*
G02X761949Y185212I-1502J0D01*
G01X761948D01*
G03X761826Y185090I67J-189D01*
G01X761723Y184796D01*
G03X761740Y184625I188J-68D01*
G01X761741Y184624D01*
G02X761966Y183834I-1277J-791D01*
G02X758962I-1502J0D01*
G02X759965Y185251I1502J0D01*
G01X759966D01*
G03X760088Y185373I-67J189D01*
G01X760191Y185667D01*
G03X760174Y185838I-188J68D01*
G01X760173Y185839D01*
G02X759948Y186629I1277J791D01*
G37*
G36*
G01X862310D02*
G02X865314I1502J0D01*
G02X864311Y185212I-1502J0D01*
G01X864310D01*
G03X864188Y185090I67J-189D01*
G01X864085Y184796D01*
G03X864102Y184625I188J-68D01*
G01X864103Y184624D01*
G02X864328Y183834I-1277J-791D01*
G02X861324I-1502J0D01*
G02X862327Y185251I1502J0D01*
G01X862328D01*
G03X862450Y185373I-67J189D01*
G01X862553Y185667D01*
G03X862536Y185838I-188J68D01*
G01X862535Y185839D01*
G02X862310Y186629I1277J791D01*
G37*
G36*
G01X1012310D02*
G02X1015314I1502J0D01*
G02X1014311Y185212I-1502J0D01*
G01X1014310D01*
G03X1014188Y185090I67J-189D01*
G01X1014085Y184796D01*
G03X1014102Y184625I188J-68D01*
G01X1014103Y184624D01*
G02X1014328Y183834I-1277J-791D01*
G02X1011324I-1502J0D01*
G02X1012327Y185251I1502J0D01*
G01X1012328D01*
G03X1012450Y185373I-67J189D01*
G01X1012553Y185667D01*
G03X1012536Y185838I-188J68D01*
G01X1012535Y185839D01*
G02X1012310Y186629I1277J791D01*
G37*
G36*
G01X1114672D02*
G02X1117676I1502J0D01*
G02X1116673Y185212I-1502J0D01*
G01X1116672D01*
G03X1116550Y185090I67J-189D01*
G01X1116447Y184796D01*
G03X1116464Y184625I188J-68D01*
G01X1116465Y184624D01*
G02X1116690Y183834I-1277J-791D01*
G02X1113686I-1502J0D01*
G02X1114689Y185251I1502J0D01*
G01X1114690D01*
G03X1114812Y185373I-67J189D01*
G01X1114915Y185667D01*
G03X1114898Y185838I-188J68D01*
G01X1114897Y185839D01*
G02X1114672Y186629I1277J791D01*
G37*
G36*
G01X1217034D02*
G02X1220038I1502J0D01*
G02X1219035Y185212I-1502J0D01*
G01X1219034D01*
G03X1218912Y185090I67J-189D01*
G01X1218809Y184796D01*
G03X1218826Y184625I188J-68D01*
G01X1218827Y184624D01*
G02X1219052Y183834I-1277J-791D01*
G02X1216048I-1502J0D01*
G02X1217051Y185251I1502J0D01*
G01X1217052D01*
G03X1217174Y185373I-67J189D01*
G01X1217277Y185667D01*
G03X1217260Y185838I-188J68D01*
G01X1217259Y185839D01*
G02X1217034Y186629I1277J791D01*
G37*
G36*
G01X1319396D02*
G02X1322400I1502J0D01*
G02X1321397Y185212I-1502J0D01*
G01X1321396D01*
G03X1321274Y185090I67J-189D01*
G01X1321171Y184796D01*
G03X1321188Y184625I188J-68D01*
G01X1321189Y184624D01*
G02X1321414Y183834I-1277J-791D01*
G02X1318410I-1502J0D01*
G02X1319413Y185251I1502J0D01*
G01X1319414D01*
G03X1319536Y185373I-67J189D01*
G01X1319639Y185667D01*
G03X1319622Y185838I-188J68D01*
G01X1319621Y185839D01*
G02X1319396Y186629I1277J791D01*
G37*
G36*
G01X1469397D02*
G02X1472401I1502J0D01*
G02X1471398Y185212I-1502J0D01*
G01X1471397D01*
G03X1471275Y185090I67J-189D01*
G01X1471172Y184796D01*
G03X1471189Y184625I188J-68D01*
G01X1471190Y184624D01*
G02X1471415Y183834I-1277J-791D01*
G02X1468411I-1502J0D01*
G02X1469414Y185251I1502J0D01*
G01X1469415D01*
G03X1469537Y185373I-67J189D01*
G01X1469640Y185667D01*
G03X1469623Y185838I-188J68D01*
G01X1469622Y185839D01*
G02X1469397Y186629I1277J791D01*
G37*
G36*
G01X1571759D02*
G02X1574763I1502J0D01*
G02X1573760Y185212I-1502J0D01*
G01X1573759D01*
G03X1573637Y185090I67J-189D01*
G01X1573534Y184796D01*
G03X1573551Y184625I188J-68D01*
G01X1573552Y184624D01*
G02X1573777Y183834I-1277J-791D01*
G02X1570773I-1502J0D01*
G02X1571776Y185251I1502J0D01*
G01X1571777D01*
G03X1571899Y185373I-67J189D01*
G01X1572002Y185667D01*
G03X1571985Y185838I-188J68D01*
G01X1571984Y185839D01*
G02X1571759Y186629I1277J791D01*
G37*
G36*
G01X1674121D02*
G02X1677125I1502J0D01*
G02X1676122Y185212I-1502J0D01*
G01X1676121D01*
G03X1675999Y185090I67J-189D01*
G01X1675896Y184796D01*
G03X1675913Y184625I188J-68D01*
G01X1675914Y184624D01*
G02X1676139Y183834I-1277J-791D01*
G02X1673135I-1502J0D01*
G02X1674138Y185251I1502J0D01*
G01X1674139D01*
G03X1674261Y185373I-67J189D01*
G01X1674364Y185667D01*
G03X1674347Y185838I-188J68D01*
G01X1674346Y185839D01*
G02X1674121Y186629I1277J791D01*
G37*
G36*
G01X1776483D02*
G02X1779487I1502J0D01*
G02X1778484Y185212I-1502J0D01*
G01X1778483D01*
G03X1778361Y185090I67J-189D01*
G01X1778258Y184796D01*
G03X1778275Y184625I188J-68D01*
G01X1778276Y184624D01*
G02X1778501Y183834I-1277J-791D01*
G02X1775497I-1502J0D01*
G02X1776500Y185251I1502J0D01*
G01X1776501D01*
G03X1776623Y185373I-67J189D01*
G01X1776726Y185667D01*
G03X1776709Y185838I-188J68D01*
G01X1776708Y185839D01*
G02X1776483Y186629I1277J791D01*
G37*
G36*
G01X942260Y190475D02*
G02Y193479I0J1502D01*
G02X943247Y193109I0J-1501D01*
G01X943248D01*
Y193108D01*
G03X943378Y193060I130J152D01*
G01X943642D01*
G03X943772Y193108I0J200D01*
G01X943773Y193109D01*
G02X944760Y193479I987J-1131D01*
G02Y190475I0J-1502D01*
G02X943773Y190845I0J1501D01*
G01X943772D01*
Y190846D01*
G03X943642Y190894I-130J-152D01*
G01X943378D01*
G03X943248Y190846I0J-200D01*
G01X943247Y190845D01*
G02X942260Y190475I-987J1131D01*
G37*
G36*
G01X338640Y196308D02*
X338641Y196307D01*
G03X338771Y196259I130J152D01*
G01X339035D01*
G03X339165Y196307I0J200D01*
G01X339166Y196308D01*
G02X340153Y196678I987J-1131D01*
G02Y193674I0J-1502D01*
G02X339166Y194044I0J1501D01*
G01X339165D01*
Y194045D01*
G03X339035Y194093I-130J-152D01*
G01X338771D01*
G03X338641Y194045I0J-200D01*
G01X338640Y194044D01*
G02X336666I-987J1131D01*
G01X336665D01*
Y194045D01*
G03X336535Y194093I-130J-152D01*
G01X336271D01*
G03X336141Y194045I0J-200D01*
G01X336140Y194044D01*
G02X334166I-987J1131D01*
G01X334165D01*
Y194045D01*
G03X334035Y194093I-130J-152D01*
G01X333771D01*
G03X333641Y194045I0J-200D01*
G01X333640Y194044D01*
G02X332653Y193674I-987J1131D01*
G02Y196678I0J1502D01*
G02X333640Y196308I0J-1501D01*
G01X333641D01*
Y196307D01*
G03X333771Y196259I130J152D01*
G01X334035D01*
G03X334165Y196307I0J200D01*
G01X334166Y196308D01*
G02X336140I987J-1131D01*
G01X336141D01*
Y196307D01*
G03X336271Y196259I130J152D01*
G01X336535D01*
G03X336665Y196307I0J200D01*
G01X336666Y196308D01*
G02X338640I987J-1131D01*
G37*
G36*
G01X795727D02*
X795728Y196307D01*
G03X795858Y196259I130J152D01*
G01X796122D01*
G03X796252Y196307I0J200D01*
G01X796253Y196308D01*
G02X797240Y196678I987J-1131D01*
G02Y193674I0J-1502D01*
G02X796253Y194044I0J1501D01*
G01X796252D01*
Y194045D01*
G03X796122Y194093I-130J-152D01*
G01X795858D01*
G03X795728Y194045I0J-200D01*
G01X795727Y194044D01*
G02X793753I-987J1131D01*
G01X793752D01*
Y194045D01*
G03X793622Y194093I-130J-152D01*
G01X793358D01*
G03X793228Y194045I0J-200D01*
G01X793227Y194044D01*
G02X791253I-987J1131D01*
G01X791252D01*
Y194045D01*
G03X791122Y194093I-130J-152D01*
G01X790858D01*
G03X790728Y194045I0J-200D01*
G01X790727Y194044D01*
G02X789740Y193674I-987J1131D01*
G02Y196678I0J1502D01*
G02X790727Y196308I0J-1501D01*
G01X790728D01*
Y196307D01*
G03X790858Y196259I130J152D01*
G01X791122D01*
G03X791252Y196307I0J200D01*
G01X791253Y196308D01*
G02X793227I987J-1131D01*
G01X793228D01*
Y196307D01*
G03X793358Y196259I130J152D01*
G01X793622D01*
G03X793752Y196307I0J200D01*
G01X793753Y196308D01*
G02X795727I987J-1131D01*
G37*
G36*
G01X1252813D02*
X1252814Y196307D01*
G03X1252944Y196259I130J152D01*
G01X1253208D01*
G03X1253338Y196307I0J200D01*
G01X1253339Y196308D01*
G02X1254326Y196678I987J-1131D01*
G02Y193674I0J-1502D01*
G02X1253339Y194044I0J1501D01*
G01X1253338D01*
Y194045D01*
G03X1253208Y194093I-130J-152D01*
G01X1252944D01*
G03X1252814Y194045I0J-200D01*
G01X1252813Y194044D01*
G02X1250839I-987J1131D01*
G01X1250838D01*
Y194045D01*
G03X1250708Y194093I-130J-152D01*
G01X1250444D01*
G03X1250314Y194045I0J-200D01*
G01X1250313Y194044D01*
G02X1248339I-987J1131D01*
G01X1248338D01*
Y194045D01*
G03X1248208Y194093I-130J-152D01*
G01X1247944D01*
G03X1247814Y194045I0J-200D01*
G01X1247813Y194044D01*
G02X1246826Y193674I-987J1131D01*
G02Y196678I0J1502D01*
G02X1247813Y196308I0J-1501D01*
G01X1247814D01*
Y196307D01*
G03X1247944Y196259I130J152D01*
G01X1248208D01*
G03X1248338Y196307I0J200D01*
G01X1248339Y196308D01*
G02X1250313I987J-1131D01*
G01X1250314D01*
Y196307D01*
G03X1250444Y196259I130J152D01*
G01X1250708D01*
G03X1250838Y196307I0J200D01*
G01X1250839Y196308D01*
G02X1252813I987J-1131D01*
G37*
G36*
G01X1709900D02*
X1709901Y196307D01*
G03X1710031Y196259I130J152D01*
G01X1710295D01*
G03X1710425Y196307I0J200D01*
G01X1710426Y196308D01*
G02X1711413Y196678I987J-1131D01*
G02Y193674I0J-1502D01*
G02X1710426Y194044I0J1501D01*
G01X1710425D01*
Y194045D01*
G03X1710295Y194093I-130J-152D01*
G01X1710031D01*
G03X1709901Y194045I0J-200D01*
G01X1709900Y194044D01*
G02X1707926I-987J1131D01*
G01X1707925D01*
Y194045D01*
G03X1707795Y194093I-130J-152D01*
G01X1707531D01*
G03X1707401Y194045I0J-200D01*
G01X1707400Y194044D01*
G02X1705426I-987J1131D01*
G01X1705425D01*
Y194045D01*
G03X1705295Y194093I-130J-152D01*
G01X1705031D01*
G03X1704901Y194045I0J-200D01*
G01X1704900Y194044D01*
G02X1703913Y193674I-987J1131D01*
G02Y196678I0J1502D01*
G02X1704900Y196308I0J-1501D01*
G01X1704901D01*
Y196307D01*
G03X1705031Y196259I130J152D01*
G01X1705295D01*
G03X1705425Y196307I0J200D01*
G01X1705426Y196308D01*
G02X1707400I987J-1131D01*
G01X1707401D01*
Y196307D01*
G03X1707531Y196259I130J152D01*
G01X1707795D01*
G03X1707925Y196307I0J200D01*
G01X1707926Y196308D01*
G02X1709900I987J-1131D01*
G37*
G36*
G01X940487Y194178D02*
G02Y197182I0J1502D01*
G02X941474Y196812I0J-1501D01*
G01X941475D01*
Y196811D01*
G03X941605Y196763I130J152D01*
G01X941869D01*
G03X941999Y196811I0J200D01*
G01X942000Y196812D01*
G02X942987Y197182I987J-1131D01*
G02Y194178I0J-1502D01*
G02X942000Y194548I0J1501D01*
G01X941999D01*
Y194549D01*
G03X941869Y194597I-130J-152D01*
G01X941605D01*
G03X941475Y194549I0J-200D01*
G01X941474Y194548D01*
G02X940487Y194178I-987J1131D01*
G37*
G36*
G01X926645Y202304D02*
X926351D01*
G03X926204Y202239I1J-200D01*
G02X925098Y201754I-1106J1019D01*
G02Y204758I0J1502D01*
G02X926204Y204273I0J-1504D01*
G03X926351Y204208I148J135D01*
G01X926645D01*
G03X926792Y204273I-1J200D01*
G02X927898Y204758I1106J-1019D01*
G02Y201754I0J-1502D01*
G02X926792Y202239I0J1504D01*
G03X926645Y202304I-148J-135D01*
G37*
G36*
G01X90340Y207899D02*
X90341Y207898D01*
G03X90471Y207850I130J152D01*
G01X90735D01*
G03X90865Y207898I0J200D01*
G01X90866Y207899D01*
G02X91853Y208269I987J-1131D01*
G02Y205265I0J-1502D01*
G02X90866Y205635I0J1501D01*
G01X90865D01*
Y205636D01*
G03X90735Y205684I-130J-152D01*
G01X90471D01*
G03X90341Y205636I0J-200D01*
G01X90340Y205635D01*
G02X88366I-987J1131D01*
G01X88365D01*
Y205636D01*
G03X88235Y205684I-130J-152D01*
G01X87971D01*
G03X87841Y205636I0J-200D01*
G01X87840Y205635D01*
G02X86853Y205265I-987J1131D01*
G02Y208269I0J1502D01*
G02X87840Y207899I0J-1501D01*
G01X87841D01*
Y207898D01*
G03X87971Y207850I130J152D01*
G01X88235D01*
G03X88365Y207898I0J200D01*
G01X88366Y207899D01*
G02X90340I987J-1131D01*
G37*
G36*
G01X192702D02*
X192703Y207898D01*
G03X192833Y207850I130J152D01*
G01X193097D01*
G03X193227Y207898I0J200D01*
G01X193228Y207899D01*
G02X194215Y208269I987J-1131D01*
G02Y205265I0J-1502D01*
G02X193228Y205635I0J1501D01*
G01X193227D01*
Y205636D01*
G03X193097Y205684I-130J-152D01*
G01X192833D01*
G03X192703Y205636I0J-200D01*
G01X192702Y205635D01*
G02X190728I-987J1131D01*
G01X190727D01*
Y205636D01*
G03X190597Y205684I-130J-152D01*
G01X190333D01*
G03X190203Y205636I0J-200D01*
G01X190202Y205635D01*
G02X189215Y205265I-987J1131D01*
G02Y208269I0J1502D01*
G02X190202Y207899I0J-1501D01*
G01X190203D01*
Y207898D01*
G03X190333Y207850I130J152D01*
G01X190597D01*
G03X190727Y207898I0J200D01*
G01X190728Y207899D01*
G02X192702I987J-1131D01*
G37*
G36*
G01X295064D02*
X295065Y207898D01*
G03X295195Y207850I130J152D01*
G01X295459D01*
G03X295589Y207898I0J200D01*
G01X295590Y207899D01*
G02X296577Y208269I987J-1131D01*
G02Y205265I0J-1502D01*
G02X295590Y205635I0J1501D01*
G01X295589D01*
Y205636D01*
G03X295459Y205684I-130J-152D01*
G01X295195D01*
G03X295065Y205636I0J-200D01*
G01X295064Y205635D01*
G02X293090I-987J1131D01*
G01X293089D01*
Y205636D01*
G03X292959Y205684I-130J-152D01*
G01X292695D01*
G03X292565Y205636I0J-200D01*
G01X292564Y205635D01*
G02X291577Y205265I-987J1131D01*
G02Y208269I0J1502D01*
G02X292564Y207899I0J-1501D01*
G01X292565D01*
Y207898D01*
G03X292695Y207850I130J152D01*
G01X292959D01*
G03X293089Y207898I0J200D01*
G01X293090Y207899D01*
G02X295064I987J-1131D01*
G37*
G36*
G01X397426D02*
X397427Y207898D01*
G03X397557Y207850I130J152D01*
G01X397821D01*
G03X397951Y207898I0J200D01*
G01X397952Y207899D01*
G02X398939Y208269I987J-1131D01*
G02Y205265I0J-1502D01*
G02X397952Y205635I0J1501D01*
G01X397951D01*
Y205636D01*
G03X397821Y205684I-130J-152D01*
G01X397557D01*
G03X397427Y205636I0J-200D01*
G01X397426Y205635D01*
G02X395452I-987J1131D01*
G01X395451D01*
Y205636D01*
G03X395321Y205684I-130J-152D01*
G01X395057D01*
G03X394927Y205636I0J-200D01*
G01X394926Y205635D01*
G02X393939Y205265I-987J1131D01*
G02Y208269I0J1502D01*
G02X394926Y207899I0J-1501D01*
G01X394927D01*
Y207898D01*
G03X395057Y207850I130J152D01*
G01X395321D01*
G03X395451Y207898I0J200D01*
G01X395452Y207899D01*
G02X397426I987J-1131D01*
G37*
G36*
G01X547427D02*
X547428Y207898D01*
G03X547558Y207850I130J152D01*
G01X547822D01*
G03X547952Y207898I0J200D01*
G01X547953Y207899D01*
G02X548940Y208269I987J-1131D01*
G02Y205265I0J-1502D01*
G02X547953Y205635I0J1501D01*
G01X547952D01*
Y205636D01*
G03X547822Y205684I-130J-152D01*
G01X547558D01*
G03X547428Y205636I0J-200D01*
G01X547427Y205635D01*
G02X545453I-987J1131D01*
G01X545452D01*
Y205636D01*
G03X545322Y205684I-130J-152D01*
G01X545058D01*
G03X544928Y205636I0J-200D01*
G01X544927Y205635D01*
G02X543940Y205265I-987J1131D01*
G02Y208269I0J1502D01*
G02X544927Y207899I0J-1501D01*
G01X544928D01*
Y207898D01*
G03X545058Y207850I130J152D01*
G01X545322D01*
G03X545452Y207898I0J200D01*
G01X545453Y207899D01*
G02X547427I987J-1131D01*
G37*
G36*
G01X649789D02*
X649790Y207898D01*
G03X649920Y207850I130J152D01*
G01X650184D01*
G03X650314Y207898I0J200D01*
G01X650315Y207899D01*
G02X651302Y208269I987J-1131D01*
G02Y205265I0J-1502D01*
G02X650315Y205635I0J1501D01*
G01X650314D01*
Y205636D01*
G03X650184Y205684I-130J-152D01*
G01X649920D01*
G03X649790Y205636I0J-200D01*
G01X649789Y205635D01*
G02X647815I-987J1131D01*
G01X647814D01*
Y205636D01*
G03X647684Y205684I-130J-152D01*
G01X647420D01*
G03X647290Y205636I0J-200D01*
G01X647289Y205635D01*
G02X646302Y205265I-987J1131D01*
G02Y208269I0J1502D01*
G02X647289Y207899I0J-1501D01*
G01X647290D01*
Y207898D01*
G03X647420Y207850I130J152D01*
G01X647684D01*
G03X647814Y207898I0J200D01*
G01X647815Y207899D01*
G02X649789I987J-1131D01*
G37*
G36*
G01X752151D02*
X752152Y207898D01*
G03X752282Y207850I130J152D01*
G01X752546D01*
G03X752676Y207898I0J200D01*
G01X752677Y207899D01*
G02X753664Y208269I987J-1131D01*
G02Y205265I0J-1502D01*
G02X752677Y205635I0J1501D01*
G01X752676D01*
Y205636D01*
G03X752546Y205684I-130J-152D01*
G01X752282D01*
G03X752152Y205636I0J-200D01*
G01X752151Y205635D01*
G02X750177I-987J1131D01*
G01X750176D01*
Y205636D01*
G03X750046Y205684I-130J-152D01*
G01X749782D01*
G03X749652Y205636I0J-200D01*
G01X749651Y205635D01*
G02X748664Y205265I-987J1131D01*
G02Y208269I0J1502D01*
G02X749651Y207899I0J-1501D01*
G01X749652D01*
Y207898D01*
G03X749782Y207850I130J152D01*
G01X750046D01*
G03X750176Y207898I0J200D01*
G01X750177Y207899D01*
G02X752151I987J-1131D01*
G37*
G36*
G01X854513D02*
X854514Y207898D01*
G03X854644Y207850I130J152D01*
G01X854908D01*
G03X855038Y207898I0J200D01*
G01X855039Y207899D01*
G02X856026Y208269I987J-1131D01*
G02Y205265I0J-1502D01*
G02X855039Y205635I0J1501D01*
G01X855038D01*
Y205636D01*
G03X854908Y205684I-130J-152D01*
G01X854644D01*
G03X854514Y205636I0J-200D01*
G01X854513Y205635D01*
G02X852539I-987J1131D01*
G01X852538D01*
Y205636D01*
G03X852408Y205684I-130J-152D01*
G01X852144D01*
G03X852014Y205636I0J-200D01*
G01X852013Y205635D01*
G02X851026Y205265I-987J1131D01*
G02Y208269I0J1502D01*
G02X852013Y207899I0J-1501D01*
G01X852014D01*
Y207898D01*
G03X852144Y207850I130J152D01*
G01X852408D01*
G03X852538Y207898I0J200D01*
G01X852539Y207899D01*
G02X854513I987J-1131D01*
G37*
G36*
G01X1004513D02*
X1004514Y207898D01*
G03X1004644Y207850I130J152D01*
G01X1004908D01*
G03X1005038Y207898I0J200D01*
G01X1005039Y207899D01*
G02X1006026Y208269I987J-1131D01*
G02Y205265I0J-1502D01*
G02X1005039Y205635I0J1501D01*
G01X1005038D01*
Y205636D01*
G03X1004908Y205684I-130J-152D01*
G01X1004644D01*
G03X1004514Y205636I0J-200D01*
G01X1004513Y205635D01*
G02X1002539I-987J1131D01*
G01X1002538D01*
Y205636D01*
G03X1002408Y205684I-130J-152D01*
G01X1002144D01*
G03X1002014Y205636I0J-200D01*
G01X1002013Y205635D01*
G02X1001026Y205265I-987J1131D01*
G02Y208269I0J1502D01*
G02X1002013Y207899I0J-1501D01*
G01X1002014D01*
Y207898D01*
G03X1002144Y207850I130J152D01*
G01X1002408D01*
G03X1002538Y207898I0J200D01*
G01X1002539Y207899D01*
G02X1004513I987J-1131D01*
G37*
G36*
G01X1106875D02*
X1106876Y207898D01*
G03X1107006Y207850I130J152D01*
G01X1107270D01*
G03X1107400Y207898I0J200D01*
G01X1107401Y207899D01*
G02X1108388Y208269I987J-1131D01*
G02Y205265I0J-1502D01*
G02X1107401Y205635I0J1501D01*
G01X1107400D01*
Y205636D01*
G03X1107270Y205684I-130J-152D01*
G01X1107006D01*
G03X1106876Y205636I0J-200D01*
G01X1106875Y205635D01*
G02X1104901I-987J1131D01*
G01X1104900D01*
Y205636D01*
G03X1104770Y205684I-130J-152D01*
G01X1104506D01*
G03X1104376Y205636I0J-200D01*
G01X1104375Y205635D01*
G02X1103388Y205265I-987J1131D01*
G02Y208269I0J1502D01*
G02X1104375Y207899I0J-1501D01*
G01X1104376D01*
Y207898D01*
G03X1104506Y207850I130J152D01*
G01X1104770D01*
G03X1104900Y207898I0J200D01*
G01X1104901Y207899D01*
G02X1106875I987J-1131D01*
G37*
G36*
G01X1209237D02*
X1209238Y207898D01*
G03X1209368Y207850I130J152D01*
G01X1209632D01*
G03X1209762Y207898I0J200D01*
G01X1209763Y207899D01*
G02X1210750Y208269I987J-1131D01*
G02Y205265I0J-1502D01*
G02X1209763Y205635I0J1501D01*
G01X1209762D01*
Y205636D01*
G03X1209632Y205684I-130J-152D01*
G01X1209368D01*
G03X1209238Y205636I0J-200D01*
G01X1209237Y205635D01*
G02X1207263I-987J1131D01*
G01X1207262D01*
Y205636D01*
G03X1207132Y205684I-130J-152D01*
G01X1206868D01*
G03X1206738Y205636I0J-200D01*
G01X1206737Y205635D01*
G02X1205750Y205265I-987J1131D01*
G02Y208269I0J1502D01*
G02X1206737Y207899I0J-1501D01*
G01X1206738D01*
Y207898D01*
G03X1206868Y207850I130J152D01*
G01X1207132D01*
G03X1207262Y207898I0J200D01*
G01X1207263Y207899D01*
G02X1209237I987J-1131D01*
G37*
G36*
G01X1311599D02*
X1311600Y207898D01*
G03X1311730Y207850I130J152D01*
G01X1311994D01*
G03X1312124Y207898I0J200D01*
G01X1312125Y207899D01*
G02X1313112Y208269I987J-1131D01*
G02Y205265I0J-1502D01*
G02X1312125Y205635I0J1501D01*
G01X1312124D01*
Y205636D01*
G03X1311994Y205684I-130J-152D01*
G01X1311730D01*
G03X1311600Y205636I0J-200D01*
G01X1311599Y205635D01*
G02X1309625I-987J1131D01*
G01X1309624D01*
Y205636D01*
G03X1309494Y205684I-130J-152D01*
G01X1309230D01*
G03X1309100Y205636I0J-200D01*
G01X1309099Y205635D01*
G02X1308112Y205265I-987J1131D01*
G02Y208269I0J1502D01*
G02X1309099Y207899I0J-1501D01*
G01X1309100D01*
Y207898D01*
G03X1309230Y207850I130J152D01*
G01X1309494D01*
G03X1309624Y207898I0J200D01*
G01X1309625Y207899D01*
G02X1311599I987J-1131D01*
G37*
G36*
G01X1461600D02*
X1461601Y207898D01*
G03X1461731Y207850I130J152D01*
G01X1461995D01*
G03X1462125Y207898I0J200D01*
G01X1462126Y207899D01*
G02X1463113Y208269I987J-1131D01*
G02Y205265I0J-1502D01*
G02X1462126Y205635I0J1501D01*
G01X1462125D01*
Y205636D01*
G03X1461995Y205684I-130J-152D01*
G01X1461731D01*
G03X1461601Y205636I0J-200D01*
G01X1461600Y205635D01*
G02X1459626I-987J1131D01*
G01X1459625D01*
Y205636D01*
G03X1459495Y205684I-130J-152D01*
G01X1459231D01*
G03X1459101Y205636I0J-200D01*
G01X1459100Y205635D01*
G02X1458113Y205265I-987J1131D01*
G02Y208269I0J1502D01*
G02X1459100Y207899I0J-1501D01*
G01X1459101D01*
Y207898D01*
G03X1459231Y207850I130J152D01*
G01X1459495D01*
G03X1459625Y207898I0J200D01*
G01X1459626Y207899D01*
G02X1461600I987J-1131D01*
G37*
G36*
G01X1563962D02*
X1563963Y207898D01*
G03X1564093Y207850I130J152D01*
G01X1564357D01*
G03X1564487Y207898I0J200D01*
G01X1564488Y207899D01*
G02X1565475Y208269I987J-1131D01*
G02Y205265I0J-1502D01*
G02X1564488Y205635I0J1501D01*
G01X1564487D01*
Y205636D01*
G03X1564357Y205684I-130J-152D01*
G01X1564093D01*
G03X1563963Y205636I0J-200D01*
G01X1563962Y205635D01*
G02X1561988I-987J1131D01*
G01X1561987D01*
Y205636D01*
G03X1561857Y205684I-130J-152D01*
G01X1561593D01*
G03X1561463Y205636I0J-200D01*
G01X1561462Y205635D01*
G02X1560475Y205265I-987J1131D01*
G02Y208269I0J1502D01*
G02X1561462Y207899I0J-1501D01*
G01X1561463D01*
Y207898D01*
G03X1561593Y207850I130J152D01*
G01X1561857D01*
G03X1561987Y207898I0J200D01*
G01X1561988Y207899D01*
G02X1563962I987J-1131D01*
G37*
G36*
G01X1666324D02*
X1666325Y207898D01*
G03X1666455Y207850I130J152D01*
G01X1666719D01*
G03X1666849Y207898I0J200D01*
G01X1666850Y207899D01*
G02X1667837Y208269I987J-1131D01*
G02Y205265I0J-1502D01*
G02X1666850Y205635I0J1501D01*
G01X1666849D01*
Y205636D01*
G03X1666719Y205684I-130J-152D01*
G01X1666455D01*
G03X1666325Y205636I0J-200D01*
G01X1666324Y205635D01*
G02X1664350I-987J1131D01*
G01X1664349D01*
Y205636D01*
G03X1664219Y205684I-130J-152D01*
G01X1663955D01*
G03X1663825Y205636I0J-200D01*
G01X1663824Y205635D01*
G02X1662837Y205265I-987J1131D01*
G02Y208269I0J1502D01*
G02X1663824Y207899I0J-1501D01*
G01X1663825D01*
Y207898D01*
G03X1663955Y207850I130J152D01*
G01X1664219D01*
G03X1664349Y207898I0J200D01*
G01X1664350Y207899D01*
G02X1666324I987J-1131D01*
G37*
G36*
G01X1768686D02*
X1768687Y207898D01*
G03X1768817Y207850I130J152D01*
G01X1769081D01*
G03X1769211Y207898I0J200D01*
G01X1769212Y207899D01*
G02X1770199Y208269I987J-1131D01*
G02Y205265I0J-1502D01*
G02X1769212Y205635I0J1501D01*
G01X1769211D01*
Y205636D01*
G03X1769081Y205684I-130J-152D01*
G01X1768817D01*
G03X1768687Y205636I0J-200D01*
G01X1768686Y205635D01*
G02X1766712I-987J1131D01*
G01X1766711D01*
Y205636D01*
G03X1766581Y205684I-130J-152D01*
G01X1766317D01*
G03X1766187Y205636I0J-200D01*
G01X1766186Y205635D01*
G02X1765199Y205265I-987J1131D01*
G02Y208269I0J1502D01*
G02X1766186Y207899I0J-1501D01*
G01X1766187D01*
Y207898D01*
G03X1766317Y207850I130J152D01*
G01X1766581D01*
G03X1766711Y207898I0J200D01*
G01X1766712Y207899D01*
G02X1768686I987J-1131D01*
G37*
G36*
G01X27421Y205304D02*
G02Y208308I0J1502D01*
G02X28408Y207938I0J-1501D01*
G01X28409D01*
Y207937D01*
G03X28539Y207889I130J152D01*
G01X28803D01*
G03X28933Y207937I0J200D01*
G01X28934Y207938D01*
G02X29921Y208308I987J-1131D01*
G02Y205304I0J-1502D01*
G02X28934Y205674I0J1501D01*
G01X28933D01*
Y205675D01*
G03X28803Y205723I-130J-152D01*
G01X28539D01*
G03X28409Y205675I0J-200D01*
G01X28408Y205674D01*
G02X27421Y205304I-987J1131D01*
G37*
G36*
G01X129783D02*
G02Y208308I0J1502D01*
G02X130770Y207938I0J-1501D01*
G01X130771D01*
Y207937D01*
G03X130901Y207889I130J152D01*
G01X131165D01*
G03X131295Y207937I0J200D01*
G01X131296Y207938D01*
G02X132283Y208308I987J-1131D01*
G02Y205304I0J-1502D01*
G02X131296Y205674I0J1501D01*
G01X131295D01*
Y205675D01*
G03X131165Y205723I-130J-152D01*
G01X130901D01*
G03X130771Y205675I0J-200D01*
G01X130770Y205674D01*
G02X129783Y205304I-987J1131D01*
G37*
G36*
G01X232145D02*
G02Y208308I0J1502D01*
G02X233132Y207938I0J-1501D01*
G01X233133D01*
Y207937D01*
G03X233263Y207889I130J152D01*
G01X233527D01*
G03X233657Y207937I0J200D01*
G01X233658Y207938D01*
G02X234645Y208308I987J-1131D01*
G02Y205304I0J-1502D01*
G02X233658Y205674I0J1501D01*
G01X233657D01*
Y205675D01*
G03X233527Y205723I-130J-152D01*
G01X233263D01*
G03X233133Y205675I0J-200D01*
G01X233132Y205674D01*
G02X232145Y205304I-987J1131D01*
G37*
G36*
G01X334507D02*
G02Y208308I0J1502D01*
G02X335494Y207938I0J-1501D01*
G01X335495D01*
Y207937D01*
G03X335625Y207889I130J152D01*
G01X335889D01*
G03X336019Y207937I0J200D01*
G01X336020Y207938D01*
G02X337007Y208308I987J-1131D01*
G02Y205304I0J-1502D01*
G02X336020Y205674I0J1501D01*
G01X336019D01*
Y205675D01*
G03X335889Y205723I-130J-152D01*
G01X335625D01*
G03X335495Y205675I0J-200D01*
G01X335494Y205674D01*
G02X334507Y205304I-987J1131D01*
G37*
G36*
G01X484508D02*
G02Y208308I0J1502D01*
G02X485495Y207938I0J-1501D01*
G01X485496D01*
Y207937D01*
G03X485626Y207889I130J152D01*
G01X485890D01*
G03X486020Y207937I0J200D01*
G01X486021Y207938D01*
G02X487008Y208308I987J-1131D01*
G02Y205304I0J-1502D01*
G02X486021Y205674I0J1501D01*
G01X486020D01*
Y205675D01*
G03X485890Y205723I-130J-152D01*
G01X485626D01*
G03X485496Y205675I0J-200D01*
G01X485495Y205674D01*
G02X484508Y205304I-987J1131D01*
G37*
G36*
G01X586870D02*
G02Y208308I0J1502D01*
G02X587857Y207938I0J-1501D01*
G01X587858D01*
Y207937D01*
G03X587988Y207889I130J152D01*
G01X588252D01*
G03X588382Y207937I0J200D01*
G01X588383Y207938D01*
G02X589370Y208308I987J-1131D01*
G02Y205304I0J-1502D01*
G02X588383Y205674I0J1501D01*
G01X588382D01*
Y205675D01*
G03X588252Y205723I-130J-152D01*
G01X587988D01*
G03X587858Y205675I0J-200D01*
G01X587857Y205674D01*
G02X586870Y205304I-987J1131D01*
G37*
G36*
G01X689232D02*
G02Y208308I0J1502D01*
G02X690219Y207938I0J-1501D01*
G01X690220D01*
Y207937D01*
G03X690350Y207889I130J152D01*
G01X690614D01*
G03X690744Y207937I0J200D01*
G01X690745Y207938D01*
G02X691732Y208308I987J-1131D01*
G02Y205304I0J-1502D01*
G02X690745Y205674I0J1501D01*
G01X690744D01*
Y205675D01*
G03X690614Y205723I-130J-152D01*
G01X690350D01*
G03X690220Y205675I0J-200D01*
G01X690219Y205674D01*
G02X689232Y205304I-987J1131D01*
G37*
G36*
G01X791594D02*
G02Y208308I0J1502D01*
G02X792581Y207938I0J-1501D01*
G01X792582D01*
Y207937D01*
G03X792712Y207889I130J152D01*
G01X792976D01*
G03X793106Y207937I0J200D01*
G01X793107Y207938D01*
G02X794094Y208308I987J-1131D01*
G02Y205304I0J-1502D01*
G02X793107Y205674I0J1501D01*
G01X793106D01*
Y205675D01*
G03X792976Y205723I-130J-152D01*
G01X792712D01*
G03X792582Y205675I0J-200D01*
G01X792581Y205674D01*
G02X791594Y205304I-987J1131D01*
G37*
G36*
G01X1043956D02*
G02Y208308I0J1502D01*
G02X1044943Y207938I0J-1501D01*
G01X1044944D01*
Y207937D01*
G03X1045074Y207889I130J152D01*
G01X1045338D01*
G03X1045468Y207937I0J200D01*
G01X1045469Y207938D01*
G02X1046456Y208308I987J-1131D01*
G02Y205304I0J-1502D01*
G02X1045469Y205674I0J1501D01*
G01X1045468D01*
Y205675D01*
G03X1045338Y205723I-130J-152D01*
G01X1045074D01*
G03X1044944Y205675I0J-200D01*
G01X1044943Y205674D01*
G02X1043956Y205304I-987J1131D01*
G37*
G36*
G01X1146318D02*
G02Y208308I0J1502D01*
G02X1147305Y207938I0J-1501D01*
G01X1147306D01*
Y207937D01*
G03X1147436Y207889I130J152D01*
G01X1147700D01*
G03X1147830Y207937I0J200D01*
G01X1147831Y207938D01*
G02X1148818Y208308I987J-1131D01*
G02Y205304I0J-1502D01*
G02X1147831Y205674I0J1501D01*
G01X1147830D01*
Y205675D01*
G03X1147700Y205723I-130J-152D01*
G01X1147436D01*
G03X1147306Y205675I0J-200D01*
G01X1147305Y205674D01*
G02X1146318Y205304I-987J1131D01*
G37*
G36*
G01X1248680D02*
G02Y208308I0J1502D01*
G02X1249667Y207938I0J-1501D01*
G01X1249668D01*
Y207937D01*
G03X1249798Y207889I130J152D01*
G01X1250062D01*
G03X1250192Y207937I0J200D01*
G01X1250193Y207938D01*
G02X1251180Y208308I987J-1131D01*
G02Y205304I0J-1502D01*
G02X1250193Y205674I0J1501D01*
G01X1250192D01*
Y205675D01*
G03X1250062Y205723I-130J-152D01*
G01X1249798D01*
G03X1249668Y205675I0J-200D01*
G01X1249667Y205674D01*
G02X1248680Y205304I-987J1131D01*
G37*
G36*
G01X1398681D02*
G02Y208308I0J1502D01*
G02X1399668Y207938I0J-1501D01*
G01X1399669D01*
Y207937D01*
G03X1399799Y207889I130J152D01*
G01X1400063D01*
G03X1400193Y207937I0J200D01*
G01X1400194Y207938D01*
G02X1401181Y208308I987J-1131D01*
G02Y205304I0J-1502D01*
G02X1400194Y205674I0J1501D01*
G01X1400193D01*
Y205675D01*
G03X1400063Y205723I-130J-152D01*
G01X1399799D01*
G03X1399669Y205675I0J-200D01*
G01X1399668Y205674D01*
G02X1398681Y205304I-987J1131D01*
G37*
G36*
G01X1501043D02*
G02Y208308I0J1502D01*
G02X1502030Y207938I0J-1501D01*
G01X1502031D01*
Y207937D01*
G03X1502161Y207889I130J152D01*
G01X1502425D01*
G03X1502555Y207937I0J200D01*
G01X1502556Y207938D01*
G02X1503543Y208308I987J-1131D01*
G02Y205304I0J-1502D01*
G02X1502556Y205674I0J1501D01*
G01X1502555D01*
Y205675D01*
G03X1502425Y205723I-130J-152D01*
G01X1502161D01*
G03X1502031Y205675I0J-200D01*
G01X1502030Y205674D01*
G02X1501043Y205304I-987J1131D01*
G37*
G36*
G01X1603405D02*
G02Y208308I0J1502D01*
G02X1604392Y207938I0J-1501D01*
G01X1604393D01*
Y207937D01*
G03X1604523Y207889I130J152D01*
G01X1604787D01*
G03X1604917Y207937I0J200D01*
G01X1604918Y207938D01*
G02X1605905Y208308I987J-1131D01*
G02Y205304I0J-1502D01*
G02X1604918Y205674I0J1501D01*
G01X1604917D01*
Y205675D01*
G03X1604787Y205723I-130J-152D01*
G01X1604523D01*
G03X1604393Y205675I0J-200D01*
G01X1604392Y205674D01*
G02X1603405Y205304I-987J1131D01*
G37*
G36*
G01X1705767D02*
G02Y208308I0J1502D01*
G02X1706754Y207938I0J-1501D01*
G01X1706755D01*
Y207937D01*
G03X1706885Y207889I130J152D01*
G01X1707149D01*
G03X1707279Y207937I0J200D01*
G01X1707280Y207938D01*
G02X1708267Y208308I987J-1131D01*
G02Y205304I0J-1502D01*
G02X1707280Y205674I0J1501D01*
G01X1707279D01*
Y205675D01*
G03X1707149Y205723I-130J-152D01*
G01X1706885D01*
G03X1706755Y205675I0J-200D01*
G01X1706754Y205674D01*
G02X1705767Y205304I-987J1131D01*
G37*
G36*
G01X932909Y207141D02*
G02X935913I1502J0D01*
G02X935543Y206154I-1501J0D01*
G01Y206153D01*
X935542D01*
G03X935494Y206023I152J-130D01*
G01Y205759D01*
G03X935542Y205629I200J0D01*
G01X935543Y205628D01*
G02Y203654I-1131J-987D01*
G01Y203653D01*
X935542D01*
G03X935494Y203523I152J-130D01*
G01Y203259D01*
G03X935542Y203129I200J0D01*
G01X935543Y203128D01*
G02X935913Y202141I-1131J-987D01*
G02X934411Y200639I-1502J0D01*
G02X933556Y200906I0J1502D01*
G01X933522Y200929D01*
X933441Y200946D01*
X933074Y200866D01*
X933007Y200818D01*
X932986Y200783D01*
G02X931698Y200054I-1288J773D01*
G02Y203058I0J1502D01*
G02X932553Y202791I0J-1502D01*
G01X932587Y202768D01*
X932668Y202751D01*
X933035Y202831D01*
X933102Y202879D01*
X933123Y202914D01*
G02X933279Y203127I1285J-777D01*
G03X933280Y203129I-173J88D01*
G03X933328Y203259I-152J130D01*
G01Y203523D01*
G03X933280Y203653I-200J0D01*
G01X933279Y203654D01*
G02Y205628I1131J987D01*
G01Y205629D01*
X933280D01*
G03X933328Y205759I-152J130D01*
G01Y206023D01*
G03X933280Y206153I-200J0D01*
G01X933279Y206154D01*
G02X932909Y207141I1131J987D01*
G37*
G36*
G01X25648Y209007D02*
G02Y212011I0J1502D01*
G02X26635Y211641I0J-1501D01*
G01X26636D01*
Y211640D01*
G03X26766Y211592I130J152D01*
G01X27030D01*
G03X27160Y211640I0J200D01*
G01X27161Y211641D01*
G02X28148Y212011I987J-1131D01*
G02Y209007I0J-1502D01*
G02X27161Y209377I0J1501D01*
G01X27160D01*
Y209378D01*
G03X27030Y209426I-130J-152D01*
G01X26766D01*
G03X26636Y209378I0J-200D01*
G01X26635Y209377D01*
G02X25648Y209007I-987J1131D01*
G37*
G36*
G01X128010D02*
G02Y212011I0J1502D01*
G02X128997Y211641I0J-1501D01*
G01X128998D01*
Y211640D01*
G03X129128Y211592I130J152D01*
G01X129392D01*
G03X129522Y211640I0J200D01*
G01X129523Y211641D01*
G02X130510Y212011I987J-1131D01*
G02Y209007I0J-1502D01*
G02X129523Y209377I0J1501D01*
G01X129522D01*
Y209378D01*
G03X129392Y209426I-130J-152D01*
G01X129128D01*
G03X128998Y209378I0J-200D01*
G01X128997Y209377D01*
G02X128010Y209007I-987J1131D01*
G37*
G36*
G01X230372D02*
G02Y212011I0J1502D01*
G02X231359Y211641I0J-1501D01*
G01X231360D01*
Y211640D01*
G03X231490Y211592I130J152D01*
G01X231754D01*
G03X231884Y211640I0J200D01*
G01X231885Y211641D01*
G02X232872Y212011I987J-1131D01*
G02Y209007I0J-1502D01*
G02X231885Y209377I0J1501D01*
G01X231884D01*
Y209378D01*
G03X231754Y209426I-130J-152D01*
G01X231490D01*
G03X231360Y209378I0J-200D01*
G01X231359Y209377D01*
G02X230372Y209007I-987J1131D01*
G37*
G36*
G01X332734D02*
G02Y212011I0J1502D01*
G02X333721Y211641I0J-1501D01*
G01X333722D01*
Y211640D01*
G03X333852Y211592I130J152D01*
G01X334116D01*
G03X334246Y211640I0J200D01*
G01X334247Y211641D01*
G02X335234Y212011I987J-1131D01*
G02Y209007I0J-1502D01*
G02X334247Y209377I0J1501D01*
G01X334246D01*
Y209378D01*
G03X334116Y209426I-130J-152D01*
G01X333852D01*
G03X333722Y209378I0J-200D01*
G01X333721Y209377D01*
G02X332734Y209007I-987J1131D01*
G37*
G36*
G01X482735D02*
G02Y212011I0J1502D01*
G02X483722Y211641I0J-1501D01*
G01X483723D01*
Y211640D01*
G03X483853Y211592I130J152D01*
G01X484117D01*
G03X484247Y211640I0J200D01*
G01X484248Y211641D01*
G02X485235Y212011I987J-1131D01*
G02Y209007I0J-1502D01*
G02X484248Y209377I0J1501D01*
G01X484247D01*
Y209378D01*
G03X484117Y209426I-130J-152D01*
G01X483853D01*
G03X483723Y209378I0J-200D01*
G01X483722Y209377D01*
G02X482735Y209007I-987J1131D01*
G37*
G36*
G01X585097D02*
G02Y212011I0J1502D01*
G02X586084Y211641I0J-1501D01*
G01X586085D01*
Y211640D01*
G03X586215Y211592I130J152D01*
G01X586479D01*
G03X586609Y211640I0J200D01*
G01X586610Y211641D01*
G02X587597Y212011I987J-1131D01*
G02Y209007I0J-1502D01*
G02X586610Y209377I0J1501D01*
G01X586609D01*
Y209378D01*
G03X586479Y209426I-130J-152D01*
G01X586215D01*
G03X586085Y209378I0J-200D01*
G01X586084Y209377D01*
G02X585097Y209007I-987J1131D01*
G37*
G36*
G01X687459D02*
G02Y212011I0J1502D01*
G02X688446Y211641I0J-1501D01*
G01X688447D01*
Y211640D01*
G03X688577Y211592I130J152D01*
G01X688841D01*
G03X688971Y211640I0J200D01*
G01X688972Y211641D01*
G02X689959Y212011I987J-1131D01*
G02Y209007I0J-1502D01*
G02X688972Y209377I0J1501D01*
G01X688971D01*
Y209378D01*
G03X688841Y209426I-130J-152D01*
G01X688577D01*
G03X688447Y209378I0J-200D01*
G01X688446Y209377D01*
G02X687459Y209007I-987J1131D01*
G37*
G36*
G01X789821D02*
G02Y212011I0J1502D01*
G02X790808Y211641I0J-1501D01*
G01X790809D01*
Y211640D01*
G03X790939Y211592I130J152D01*
G01X791203D01*
G03X791333Y211640I0J200D01*
G01X791334Y211641D01*
G02X792321Y212011I987J-1131D01*
G02Y209007I0J-1502D01*
G02X791334Y209377I0J1501D01*
G01X791333D01*
Y209378D01*
G03X791203Y209426I-130J-152D01*
G01X790939D01*
G03X790809Y209378I0J-200D01*
G01X790808Y209377D01*
G02X789821Y209007I-987J1131D01*
G37*
G36*
G01X1042183D02*
G02Y212011I0J1502D01*
G02X1043170Y211641I0J-1501D01*
G01X1043171D01*
Y211640D01*
G03X1043301Y211592I130J152D01*
G01X1043565D01*
G03X1043695Y211640I0J200D01*
G01X1043696Y211641D01*
G02X1044683Y212011I987J-1131D01*
G02Y209007I0J-1502D01*
G02X1043696Y209377I0J1501D01*
G01X1043695D01*
Y209378D01*
G03X1043565Y209426I-130J-152D01*
G01X1043301D01*
G03X1043171Y209378I0J-200D01*
G01X1043170Y209377D01*
G02X1042183Y209007I-987J1131D01*
G37*
G36*
G01X1144545D02*
G02Y212011I0J1502D01*
G02X1145532Y211641I0J-1501D01*
G01X1145533D01*
Y211640D01*
G03X1145663Y211592I130J152D01*
G01X1145927D01*
G03X1146057Y211640I0J200D01*
G01X1146058Y211641D01*
G02X1147045Y212011I987J-1131D01*
G02Y209007I0J-1502D01*
G02X1146058Y209377I0J1501D01*
G01X1146057D01*
Y209378D01*
G03X1145927Y209426I-130J-152D01*
G01X1145663D01*
G03X1145533Y209378I0J-200D01*
G01X1145532Y209377D01*
G02X1144545Y209007I-987J1131D01*
G37*
G36*
G01X1246907D02*
G02Y212011I0J1502D01*
G02X1247894Y211641I0J-1501D01*
G01X1247895D01*
Y211640D01*
G03X1248025Y211592I130J152D01*
G01X1248289D01*
G03X1248419Y211640I0J200D01*
G01X1248420Y211641D01*
G02X1249407Y212011I987J-1131D01*
G02Y209007I0J-1502D01*
G02X1248420Y209377I0J1501D01*
G01X1248419D01*
Y209378D01*
G03X1248289Y209426I-130J-152D01*
G01X1248025D01*
G03X1247895Y209378I0J-200D01*
G01X1247894Y209377D01*
G02X1246907Y209007I-987J1131D01*
G37*
G36*
G01X1396908D02*
G02Y212011I0J1502D01*
G02X1397895Y211641I0J-1501D01*
G01X1397896D01*
Y211640D01*
G03X1398026Y211592I130J152D01*
G01X1398290D01*
G03X1398420Y211640I0J200D01*
G01X1398421Y211641D01*
G02X1399408Y212011I987J-1131D01*
G02Y209007I0J-1502D01*
G02X1398421Y209377I0J1501D01*
G01X1398420D01*
Y209378D01*
G03X1398290Y209426I-130J-152D01*
G01X1398026D01*
G03X1397896Y209378I0J-200D01*
G01X1397895Y209377D01*
G02X1396908Y209007I-987J1131D01*
G37*
G36*
G01X1499270D02*
G02Y212011I0J1502D01*
G02X1500257Y211641I0J-1501D01*
G01X1500258D01*
Y211640D01*
G03X1500388Y211592I130J152D01*
G01X1500652D01*
G03X1500782Y211640I0J200D01*
G01X1500783Y211641D01*
G02X1501770Y212011I987J-1131D01*
G02Y209007I0J-1502D01*
G02X1500783Y209377I0J1501D01*
G01X1500782D01*
Y209378D01*
G03X1500652Y209426I-130J-152D01*
G01X1500388D01*
G03X1500258Y209378I0J-200D01*
G01X1500257Y209377D01*
G02X1499270Y209007I-987J1131D01*
G37*
G36*
G01X1601632D02*
G02Y212011I0J1502D01*
G02X1602619Y211641I0J-1501D01*
G01X1602620D01*
Y211640D01*
G03X1602750Y211592I130J152D01*
G01X1603014D01*
G03X1603144Y211640I0J200D01*
G01X1603145Y211641D01*
G02X1604132Y212011I987J-1131D01*
G02Y209007I0J-1502D01*
G02X1603145Y209377I0J1501D01*
G01X1603144D01*
Y209378D01*
G03X1603014Y209426I-130J-152D01*
G01X1602750D01*
G03X1602620Y209378I0J-200D01*
G01X1602619Y209377D01*
G02X1601632Y209007I-987J1131D01*
G37*
G36*
G01X1703994D02*
G02Y212011I0J1502D01*
G02X1704981Y211641I0J-1501D01*
G01X1704982D01*
Y211640D01*
G03X1705112Y211592I130J152D01*
G01X1705376D01*
G03X1705506Y211640I0J200D01*
G01X1705507Y211641D01*
G02X1706494Y212011I987J-1131D01*
G02Y209007I0J-1502D01*
G02X1705507Y209377I0J1501D01*
G01X1705506D01*
Y209378D01*
G03X1705376Y209426I-130J-152D01*
G01X1705112D01*
G03X1704982Y209378I0J-200D01*
G01X1704981Y209377D01*
G02X1703994Y209007I-987J1131D01*
G37*
G36*
G01X75317Y213859D02*
G02X78321I1502J0D01*
G02X77951Y212872I-1501J0D01*
G01Y212871D01*
X77950D01*
G03X77902Y212741I152J-130D01*
G01Y212477D01*
G03X77950Y212347I200J0D01*
G01X77951Y212346D01*
G02X78321Y211359I-1131J-987D01*
G02X75317I-1502J0D01*
G02X75687Y212346I1501J0D01*
G01Y212347D01*
X75688D01*
G03X75736Y212477I-152J130D01*
G01Y212741D01*
G03X75688Y212871I-200J0D01*
G01X75687Y212872D01*
G02X75317Y213859I1131J987D01*
G37*
G36*
G01X177679D02*
G02X180683I1502J0D01*
G02X180313Y212872I-1501J0D01*
G01Y212871D01*
X180312D01*
G03X180264Y212741I152J-130D01*
G01Y212477D01*
G03X180312Y212347I200J0D01*
G01X180313Y212346D01*
G02X180683Y211359I-1131J-987D01*
G02X177679I-1502J0D01*
G02X178049Y212346I1501J0D01*
G01Y212347D01*
X178050D01*
G03X178098Y212477I-152J130D01*
G01Y212741D01*
G03X178050Y212871I-200J0D01*
G01X178049Y212872D01*
G02X177679Y213859I1131J987D01*
G37*
G36*
G01X280041D02*
G02X283045I1502J0D01*
G02X282675Y212872I-1501J0D01*
G01Y212871D01*
X282674D01*
G03X282626Y212741I152J-130D01*
G01Y212477D01*
G03X282674Y212347I200J0D01*
G01X282675Y212346D01*
G02X283045Y211359I-1131J-987D01*
G02X280041I-1502J0D01*
G02X280411Y212346I1501J0D01*
G01Y212347D01*
X280412D01*
G03X280460Y212477I-152J130D01*
G01Y212741D01*
G03X280412Y212871I-200J0D01*
G01X280411Y212872D01*
G02X280041Y213859I1131J987D01*
G37*
G36*
G01X382403D02*
G02X385407I1502J0D01*
G02X385037Y212872I-1501J0D01*
G01Y212871D01*
X385036D01*
G03X384988Y212741I152J-130D01*
G01Y212477D01*
G03X385036Y212347I200J0D01*
G01X385037Y212346D01*
G02X385407Y211359I-1131J-987D01*
G02X382403I-1502J0D01*
G02X382773Y212346I1501J0D01*
G01Y212347D01*
X382774D01*
G03X382822Y212477I-152J130D01*
G01Y212741D01*
G03X382774Y212871I-200J0D01*
G01X382773Y212872D01*
G02X382403Y213859I1131J987D01*
G37*
G36*
G01X532404D02*
G02X535408I1502J0D01*
G02X535038Y212872I-1501J0D01*
G01Y212871D01*
X535037D01*
G03X534989Y212741I152J-130D01*
G01Y212477D01*
G03X535037Y212347I200J0D01*
G01X535038Y212346D01*
G02X535408Y211359I-1131J-987D01*
G02X532404I-1502J0D01*
G02X532774Y212346I1501J0D01*
G01Y212347D01*
X532775D01*
G03X532823Y212477I-152J130D01*
G01Y212741D01*
G03X532775Y212871I-200J0D01*
G01X532774Y212872D01*
G02X532404Y213859I1131J987D01*
G37*
G36*
G01X634766D02*
G02X637770I1502J0D01*
G02X637400Y212872I-1501J0D01*
G01Y212871D01*
X637399D01*
G03X637351Y212741I152J-130D01*
G01Y212477D01*
G03X637399Y212347I200J0D01*
G01X637400Y212346D01*
G02X637770Y211359I-1131J-987D01*
G02X634766I-1502J0D01*
G02X635136Y212346I1501J0D01*
G01Y212347D01*
X635137D01*
G03X635185Y212477I-152J130D01*
G01Y212741D01*
G03X635137Y212871I-200J0D01*
G01X635136Y212872D01*
G02X634766Y213859I1131J987D01*
G37*
G36*
G01X737128D02*
G02X740132I1502J0D01*
G02X739762Y212872I-1501J0D01*
G01Y212871D01*
X739761D01*
G03X739713Y212741I152J-130D01*
G01Y212477D01*
G03X739761Y212347I200J0D01*
G01X739762Y212346D01*
G02X740132Y211359I-1131J-987D01*
G02X737128I-1502J0D01*
G02X737498Y212346I1501J0D01*
G01Y212347D01*
X737499D01*
G03X737547Y212477I-152J130D01*
G01Y212741D01*
G03X737499Y212871I-200J0D01*
G01X737498Y212872D01*
G02X737128Y213859I1131J987D01*
G37*
G36*
G01X839490D02*
G02X842494I1502J0D01*
G02X842124Y212872I-1501J0D01*
G01Y212871D01*
X842123D01*
G03X842075Y212741I152J-130D01*
G01Y212477D01*
G03X842123Y212347I200J0D01*
G01X842124Y212346D01*
G02X842494Y211359I-1131J-987D01*
G02X839490I-1502J0D01*
G02X839860Y212346I1501J0D01*
G01Y212347D01*
X839861D01*
G03X839909Y212477I-152J130D01*
G01Y212741D01*
G03X839861Y212871I-200J0D01*
G01X839860Y212872D01*
G02X839490Y213859I1131J987D01*
G37*
G36*
G01X989490D02*
G02X992494I1502J0D01*
G02X992124Y212872I-1501J0D01*
G01Y212871D01*
X992123D01*
G03X992075Y212741I152J-130D01*
G01Y212477D01*
G03X992123Y212347I200J0D01*
G01X992124Y212346D01*
G02X992494Y211359I-1131J-987D01*
G02X989490I-1502J0D01*
G02X989860Y212346I1501J0D01*
G01Y212347D01*
X989861D01*
G03X989909Y212477I-152J130D01*
G01Y212741D01*
G03X989861Y212871I-200J0D01*
G01X989860Y212872D01*
G02X989490Y213859I1131J987D01*
G37*
G36*
G01X1091852D02*
G02X1094856I1502J0D01*
G02X1094486Y212872I-1501J0D01*
G01Y212871D01*
X1094485D01*
G03X1094437Y212741I152J-130D01*
G01Y212477D01*
G03X1094485Y212347I200J0D01*
G01X1094486Y212346D01*
G02X1094856Y211359I-1131J-987D01*
G02X1091852I-1502J0D01*
G02X1092222Y212346I1501J0D01*
G01Y212347D01*
X1092223D01*
G03X1092271Y212477I-152J130D01*
G01Y212741D01*
G03X1092223Y212871I-200J0D01*
G01X1092222Y212872D01*
G02X1091852Y213859I1131J987D01*
G37*
G36*
G01X1194214D02*
G02X1197218I1502J0D01*
G02X1196848Y212872I-1501J0D01*
G01Y212871D01*
X1196847D01*
G03X1196799Y212741I152J-130D01*
G01Y212477D01*
G03X1196847Y212347I200J0D01*
G01X1196848Y212346D01*
G02X1197218Y211359I-1131J-987D01*
G02X1194214I-1502J0D01*
G02X1194584Y212346I1501J0D01*
G01Y212347D01*
X1194585D01*
G03X1194633Y212477I-152J130D01*
G01Y212741D01*
G03X1194585Y212871I-200J0D01*
G01X1194584Y212872D01*
G02X1194214Y213859I1131J987D01*
G37*
G36*
G01X1296576D02*
G02X1299580I1502J0D01*
G02X1299210Y212872I-1501J0D01*
G01Y212871D01*
X1299209D01*
G03X1299161Y212741I152J-130D01*
G01Y212477D01*
G03X1299209Y212347I200J0D01*
G01X1299210Y212346D01*
G02X1299580Y211359I-1131J-987D01*
G02X1296576I-1502J0D01*
G02X1296946Y212346I1501J0D01*
G01Y212347D01*
X1296947D01*
G03X1296995Y212477I-152J130D01*
G01Y212741D01*
G03X1296947Y212871I-200J0D01*
G01X1296946Y212872D01*
G02X1296576Y213859I1131J987D01*
G37*
G36*
G01X1446577D02*
G02X1449581I1502J0D01*
G02X1449211Y212872I-1501J0D01*
G01Y212871D01*
X1449210D01*
G03X1449162Y212741I152J-130D01*
G01Y212477D01*
G03X1449210Y212347I200J0D01*
G01X1449211Y212346D01*
G02X1449581Y211359I-1131J-987D01*
G02X1446577I-1502J0D01*
G02X1446947Y212346I1501J0D01*
G01Y212347D01*
X1446948D01*
G03X1446996Y212477I-152J130D01*
G01Y212741D01*
G03X1446948Y212871I-200J0D01*
G01X1446947Y212872D01*
G02X1446577Y213859I1131J987D01*
G37*
G36*
G01X1548939D02*
G02X1551943I1502J0D01*
G02X1551573Y212872I-1501J0D01*
G01Y212871D01*
X1551572D01*
G03X1551524Y212741I152J-130D01*
G01Y212477D01*
G03X1551572Y212347I200J0D01*
G01X1551573Y212346D01*
G02X1551943Y211359I-1131J-987D01*
G02X1548939I-1502J0D01*
G02X1549309Y212346I1501J0D01*
G01Y212347D01*
X1549310D01*
G03X1549358Y212477I-152J130D01*
G01Y212741D01*
G03X1549310Y212871I-200J0D01*
G01X1549309Y212872D01*
G02X1548939Y213859I1131J987D01*
G37*
G36*
G01X1651301D02*
G02X1654305I1502J0D01*
G02X1653935Y212872I-1501J0D01*
G01Y212871D01*
X1653934D01*
G03X1653886Y212741I152J-130D01*
G01Y212477D01*
G03X1653934Y212347I200J0D01*
G01X1653935Y212346D01*
G02X1654305Y211359I-1131J-987D01*
G02X1651301I-1502J0D01*
G02X1651671Y212346I1501J0D01*
G01Y212347D01*
X1651672D01*
G03X1651720Y212477I-152J130D01*
G01Y212741D01*
G03X1651672Y212871I-200J0D01*
G01X1651671Y212872D01*
G02X1651301Y213859I1131J987D01*
G37*
G36*
G01X1753663D02*
G02X1756667I1502J0D01*
G02X1756297Y212872I-1501J0D01*
G01Y212871D01*
X1756296D01*
G03X1756248Y212741I152J-130D01*
G01Y212477D01*
G03X1756296Y212347I200J0D01*
G01X1756297Y212346D01*
G02X1756667Y211359I-1131J-987D01*
G02X1753663I-1502J0D01*
G02X1754033Y212346I1501J0D01*
G01Y212347D01*
X1754034D01*
G03X1754082Y212477I-152J130D01*
G01Y212741D01*
G03X1754034Y212871I-200J0D01*
G01X1754033Y212872D01*
G02X1753663Y213859I1131J987D01*
G37*
G36*
G01X79020Y215632D02*
G02X82024I1502J0D01*
G02X81654Y214645I-1501J0D01*
G01Y214644D01*
X81653D01*
G03X81605Y214514I152J-130D01*
G01Y214250D01*
G03X81653Y214120I200J0D01*
G01X81654Y214119D01*
G02X82024Y213132I-1131J-987D01*
G02X79020I-1502J0D01*
G02X79390Y214119I1501J0D01*
G01Y214120D01*
X79391D01*
G03X79439Y214250I-152J130D01*
G01Y214514D01*
G03X79391Y214644I-200J0D01*
G01X79390Y214645D01*
G02X79020Y215632I1131J987D01*
G37*
G36*
G01X181382D02*
G02X184386I1502J0D01*
G02X184016Y214645I-1501J0D01*
G01Y214644D01*
X184015D01*
G03X183967Y214514I152J-130D01*
G01Y214250D01*
G03X184015Y214120I200J0D01*
G01X184016Y214119D01*
G02X184386Y213132I-1131J-987D01*
G02X181382I-1502J0D01*
G02X181752Y214119I1501J0D01*
G01Y214120D01*
X181753D01*
G03X181801Y214250I-152J130D01*
G01Y214514D01*
G03X181753Y214644I-200J0D01*
G01X181752Y214645D01*
G02X181382Y215632I1131J987D01*
G37*
G36*
G01X283744D02*
G02X286748I1502J0D01*
G02X286378Y214645I-1501J0D01*
G01Y214644D01*
X286377D01*
G03X286329Y214514I152J-130D01*
G01Y214250D01*
G03X286377Y214120I200J0D01*
G01X286378Y214119D01*
G02X286748Y213132I-1131J-987D01*
G02X283744I-1502J0D01*
G02X284114Y214119I1501J0D01*
G01Y214120D01*
X284115D01*
G03X284163Y214250I-152J130D01*
G01Y214514D01*
G03X284115Y214644I-200J0D01*
G01X284114Y214645D01*
G02X283744Y215632I1131J987D01*
G37*
G36*
G01X386106D02*
G02X389110I1502J0D01*
G02X388740Y214645I-1501J0D01*
G01Y214644D01*
X388739D01*
G03X388691Y214514I152J-130D01*
G01Y214250D01*
G03X388739Y214120I200J0D01*
G01X388740Y214119D01*
G02X389110Y213132I-1131J-987D01*
G02X386106I-1502J0D01*
G02X386476Y214119I1501J0D01*
G01Y214120D01*
X386477D01*
G03X386525Y214250I-152J130D01*
G01Y214514D01*
G03X386477Y214644I-200J0D01*
G01X386476Y214645D01*
G02X386106Y215632I1131J987D01*
G37*
G36*
G01X536107D02*
G02X539111I1502J0D01*
G02X538741Y214645I-1501J0D01*
G01Y214644D01*
X538740D01*
G03X538692Y214514I152J-130D01*
G01Y214250D01*
G03X538740Y214120I200J0D01*
G01X538741Y214119D01*
G02X539111Y213132I-1131J-987D01*
G02X536107I-1502J0D01*
G02X536477Y214119I1501J0D01*
G01Y214120D01*
X536478D01*
G03X536526Y214250I-152J130D01*
G01Y214514D01*
G03X536478Y214644I-200J0D01*
G01X536477Y214645D01*
G02X536107Y215632I1131J987D01*
G37*
G36*
G01X638469D02*
G02X641473I1502J0D01*
G02X641103Y214645I-1501J0D01*
G01Y214644D01*
X641102D01*
G03X641054Y214514I152J-130D01*
G01Y214250D01*
G03X641102Y214120I200J0D01*
G01X641103Y214119D01*
G02X641473Y213132I-1131J-987D01*
G02X638469I-1502J0D01*
G02X638839Y214119I1501J0D01*
G01Y214120D01*
X638840D01*
G03X638888Y214250I-152J130D01*
G01Y214514D01*
G03X638840Y214644I-200J0D01*
G01X638839Y214645D01*
G02X638469Y215632I1131J987D01*
G37*
G36*
G01X740831D02*
G02X743835I1502J0D01*
G02X743465Y214645I-1501J0D01*
G01Y214644D01*
X743464D01*
G03X743416Y214514I152J-130D01*
G01Y214250D01*
G03X743464Y214120I200J0D01*
G01X743465Y214119D01*
G02X743835Y213132I-1131J-987D01*
G02X740831I-1502J0D01*
G02X741201Y214119I1501J0D01*
G01Y214120D01*
X741202D01*
G03X741250Y214250I-152J130D01*
G01Y214514D01*
G03X741202Y214644I-200J0D01*
G01X741201Y214645D01*
G02X740831Y215632I1131J987D01*
G37*
G36*
G01X843193D02*
G02X846197I1502J0D01*
G02X845827Y214645I-1501J0D01*
G01Y214644D01*
X845826D01*
G03X845778Y214514I152J-130D01*
G01Y214250D01*
G03X845826Y214120I200J0D01*
G01X845827Y214119D01*
G02X846197Y213132I-1131J-987D01*
G02X843193I-1502J0D01*
G02X843563Y214119I1501J0D01*
G01Y214120D01*
X843564D01*
G03X843612Y214250I-152J130D01*
G01Y214514D01*
G03X843564Y214644I-200J0D01*
G01X843563Y214645D01*
G02X843193Y215632I1131J987D01*
G37*
G36*
G01X993193D02*
G02X996197I1502J0D01*
G02X995827Y214645I-1501J0D01*
G01Y214644D01*
X995826D01*
G03X995778Y214514I152J-130D01*
G01Y214250D01*
G03X995826Y214120I200J0D01*
G01X995827Y214119D01*
G02X996197Y213132I-1131J-987D01*
G02X993193I-1502J0D01*
G02X993563Y214119I1501J0D01*
G01Y214120D01*
X993564D01*
G03X993612Y214250I-152J130D01*
G01Y214514D01*
G03X993564Y214644I-200J0D01*
G01X993563Y214645D01*
G02X993193Y215632I1131J987D01*
G37*
G36*
G01X1095555D02*
G02X1098559I1502J0D01*
G02X1098189Y214645I-1501J0D01*
G01Y214644D01*
X1098188D01*
G03X1098140Y214514I152J-130D01*
G01Y214250D01*
G03X1098188Y214120I200J0D01*
G01X1098189Y214119D01*
G02X1098559Y213132I-1131J-987D01*
G02X1095555I-1502J0D01*
G02X1095925Y214119I1501J0D01*
G01Y214120D01*
X1095926D01*
G03X1095974Y214250I-152J130D01*
G01Y214514D01*
G03X1095926Y214644I-200J0D01*
G01X1095925Y214645D01*
G02X1095555Y215632I1131J987D01*
G37*
G36*
G01X1197917D02*
G02X1200921I1502J0D01*
G02X1200551Y214645I-1501J0D01*
G01Y214644D01*
X1200550D01*
G03X1200502Y214514I152J-130D01*
G01Y214250D01*
G03X1200550Y214120I200J0D01*
G01X1200551Y214119D01*
G02X1200921Y213132I-1131J-987D01*
G02X1197917I-1502J0D01*
G02X1198287Y214119I1501J0D01*
G01Y214120D01*
X1198288D01*
G03X1198336Y214250I-152J130D01*
G01Y214514D01*
G03X1198288Y214644I-200J0D01*
G01X1198287Y214645D01*
G02X1197917Y215632I1131J987D01*
G37*
G36*
G01X1300279D02*
G02X1303283I1502J0D01*
G02X1302913Y214645I-1501J0D01*
G01Y214644D01*
X1302912D01*
G03X1302864Y214514I152J-130D01*
G01Y214250D01*
G03X1302912Y214120I200J0D01*
G01X1302913Y214119D01*
G02X1303283Y213132I-1131J-987D01*
G02X1300279I-1502J0D01*
G02X1300649Y214119I1501J0D01*
G01Y214120D01*
X1300650D01*
G03X1300698Y214250I-152J130D01*
G01Y214514D01*
G03X1300650Y214644I-200J0D01*
G01X1300649Y214645D01*
G02X1300279Y215632I1131J987D01*
G37*
G36*
G01X1450280D02*
G02X1453284I1502J0D01*
G02X1452914Y214645I-1501J0D01*
G01Y214644D01*
X1452913D01*
G03X1452865Y214514I152J-130D01*
G01Y214250D01*
G03X1452913Y214120I200J0D01*
G01X1452914Y214119D01*
G02X1453284Y213132I-1131J-987D01*
G02X1450280I-1502J0D01*
G02X1450650Y214119I1501J0D01*
G01Y214120D01*
X1450651D01*
G03X1450699Y214250I-152J130D01*
G01Y214514D01*
G03X1450651Y214644I-200J0D01*
G01X1450650Y214645D01*
G02X1450280Y215632I1131J987D01*
G37*
G36*
G01X1552642D02*
G02X1555646I1502J0D01*
G02X1555276Y214645I-1501J0D01*
G01Y214644D01*
X1555275D01*
G03X1555227Y214514I152J-130D01*
G01Y214250D01*
G03X1555275Y214120I200J0D01*
G01X1555276Y214119D01*
G02X1555646Y213132I-1131J-987D01*
G02X1552642I-1502J0D01*
G02X1553012Y214119I1501J0D01*
G01Y214120D01*
X1553013D01*
G03X1553061Y214250I-152J130D01*
G01Y214514D01*
G03X1553013Y214644I-200J0D01*
G01X1553012Y214645D01*
G02X1552642Y215632I1131J987D01*
G37*
G36*
G01X1655004D02*
G02X1658008I1502J0D01*
G02X1657638Y214645I-1501J0D01*
G01Y214644D01*
X1657637D01*
G03X1657589Y214514I152J-130D01*
G01Y214250D01*
G03X1657637Y214120I200J0D01*
G01X1657638Y214119D01*
G02X1658008Y213132I-1131J-987D01*
G02X1655004I-1502J0D01*
G02X1655374Y214119I1501J0D01*
G01Y214120D01*
X1655375D01*
G03X1655423Y214250I-152J130D01*
G01Y214514D01*
G03X1655375Y214644I-200J0D01*
G01X1655374Y214645D01*
G02X1655004Y215632I1131J987D01*
G37*
G36*
G01X1757366D02*
G02X1760370I1502J0D01*
G02X1760000Y214645I-1501J0D01*
G01Y214644D01*
X1759999D01*
G03X1759951Y214514I152J-130D01*
G01Y214250D01*
G03X1759999Y214120I200J0D01*
G01X1760000Y214119D01*
G02X1760370Y213132I-1131J-987D01*
G02X1757366I-1502J0D01*
G02X1757736Y214119I1501J0D01*
G01Y214120D01*
X1757737D01*
G03X1757785Y214250I-152J130D01*
G01Y214514D01*
G03X1757737Y214644I-200J0D01*
G01X1757736Y214645D01*
G02X1757366Y215632I1131J987D01*
G37*
G36*
G01X63687Y215713D02*
G02X66691I1502J0D01*
G02X66321Y214726I-1501J0D01*
G01Y214725D01*
X66320D01*
G03X66272Y214595I152J-130D01*
G01Y214331D01*
G03X66320Y214201I200J0D01*
G01X66321Y214200D01*
G02Y212226I-1131J-987D01*
G01Y212225D01*
X66320D01*
G03X66272Y212095I152J-130D01*
G01Y211831D01*
G03X66320Y211701I200J0D01*
G01X66321Y211700D01*
G02Y209726I-1131J-987D01*
G01Y209725D01*
X66320D01*
G03X66272Y209595I152J-130D01*
G01Y209331D01*
G03X66320Y209201I200J0D01*
G01X66321Y209200D01*
G02X66691Y208213I-1131J-987D01*
G02X63687I-1502J0D01*
G02X64057Y209200I1501J0D01*
G01Y209201D01*
X64058D01*
G03X64106Y209331I-152J130D01*
G01Y209595D01*
G03X64058Y209725I-200J0D01*
G01X64057Y209726D01*
G02Y211700I1131J987D01*
G01Y211701D01*
X64058D01*
G03X64106Y211831I-152J130D01*
G01Y212095D01*
G03X64058Y212225I-200J0D01*
G01X64057Y212226D01*
G02Y214200I1131J987D01*
G01Y214201D01*
X64058D01*
G03X64106Y214331I-152J130D01*
G01Y214595D01*
G03X64058Y214725I-200J0D01*
G01X64057Y214726D01*
G02X63687Y215713I1131J987D01*
G37*
G36*
G01X166049D02*
G02X169053I1502J0D01*
G02X168683Y214726I-1501J0D01*
G01Y214725D01*
X168682D01*
G03X168634Y214595I152J-130D01*
G01Y214331D01*
G03X168682Y214201I200J0D01*
G01X168683Y214200D01*
G02Y212226I-1131J-987D01*
G01Y212225D01*
X168682D01*
G03X168634Y212095I152J-130D01*
G01Y211831D01*
G03X168682Y211701I200J0D01*
G01X168683Y211700D01*
G02Y209726I-1131J-987D01*
G01Y209725D01*
X168682D01*
G03X168634Y209595I152J-130D01*
G01Y209331D01*
G03X168682Y209201I200J0D01*
G01X168683Y209200D01*
G02X169053Y208213I-1131J-987D01*
G02X166049I-1502J0D01*
G02X166419Y209200I1501J0D01*
G01Y209201D01*
X166420D01*
G03X166468Y209331I-152J130D01*
G01Y209595D01*
G03X166420Y209725I-200J0D01*
G01X166419Y209726D01*
G02Y211700I1131J987D01*
G01Y211701D01*
X166420D01*
G03X166468Y211831I-152J130D01*
G01Y212095D01*
G03X166420Y212225I-200J0D01*
G01X166419Y212226D01*
G02Y214200I1131J987D01*
G01Y214201D01*
X166420D01*
G03X166468Y214331I-152J130D01*
G01Y214595D01*
G03X166420Y214725I-200J0D01*
G01X166419Y214726D01*
G02X166049Y215713I1131J987D01*
G37*
G36*
G01X268411D02*
G02X271415I1502J0D01*
G02X271045Y214726I-1501J0D01*
G01Y214725D01*
X271044D01*
G03X270996Y214595I152J-130D01*
G01Y214331D01*
G03X271044Y214201I200J0D01*
G01X271045Y214200D01*
G02Y212226I-1131J-987D01*
G01Y212225D01*
X271044D01*
G03X270996Y212095I152J-130D01*
G01Y211831D01*
G03X271044Y211701I200J0D01*
G01X271045Y211700D01*
G02Y209726I-1131J-987D01*
G01Y209725D01*
X271044D01*
G03X270996Y209595I152J-130D01*
G01Y209331D01*
G03X271044Y209201I200J0D01*
G01X271045Y209200D01*
G02X271415Y208213I-1131J-987D01*
G02X268411I-1502J0D01*
G02X268781Y209200I1501J0D01*
G01Y209201D01*
X268782D01*
G03X268830Y209331I-152J130D01*
G01Y209595D01*
G03X268782Y209725I-200J0D01*
G01X268781Y209726D01*
G02Y211700I1131J987D01*
G01Y211701D01*
X268782D01*
G03X268830Y211831I-152J130D01*
G01Y212095D01*
G03X268782Y212225I-200J0D01*
G01X268781Y212226D01*
G02Y214200I1131J987D01*
G01Y214201D01*
X268782D01*
G03X268830Y214331I-152J130D01*
G01Y214595D01*
G03X268782Y214725I-200J0D01*
G01X268781Y214726D01*
G02X268411Y215713I1131J987D01*
G37*
G36*
G01X370773D02*
G02X373777I1502J0D01*
G02X373407Y214726I-1501J0D01*
G01Y214725D01*
X373406D01*
G03X373358Y214595I152J-130D01*
G01Y214331D01*
G03X373406Y214201I200J0D01*
G01X373407Y214200D01*
G02Y212226I-1131J-987D01*
G01Y212225D01*
X373406D01*
G03X373358Y212095I152J-130D01*
G01Y211831D01*
G03X373406Y211701I200J0D01*
G01X373407Y211700D01*
G02Y209726I-1131J-987D01*
G01Y209725D01*
X373406D01*
G03X373358Y209595I152J-130D01*
G01Y209331D01*
G03X373406Y209201I200J0D01*
G01X373407Y209200D01*
G02X373777Y208213I-1131J-987D01*
G02X370773I-1502J0D01*
G02X371143Y209200I1501J0D01*
G01Y209201D01*
X371144D01*
G03X371192Y209331I-152J130D01*
G01Y209595D01*
G03X371144Y209725I-200J0D01*
G01X371143Y209726D01*
G02Y211700I1131J987D01*
G01Y211701D01*
X371144D01*
G03X371192Y211831I-152J130D01*
G01Y212095D01*
G03X371144Y212225I-200J0D01*
G01X371143Y212226D01*
G02Y214200I1131J987D01*
G01Y214201D01*
X371144D01*
G03X371192Y214331I-152J130D01*
G01Y214595D01*
G03X371144Y214725I-200J0D01*
G01X371143Y214726D01*
G02X370773Y215713I1131J987D01*
G37*
G36*
G01X520774D02*
G02X523778I1502J0D01*
G02X523408Y214726I-1501J0D01*
G01Y214725D01*
X523407D01*
G03X523359Y214595I152J-130D01*
G01Y214331D01*
G03X523407Y214201I200J0D01*
G01X523408Y214200D01*
G02Y212226I-1131J-987D01*
G01Y212225D01*
X523407D01*
G03X523359Y212095I152J-130D01*
G01Y211831D01*
G03X523407Y211701I200J0D01*
G01X523408Y211700D01*
G02Y209726I-1131J-987D01*
G01Y209725D01*
X523407D01*
G03X523359Y209595I152J-130D01*
G01Y209331D01*
G03X523407Y209201I200J0D01*
G01X523408Y209200D01*
G02X523778Y208213I-1131J-987D01*
G02X520774I-1502J0D01*
G02X521144Y209200I1501J0D01*
G01Y209201D01*
X521145D01*
G03X521193Y209331I-152J130D01*
G01Y209595D01*
G03X521145Y209725I-200J0D01*
G01X521144Y209726D01*
G02Y211700I1131J987D01*
G01Y211701D01*
X521145D01*
G03X521193Y211831I-152J130D01*
G01Y212095D01*
G03X521145Y212225I-200J0D01*
G01X521144Y212226D01*
G02Y214200I1131J987D01*
G01Y214201D01*
X521145D01*
G03X521193Y214331I-152J130D01*
G01Y214595D01*
G03X521145Y214725I-200J0D01*
G01X521144Y214726D01*
G02X520774Y215713I1131J987D01*
G37*
G36*
G01X623136D02*
G02X626140I1502J0D01*
G02X625770Y214726I-1501J0D01*
G01Y214725D01*
X625769D01*
G03X625721Y214595I152J-130D01*
G01Y214331D01*
G03X625769Y214201I200J0D01*
G01X625770Y214200D01*
G02Y212226I-1131J-987D01*
G01Y212225D01*
X625769D01*
G03X625721Y212095I152J-130D01*
G01Y211831D01*
G03X625769Y211701I200J0D01*
G01X625770Y211700D01*
G02Y209726I-1131J-987D01*
G01Y209725D01*
X625769D01*
G03X625721Y209595I152J-130D01*
G01Y209331D01*
G03X625769Y209201I200J0D01*
G01X625770Y209200D01*
G02X626140Y208213I-1131J-987D01*
G02X623136I-1502J0D01*
G02X623506Y209200I1501J0D01*
G01Y209201D01*
X623507D01*
G03X623555Y209331I-152J130D01*
G01Y209595D01*
G03X623507Y209725I-200J0D01*
G01X623506Y209726D01*
G02Y211700I1131J987D01*
G01Y211701D01*
X623507D01*
G03X623555Y211831I-152J130D01*
G01Y212095D01*
G03X623507Y212225I-200J0D01*
G01X623506Y212226D01*
G02Y214200I1131J987D01*
G01Y214201D01*
X623507D01*
G03X623555Y214331I-152J130D01*
G01Y214595D01*
G03X623507Y214725I-200J0D01*
G01X623506Y214726D01*
G02X623136Y215713I1131J987D01*
G37*
G36*
G01X725498D02*
G02X728502I1502J0D01*
G02X728132Y214726I-1501J0D01*
G01Y214725D01*
X728131D01*
G03X728083Y214595I152J-130D01*
G01Y214331D01*
G03X728131Y214201I200J0D01*
G01X728132Y214200D01*
G02Y212226I-1131J-987D01*
G01Y212225D01*
X728131D01*
G03X728083Y212095I152J-130D01*
G01Y211831D01*
G03X728131Y211701I200J0D01*
G01X728132Y211700D01*
G02Y209726I-1131J-987D01*
G01Y209725D01*
X728131D01*
G03X728083Y209595I152J-130D01*
G01Y209331D01*
G03X728131Y209201I200J0D01*
G01X728132Y209200D01*
G02X728502Y208213I-1131J-987D01*
G02X725498I-1502J0D01*
G02X725868Y209200I1501J0D01*
G01Y209201D01*
X725869D01*
G03X725917Y209331I-152J130D01*
G01Y209595D01*
G03X725869Y209725I-200J0D01*
G01X725868Y209726D01*
G02Y211700I1131J987D01*
G01Y211701D01*
X725869D01*
G03X725917Y211831I-152J130D01*
G01Y212095D01*
G03X725869Y212225I-200J0D01*
G01X725868Y212226D01*
G02Y214200I1131J987D01*
G01Y214201D01*
X725869D01*
G03X725917Y214331I-152J130D01*
G01Y214595D01*
G03X725869Y214725I-200J0D01*
G01X725868Y214726D01*
G02X725498Y215713I1131J987D01*
G37*
G36*
G01X827860D02*
G02X830864I1502J0D01*
G02X830494Y214726I-1501J0D01*
G01Y214725D01*
X830493D01*
G03X830445Y214595I152J-130D01*
G01Y214331D01*
G03X830493Y214201I200J0D01*
G01X830494Y214200D01*
G02Y212226I-1131J-987D01*
G01Y212225D01*
X830493D01*
G03X830445Y212095I152J-130D01*
G01Y211831D01*
G03X830493Y211701I200J0D01*
G01X830494Y211700D01*
G02Y209726I-1131J-987D01*
G01Y209725D01*
X830493D01*
G03X830445Y209595I152J-130D01*
G01Y209331D01*
G03X830493Y209201I200J0D01*
G01X830494Y209200D01*
G02X830864Y208213I-1131J-987D01*
G02X827860I-1502J0D01*
G02X828230Y209200I1501J0D01*
G01Y209201D01*
X828231D01*
G03X828279Y209331I-152J130D01*
G01Y209595D01*
G03X828231Y209725I-200J0D01*
G01X828230Y209726D01*
G02Y211700I1131J987D01*
G01Y211701D01*
X828231D01*
G03X828279Y211831I-152J130D01*
G01Y212095D01*
G03X828231Y212225I-200J0D01*
G01X828230Y212226D01*
G02Y214200I1131J987D01*
G01Y214201D01*
X828231D01*
G03X828279Y214331I-152J130D01*
G01Y214595D01*
G03X828231Y214725I-200J0D01*
G01X828230Y214726D01*
G02X827860Y215713I1131J987D01*
G37*
G36*
G01X977860D02*
G02X980864I1502J0D01*
G02X980494Y214726I-1501J0D01*
G01Y214725D01*
X980493D01*
G03X980445Y214595I152J-130D01*
G01Y214331D01*
G03X980493Y214201I200J0D01*
G01X980494Y214200D01*
G02Y212226I-1131J-987D01*
G01Y212225D01*
X980493D01*
G03X980445Y212095I152J-130D01*
G01Y211831D01*
G03X980493Y211701I200J0D01*
G01X980494Y211700D01*
G02Y209726I-1131J-987D01*
G01Y209725D01*
X980493D01*
G03X980445Y209595I152J-130D01*
G01Y209331D01*
G03X980493Y209201I200J0D01*
G01X980494Y209200D01*
G02X980864Y208213I-1131J-987D01*
G02X977860I-1502J0D01*
G02X978230Y209200I1501J0D01*
G01Y209201D01*
X978231D01*
G03X978279Y209331I-152J130D01*
G01Y209595D01*
G03X978231Y209725I-200J0D01*
G01X978230Y209726D01*
G02Y211700I1131J987D01*
G01Y211701D01*
X978231D01*
G03X978279Y211831I-152J130D01*
G01Y212095D01*
G03X978231Y212225I-200J0D01*
G01X978230Y212226D01*
G02Y214200I1131J987D01*
G01Y214201D01*
X978231D01*
G03X978279Y214331I-152J130D01*
G01Y214595D01*
G03X978231Y214725I-200J0D01*
G01X978230Y214726D01*
G02X977860Y215713I1131J987D01*
G37*
G36*
G01X1080222D02*
G02X1083226I1502J0D01*
G02X1082856Y214726I-1501J0D01*
G01Y214725D01*
X1082855D01*
G03X1082807Y214595I152J-130D01*
G01Y214331D01*
G03X1082855Y214201I200J0D01*
G01X1082856Y214200D01*
G02Y212226I-1131J-987D01*
G01Y212225D01*
X1082855D01*
G03X1082807Y212095I152J-130D01*
G01Y211831D01*
G03X1082855Y211701I200J0D01*
G01X1082856Y211700D01*
G02Y209726I-1131J-987D01*
G01Y209725D01*
X1082855D01*
G03X1082807Y209595I152J-130D01*
G01Y209331D01*
G03X1082855Y209201I200J0D01*
G01X1082856Y209200D01*
G02X1083226Y208213I-1131J-987D01*
G02X1080222I-1502J0D01*
G02X1080592Y209200I1501J0D01*
G01Y209201D01*
X1080593D01*
G03X1080641Y209331I-152J130D01*
G01Y209595D01*
G03X1080593Y209725I-200J0D01*
G01X1080592Y209726D01*
G02Y211700I1131J987D01*
G01Y211701D01*
X1080593D01*
G03X1080641Y211831I-152J130D01*
G01Y212095D01*
G03X1080593Y212225I-200J0D01*
G01X1080592Y212226D01*
G02Y214200I1131J987D01*
G01Y214201D01*
X1080593D01*
G03X1080641Y214331I-152J130D01*
G01Y214595D01*
G03X1080593Y214725I-200J0D01*
G01X1080592Y214726D01*
G02X1080222Y215713I1131J987D01*
G37*
G36*
G01X1182584D02*
G02X1185588I1502J0D01*
G02X1185218Y214726I-1501J0D01*
G01Y214725D01*
X1185217D01*
G03X1185169Y214595I152J-130D01*
G01Y214331D01*
G03X1185217Y214201I200J0D01*
G01X1185218Y214200D01*
G02Y212226I-1131J-987D01*
G01Y212225D01*
X1185217D01*
G03X1185169Y212095I152J-130D01*
G01Y211831D01*
G03X1185217Y211701I200J0D01*
G01X1185218Y211700D01*
G02Y209726I-1131J-987D01*
G01Y209725D01*
X1185217D01*
G03X1185169Y209595I152J-130D01*
G01Y209331D01*
G03X1185217Y209201I200J0D01*
G01X1185218Y209200D01*
G02X1185588Y208213I-1131J-987D01*
G02X1182584I-1502J0D01*
G02X1182954Y209200I1501J0D01*
G01Y209201D01*
X1182955D01*
G03X1183003Y209331I-152J130D01*
G01Y209595D01*
G03X1182955Y209725I-200J0D01*
G01X1182954Y209726D01*
G02Y211700I1131J987D01*
G01Y211701D01*
X1182955D01*
G03X1183003Y211831I-152J130D01*
G01Y212095D01*
G03X1182955Y212225I-200J0D01*
G01X1182954Y212226D01*
G02Y214200I1131J987D01*
G01Y214201D01*
X1182955D01*
G03X1183003Y214331I-152J130D01*
G01Y214595D01*
G03X1182955Y214725I-200J0D01*
G01X1182954Y214726D01*
G02X1182584Y215713I1131J987D01*
G37*
G36*
G01X1284946D02*
G02X1287950I1502J0D01*
G02X1287580Y214726I-1501J0D01*
G01Y214725D01*
X1287579D01*
G03X1287531Y214595I152J-130D01*
G01Y214331D01*
G03X1287579Y214201I200J0D01*
G01X1287580Y214200D01*
G02Y212226I-1131J-987D01*
G01Y212225D01*
X1287579D01*
G03X1287531Y212095I152J-130D01*
G01Y211831D01*
G03X1287579Y211701I200J0D01*
G01X1287580Y211700D01*
G02Y209726I-1131J-987D01*
G01Y209725D01*
X1287579D01*
G03X1287531Y209595I152J-130D01*
G01Y209331D01*
G03X1287579Y209201I200J0D01*
G01X1287580Y209200D01*
G02X1287950Y208213I-1131J-987D01*
G02X1284946I-1502J0D01*
G02X1285316Y209200I1501J0D01*
G01Y209201D01*
X1285317D01*
G03X1285365Y209331I-152J130D01*
G01Y209595D01*
G03X1285317Y209725I-200J0D01*
G01X1285316Y209726D01*
G02Y211700I1131J987D01*
G01Y211701D01*
X1285317D01*
G03X1285365Y211831I-152J130D01*
G01Y212095D01*
G03X1285317Y212225I-200J0D01*
G01X1285316Y212226D01*
G02Y214200I1131J987D01*
G01Y214201D01*
X1285317D01*
G03X1285365Y214331I-152J130D01*
G01Y214595D01*
G03X1285317Y214725I-200J0D01*
G01X1285316Y214726D01*
G02X1284946Y215713I1131J987D01*
G37*
G36*
G01X1434947D02*
G02X1437951I1502J0D01*
G02X1437581Y214726I-1501J0D01*
G01Y214725D01*
X1437580D01*
G03X1437532Y214595I152J-130D01*
G01Y214331D01*
G03X1437580Y214201I200J0D01*
G01X1437581Y214200D01*
G02Y212226I-1131J-987D01*
G01Y212225D01*
X1437580D01*
G03X1437532Y212095I152J-130D01*
G01Y211831D01*
G03X1437580Y211701I200J0D01*
G01X1437581Y211700D01*
G02Y209726I-1131J-987D01*
G01Y209725D01*
X1437580D01*
G03X1437532Y209595I152J-130D01*
G01Y209331D01*
G03X1437580Y209201I200J0D01*
G01X1437581Y209200D01*
G02X1437951Y208213I-1131J-987D01*
G02X1434947I-1502J0D01*
G02X1435317Y209200I1501J0D01*
G01Y209201D01*
X1435318D01*
G03X1435366Y209331I-152J130D01*
G01Y209595D01*
G03X1435318Y209725I-200J0D01*
G01X1435317Y209726D01*
G02Y211700I1131J987D01*
G01Y211701D01*
X1435318D01*
G03X1435366Y211831I-152J130D01*
G01Y212095D01*
G03X1435318Y212225I-200J0D01*
G01X1435317Y212226D01*
G02Y214200I1131J987D01*
G01Y214201D01*
X1435318D01*
G03X1435366Y214331I-152J130D01*
G01Y214595D01*
G03X1435318Y214725I-200J0D01*
G01X1435317Y214726D01*
G02X1434947Y215713I1131J987D01*
G37*
G36*
G01X1537309D02*
G02X1540313I1502J0D01*
G02X1539943Y214726I-1501J0D01*
G01Y214725D01*
X1539942D01*
G03X1539894Y214595I152J-130D01*
G01Y214331D01*
G03X1539942Y214201I200J0D01*
G01X1539943Y214200D01*
G02Y212226I-1131J-987D01*
G01Y212225D01*
X1539942D01*
G03X1539894Y212095I152J-130D01*
G01Y211831D01*
G03X1539942Y211701I200J0D01*
G01X1539943Y211700D01*
G02Y209726I-1131J-987D01*
G01Y209725D01*
X1539942D01*
G03X1539894Y209595I152J-130D01*
G01Y209331D01*
G03X1539942Y209201I200J0D01*
G01X1539943Y209200D01*
G02X1540313Y208213I-1131J-987D01*
G02X1537309I-1502J0D01*
G02X1537679Y209200I1501J0D01*
G01Y209201D01*
X1537680D01*
G03X1537728Y209331I-152J130D01*
G01Y209595D01*
G03X1537680Y209725I-200J0D01*
G01X1537679Y209726D01*
G02Y211700I1131J987D01*
G01Y211701D01*
X1537680D01*
G03X1537728Y211831I-152J130D01*
G01Y212095D01*
G03X1537680Y212225I-200J0D01*
G01X1537679Y212226D01*
G02Y214200I1131J987D01*
G01Y214201D01*
X1537680D01*
G03X1537728Y214331I-152J130D01*
G01Y214595D01*
G03X1537680Y214725I-200J0D01*
G01X1537679Y214726D01*
G02X1537309Y215713I1131J987D01*
G37*
G36*
G01X1639671D02*
G02X1642675I1502J0D01*
G02X1642305Y214726I-1501J0D01*
G01Y214725D01*
X1642304D01*
G03X1642256Y214595I152J-130D01*
G01Y214331D01*
G03X1642304Y214201I200J0D01*
G01X1642305Y214200D01*
G02Y212226I-1131J-987D01*
G01Y212225D01*
X1642304D01*
G03X1642256Y212095I152J-130D01*
G01Y211831D01*
G03X1642304Y211701I200J0D01*
G01X1642305Y211700D01*
G02Y209726I-1131J-987D01*
G01Y209725D01*
X1642304D01*
G03X1642256Y209595I152J-130D01*
G01Y209331D01*
G03X1642304Y209201I200J0D01*
G01X1642305Y209200D01*
G02X1642675Y208213I-1131J-987D01*
G02X1639671I-1502J0D01*
G02X1640041Y209200I1501J0D01*
G01Y209201D01*
X1640042D01*
G03X1640090Y209331I-152J130D01*
G01Y209595D01*
G03X1640042Y209725I-200J0D01*
G01X1640041Y209726D01*
G02Y211700I1131J987D01*
G01Y211701D01*
X1640042D01*
G03X1640090Y211831I-152J130D01*
G01Y212095D01*
G03X1640042Y212225I-200J0D01*
G01X1640041Y212226D01*
G02Y214200I1131J987D01*
G01Y214201D01*
X1640042D01*
G03X1640090Y214331I-152J130D01*
G01Y214595D01*
G03X1640042Y214725I-200J0D01*
G01X1640041Y214726D01*
G02X1639671Y215713I1131J987D01*
G37*
G36*
G01X1742033D02*
G02X1745037I1502J0D01*
G02X1744667Y214726I-1501J0D01*
G01Y214725D01*
X1744666D01*
G03X1744618Y214595I152J-130D01*
G01Y214331D01*
G03X1744666Y214201I200J0D01*
G01X1744667Y214200D01*
G02Y212226I-1131J-987D01*
G01Y212225D01*
X1744666D01*
G03X1744618Y212095I152J-130D01*
G01Y211831D01*
G03X1744666Y211701I200J0D01*
G01X1744667Y211700D01*
G02Y209726I-1131J-987D01*
G01Y209725D01*
X1744666D01*
G03X1744618Y209595I152J-130D01*
G01Y209331D01*
G03X1744666Y209201I200J0D01*
G01X1744667Y209200D01*
G02X1745037Y208213I-1131J-987D01*
G02X1742033I-1502J0D01*
G02X1742403Y209200I1501J0D01*
G01Y209201D01*
X1742404D01*
G03X1742452Y209331I-152J130D01*
G01Y209595D01*
G03X1742404Y209725I-200J0D01*
G01X1742403Y209726D01*
G02Y211700I1131J987D01*
G01Y211701D01*
X1742404D01*
G03X1742452Y211831I-152J130D01*
G01Y212095D01*
G03X1742404Y212225I-200J0D01*
G01X1742403Y212226D01*
G02Y214200I1131J987D01*
G01Y214201D01*
X1742404D01*
G03X1742452Y214331I-152J130D01*
G01Y214595D01*
G03X1742404Y214725I-200J0D01*
G01X1742403Y214726D01*
G02X1742033Y215713I1131J987D01*
G37*
G36*
G01X11806Y217133D02*
X11512D01*
G03X11365Y217068I1J-200D01*
G02X10259Y216583I-1106J1019D01*
G02Y219587I0J1502D01*
G02X11365Y219102I0J-1504D01*
G03X11512Y219037I148J135D01*
G01X11806D01*
G03X11953Y219102I-1J200D01*
G02X13059Y219587I1106J-1019D01*
G02Y216583I0J-1502D01*
G02X11953Y217068I0J1504D01*
G03X11806Y217133I-148J-135D01*
G37*
G36*
G01X114168D02*
X113874D01*
G03X113727Y217068I1J-200D01*
G02X112621Y216583I-1106J1019D01*
G02Y219587I0J1502D01*
G02X113727Y219102I0J-1504D01*
G03X113874Y219037I148J135D01*
G01X114168D01*
G03X114315Y219102I-1J200D01*
G02X115421Y219587I1106J-1019D01*
G02Y216583I0J-1502D01*
G02X114315Y217068I0J1504D01*
G03X114168Y217133I-148J-135D01*
G37*
G36*
G01X216530D02*
X216236D01*
G03X216089Y217068I1J-200D01*
G02X214983Y216583I-1106J1019D01*
G02Y219587I0J1502D01*
G02X216089Y219102I0J-1504D01*
G03X216236Y219037I148J135D01*
G01X216530D01*
G03X216677Y219102I-1J200D01*
G02X217783Y219587I1106J-1019D01*
G02Y216583I0J-1502D01*
G02X216677Y217068I0J1504D01*
G03X216530Y217133I-148J-135D01*
G37*
G36*
G01X318892D02*
X318598D01*
G03X318451Y217068I1J-200D01*
G02X317345Y216583I-1106J1019D01*
G02Y219587I0J1502D01*
G02X318451Y219102I0J-1504D01*
G03X318598Y219037I148J135D01*
G01X318892D01*
G03X319039Y219102I-1J200D01*
G02X320145Y219587I1106J-1019D01*
G02Y216583I0J-1502D01*
G02X319039Y217068I0J1504D01*
G03X318892Y217133I-148J-135D01*
G37*
G36*
G01X468893D02*
X468599D01*
G03X468452Y217068I1J-200D01*
G02X467346Y216583I-1106J1019D01*
G02Y219587I0J1502D01*
G02X468452Y219102I0J-1504D01*
G03X468599Y219037I148J135D01*
G01X468893D01*
G03X469040Y219102I-1J200D01*
G02X470146Y219587I1106J-1019D01*
G02Y216583I0J-1502D01*
G02X469040Y217068I0J1504D01*
G03X468893Y217133I-148J-135D01*
G37*
G36*
G01X571255D02*
X570961D01*
G03X570814Y217068I1J-200D01*
G02X569708Y216583I-1106J1019D01*
G02Y219587I0J1502D01*
G02X570814Y219102I0J-1504D01*
G03X570961Y219037I148J135D01*
G01X571255D01*
G03X571402Y219102I-1J200D01*
G02X572508Y219587I1106J-1019D01*
G02Y216583I0J-1502D01*
G02X571402Y217068I0J1504D01*
G03X571255Y217133I-148J-135D01*
G37*
G36*
G01X673617D02*
X673323D01*
G03X673176Y217068I1J-200D01*
G02X672070Y216583I-1106J1019D01*
G02Y219587I0J1502D01*
G02X673176Y219102I0J-1504D01*
G03X673323Y219037I148J135D01*
G01X673617D01*
G03X673764Y219102I-1J200D01*
G02X674870Y219587I1106J-1019D01*
G02Y216583I0J-1502D01*
G02X673764Y217068I0J1504D01*
G03X673617Y217133I-148J-135D01*
G37*
G36*
G01X775979D02*
X775685D01*
G03X775538Y217068I1J-200D01*
G02X774432Y216583I-1106J1019D01*
G02Y219587I0J1502D01*
G02X775538Y219102I0J-1504D01*
G03X775685Y219037I148J135D01*
G01X775979D01*
G03X776126Y219102I-1J200D01*
G02X777232Y219587I1106J-1019D01*
G02Y216583I0J-1502D01*
G02X776126Y217068I0J1504D01*
G03X775979Y217133I-148J-135D01*
G37*
G36*
G01X1028341D02*
X1028047D01*
G03X1027900Y217068I1J-200D01*
G02X1026794Y216583I-1106J1019D01*
G02Y219587I0J1502D01*
G02X1027900Y219102I0J-1504D01*
G03X1028047Y219037I148J135D01*
G01X1028341D01*
G03X1028488Y219102I-1J200D01*
G02X1029594Y219587I1106J-1019D01*
G02Y216583I0J-1502D01*
G02X1028488Y217068I0J1504D01*
G03X1028341Y217133I-148J-135D01*
G37*
G36*
G01X1130703D02*
X1130409D01*
G03X1130262Y217068I1J-200D01*
G02X1129156Y216583I-1106J1019D01*
G02Y219587I0J1502D01*
G02X1130262Y219102I0J-1504D01*
G03X1130409Y219037I148J135D01*
G01X1130703D01*
G03X1130850Y219102I-1J200D01*
G02X1131956Y219587I1106J-1019D01*
G02Y216583I0J-1502D01*
G02X1130850Y217068I0J1504D01*
G03X1130703Y217133I-148J-135D01*
G37*
G36*
G01X1233065D02*
X1232771D01*
G03X1232624Y217068I1J-200D01*
G02X1231518Y216583I-1106J1019D01*
G02Y219587I0J1502D01*
G02X1232624Y219102I0J-1504D01*
G03X1232771Y219037I148J135D01*
G01X1233065D01*
G03X1233212Y219102I-1J200D01*
G02X1234318Y219587I1106J-1019D01*
G02Y216583I0J-1502D01*
G02X1233212Y217068I0J1504D01*
G03X1233065Y217133I-148J-135D01*
G37*
G36*
G01X1383066D02*
X1382772D01*
G03X1382625Y217068I1J-200D01*
G02X1381519Y216583I-1106J1019D01*
G02Y219587I0J1502D01*
G02X1382625Y219102I0J-1504D01*
G03X1382772Y219037I148J135D01*
G01X1383066D01*
G03X1383213Y219102I-1J200D01*
G02X1384319Y219587I1106J-1019D01*
G02Y216583I0J-1502D01*
G02X1383213Y217068I0J1504D01*
G03X1383066Y217133I-148J-135D01*
G37*
G36*
G01X1485428D02*
X1485134D01*
G03X1484987Y217068I1J-200D01*
G02X1483881Y216583I-1106J1019D01*
G02Y219587I0J1502D01*
G02X1484987Y219102I0J-1504D01*
G03X1485134Y219037I148J135D01*
G01X1485428D01*
G03X1485575Y219102I-1J200D01*
G02X1486681Y219587I1106J-1019D01*
G02Y216583I0J-1502D01*
G02X1485575Y217068I0J1504D01*
G03X1485428Y217133I-148J-135D01*
G37*
G36*
G01X1587790D02*
X1587496D01*
G03X1587349Y217068I1J-200D01*
G02X1586243Y216583I-1106J1019D01*
G02Y219587I0J1502D01*
G02X1587349Y219102I0J-1504D01*
G03X1587496Y219037I148J135D01*
G01X1587790D01*
G03X1587937Y219102I-1J200D01*
G02X1589043Y219587I1106J-1019D01*
G02Y216583I0J-1502D01*
G02X1587937Y217068I0J1504D01*
G03X1587790Y217133I-148J-135D01*
G37*
G36*
G01X1690152D02*
X1689858D01*
G03X1689711Y217068I1J-200D01*
G02X1688605Y216583I-1106J1019D01*
G02Y219587I0J1502D01*
G02X1689711Y219102I0J-1504D01*
G03X1689858Y219037I148J135D01*
G01X1690152D01*
G03X1690299Y219102I-1J200D01*
G02X1691405Y219587I1106J-1019D01*
G02Y216583I0J-1502D01*
G02X1690299Y217068I0J1504D01*
G03X1690152Y217133I-148J-135D01*
G37*
G36*
G01X18070Y221970D02*
G02X21074I1502J0D01*
G02X20704Y220983I-1501J0D01*
G01Y220982D01*
X20703D01*
G03X20655Y220852I152J-130D01*
G01Y220588D01*
G03X20703Y220458I200J0D01*
G01X20704Y220457D01*
G02Y218483I-1131J-987D01*
G01Y218482D01*
X20703D01*
G03X20655Y218352I152J-130D01*
G01Y218088D01*
G03X20703Y217958I200J0D01*
G01X20704Y217957D01*
G02X21074Y216970I-1131J-987D01*
G02X19572Y215468I-1502J0D01*
G02X18717Y215735I0J1502D01*
G01X18683Y215758D01*
X18602Y215775D01*
X18235Y215695D01*
X18168Y215647D01*
X18147Y215612D01*
G02X16859Y214883I-1288J773D01*
G02Y217887I0J1502D01*
G02X17714Y217620I0J-1502D01*
G01X17748Y217597D01*
X17829Y217580D01*
X18196Y217660D01*
X18263Y217708D01*
X18284Y217743D01*
G02X18440Y217956I1285J-777D01*
G03X18441Y217958I-173J88D01*
G03X18489Y218088I-152J130D01*
G01Y218352D01*
G03X18441Y218482I-200J0D01*
G01X18440Y218483D01*
G02Y220457I1131J987D01*
G01Y220458D01*
X18441D01*
G03X18489Y220588I-152J130D01*
G01Y220852D01*
G03X18441Y220982I-200J0D01*
G01X18440Y220983D01*
G02X18070Y221970I1131J987D01*
G37*
G36*
G01X120432D02*
G02X123436I1502J0D01*
G02X123066Y220983I-1501J0D01*
G01Y220982D01*
X123065D01*
G03X123017Y220852I152J-130D01*
G01Y220588D01*
G03X123065Y220458I200J0D01*
G01X123066Y220457D01*
G02Y218483I-1131J-987D01*
G01Y218482D01*
X123065D01*
G03X123017Y218352I152J-130D01*
G01Y218088D01*
G03X123065Y217958I200J0D01*
G01X123066Y217957D01*
G02X123436Y216970I-1131J-987D01*
G02X121934Y215468I-1502J0D01*
G02X121079Y215735I0J1502D01*
G01X121045Y215758D01*
X120964Y215775D01*
X120597Y215695D01*
X120530Y215647D01*
X120509Y215612D01*
G02X119221Y214883I-1288J773D01*
G02Y217887I0J1502D01*
G02X120076Y217620I0J-1502D01*
G01X120110Y217597D01*
X120191Y217580D01*
X120558Y217660D01*
X120625Y217708D01*
X120646Y217743D01*
G02X120802Y217956I1285J-777D01*
G03X120803Y217958I-173J88D01*
G03X120851Y218088I-152J130D01*
G01Y218352D01*
G03X120803Y218482I-200J0D01*
G01X120802Y218483D01*
G02Y220457I1131J987D01*
G01Y220458D01*
X120803D01*
G03X120851Y220588I-152J130D01*
G01Y220852D01*
G03X120803Y220982I-200J0D01*
G01X120802Y220983D01*
G02X120432Y221970I1131J987D01*
G37*
G36*
G01X222794D02*
G02X225798I1502J0D01*
G02X225428Y220983I-1501J0D01*
G01Y220982D01*
X225427D01*
G03X225379Y220852I152J-130D01*
G01Y220588D01*
G03X225427Y220458I200J0D01*
G01X225428Y220457D01*
G02Y218483I-1131J-987D01*
G01Y218482D01*
X225427D01*
G03X225379Y218352I152J-130D01*
G01Y218088D01*
G03X225427Y217958I200J0D01*
G01X225428Y217957D01*
G02X225798Y216970I-1131J-987D01*
G02X224296Y215468I-1502J0D01*
G02X223441Y215735I0J1502D01*
G01X223407Y215758D01*
X223326Y215775D01*
X222959Y215695D01*
X222892Y215647D01*
X222871Y215612D01*
G02X221583Y214883I-1288J773D01*
G02Y217887I0J1502D01*
G02X222438Y217620I0J-1502D01*
G01X222472Y217597D01*
X222553Y217580D01*
X222920Y217660D01*
X222987Y217708D01*
X223008Y217743D01*
G02X223164Y217956I1285J-777D01*
G03X223165Y217958I-173J88D01*
G03X223213Y218088I-152J130D01*
G01Y218352D01*
G03X223165Y218482I-200J0D01*
G01X223164Y218483D01*
G02Y220457I1131J987D01*
G01Y220458D01*
X223165D01*
G03X223213Y220588I-152J130D01*
G01Y220852D01*
G03X223165Y220982I-200J0D01*
G01X223164Y220983D01*
G02X222794Y221970I1131J987D01*
G37*
G36*
G01X325156D02*
G02X328160I1502J0D01*
G02X327790Y220983I-1501J0D01*
G01Y220982D01*
X327789D01*
G03X327741Y220852I152J-130D01*
G01Y220588D01*
G03X327789Y220458I200J0D01*
G01X327790Y220457D01*
G02Y218483I-1131J-987D01*
G01Y218482D01*
X327789D01*
G03X327741Y218352I152J-130D01*
G01Y218088D01*
G03X327789Y217958I200J0D01*
G01X327790Y217957D01*
G02X328160Y216970I-1131J-987D01*
G02X326658Y215468I-1502J0D01*
G02X325803Y215735I0J1502D01*
G01X325769Y215758D01*
X325688Y215775D01*
X325321Y215695D01*
X325254Y215647D01*
X325233Y215612D01*
G02X323945Y214883I-1288J773D01*
G02Y217887I0J1502D01*
G02X324800Y217620I0J-1502D01*
G01X324834Y217597D01*
X324915Y217580D01*
X325282Y217660D01*
X325349Y217708D01*
X325370Y217743D01*
G02X325526Y217956I1285J-777D01*
G03X325527Y217958I-173J88D01*
G03X325575Y218088I-152J130D01*
G01Y218352D01*
G03X325527Y218482I-200J0D01*
G01X325526Y218483D01*
G02Y220457I1131J987D01*
G01Y220458D01*
X325527D01*
G03X325575Y220588I-152J130D01*
G01Y220852D01*
G03X325527Y220982I-200J0D01*
G01X325526Y220983D01*
G02X325156Y221970I1131J987D01*
G37*
G36*
G01X475157D02*
G02X478161I1502J0D01*
G02X477791Y220983I-1501J0D01*
G01Y220982D01*
X477790D01*
G03X477742Y220852I152J-130D01*
G01Y220588D01*
G03X477790Y220458I200J0D01*
G01X477791Y220457D01*
G02Y218483I-1131J-987D01*
G01Y218482D01*
X477790D01*
G03X477742Y218352I152J-130D01*
G01Y218088D01*
G03X477790Y217958I200J0D01*
G01X477791Y217957D01*
G02X478161Y216970I-1131J-987D01*
G02X476659Y215468I-1502J0D01*
G02X475804Y215735I0J1502D01*
G01X475770Y215758D01*
X475689Y215775D01*
X475322Y215695D01*
X475255Y215647D01*
X475234Y215612D01*
G02X473946Y214883I-1288J773D01*
G02Y217887I0J1502D01*
G02X474801Y217620I0J-1502D01*
G01X474835Y217597D01*
X474916Y217580D01*
X475283Y217660D01*
X475350Y217708D01*
X475371Y217743D01*
G02X475527Y217956I1285J-777D01*
G03X475528Y217958I-173J88D01*
G03X475576Y218088I-152J130D01*
G01Y218352D01*
G03X475528Y218482I-200J0D01*
G01X475527Y218483D01*
G02Y220457I1131J987D01*
G01Y220458D01*
X475528D01*
G03X475576Y220588I-152J130D01*
G01Y220852D01*
G03X475528Y220982I-200J0D01*
G01X475527Y220983D01*
G02X475157Y221970I1131J987D01*
G37*
G36*
G01X577519D02*
G02X580523I1502J0D01*
G02X580153Y220983I-1501J0D01*
G01Y220982D01*
X580152D01*
G03X580104Y220852I152J-130D01*
G01Y220588D01*
G03X580152Y220458I200J0D01*
G01X580153Y220457D01*
G02Y218483I-1131J-987D01*
G01Y218482D01*
X580152D01*
G03X580104Y218352I152J-130D01*
G01Y218088D01*
G03X580152Y217958I200J0D01*
G01X580153Y217957D01*
G02X580523Y216970I-1131J-987D01*
G02X579021Y215468I-1502J0D01*
G02X578166Y215735I0J1502D01*
G01X578132Y215758D01*
X578051Y215775D01*
X577684Y215695D01*
X577617Y215647D01*
X577596Y215612D01*
G02X576308Y214883I-1288J773D01*
G02Y217887I0J1502D01*
G02X577163Y217620I0J-1502D01*
G01X577197Y217597D01*
X577278Y217580D01*
X577645Y217660D01*
X577712Y217708D01*
X577733Y217743D01*
G02X577889Y217956I1285J-777D01*
G03X577890Y217958I-173J88D01*
G03X577938Y218088I-152J130D01*
G01Y218352D01*
G03X577890Y218482I-200J0D01*
G01X577889Y218483D01*
G02Y220457I1131J987D01*
G01Y220458D01*
X577890D01*
G03X577938Y220588I-152J130D01*
G01Y220852D01*
G03X577890Y220982I-200J0D01*
G01X577889Y220983D01*
G02X577519Y221970I1131J987D01*
G37*
G36*
G01X679881D02*
G02X682885I1502J0D01*
G02X682515Y220983I-1501J0D01*
G01Y220982D01*
X682514D01*
G03X682466Y220852I152J-130D01*
G01Y220588D01*
G03X682514Y220458I200J0D01*
G01X682515Y220457D01*
G02Y218483I-1131J-987D01*
G01Y218482D01*
X682514D01*
G03X682466Y218352I152J-130D01*
G01Y218088D01*
G03X682514Y217958I200J0D01*
G01X682515Y217957D01*
G02X682885Y216970I-1131J-987D01*
G02X681383Y215468I-1502J0D01*
G02X680528Y215735I0J1502D01*
G01X680494Y215758D01*
X680413Y215775D01*
X680046Y215695D01*
X679979Y215647D01*
X679958Y215612D01*
G02X678670Y214883I-1288J773D01*
G02Y217887I0J1502D01*
G02X679525Y217620I0J-1502D01*
G01X679559Y217597D01*
X679640Y217580D01*
X680007Y217660D01*
X680074Y217708D01*
X680095Y217743D01*
G02X680251Y217956I1285J-777D01*
G03X680252Y217958I-173J88D01*
G03X680300Y218088I-152J130D01*
G01Y218352D01*
G03X680252Y218482I-200J0D01*
G01X680251Y218483D01*
G02Y220457I1131J987D01*
G01Y220458D01*
X680252D01*
G03X680300Y220588I-152J130D01*
G01Y220852D01*
G03X680252Y220982I-200J0D01*
G01X680251Y220983D01*
G02X679881Y221970I1131J987D01*
G37*
G36*
G01X782243D02*
G02X785247I1502J0D01*
G02X784877Y220983I-1501J0D01*
G01Y220982D01*
X784876D01*
G03X784828Y220852I152J-130D01*
G01Y220588D01*
G03X784876Y220458I200J0D01*
G01X784877Y220457D01*
G02Y218483I-1131J-987D01*
G01Y218482D01*
X784876D01*
G03X784828Y218352I152J-130D01*
G01Y218088D01*
G03X784876Y217958I200J0D01*
G01X784877Y217957D01*
G02X785247Y216970I-1131J-987D01*
G02X783745Y215468I-1502J0D01*
G02X782890Y215735I0J1502D01*
G01X782856Y215758D01*
X782775Y215775D01*
X782408Y215695D01*
X782341Y215647D01*
X782320Y215612D01*
G02X781032Y214883I-1288J773D01*
G02Y217887I0J1502D01*
G02X781887Y217620I0J-1502D01*
G01X781921Y217597D01*
X782002Y217580D01*
X782369Y217660D01*
X782436Y217708D01*
X782457Y217743D01*
G02X782613Y217956I1285J-777D01*
G03X782614Y217958I-173J88D01*
G03X782662Y218088I-152J130D01*
G01Y218352D01*
G03X782614Y218482I-200J0D01*
G01X782613Y218483D01*
G02Y220457I1131J987D01*
G01Y220458D01*
X782614D01*
G03X782662Y220588I-152J130D01*
G01Y220852D01*
G03X782614Y220982I-200J0D01*
G01X782613Y220983D01*
G02X782243Y221970I1131J987D01*
G37*
G36*
G01X1034605D02*
G02X1037609I1502J0D01*
G02X1037239Y220983I-1501J0D01*
G01Y220982D01*
X1037238D01*
G03X1037190Y220852I152J-130D01*
G01Y220588D01*
G03X1037238Y220458I200J0D01*
G01X1037239Y220457D01*
G02Y218483I-1131J-987D01*
G01Y218482D01*
X1037238D01*
G03X1037190Y218352I152J-130D01*
G01Y218088D01*
G03X1037238Y217958I200J0D01*
G01X1037239Y217957D01*
G02X1037609Y216970I-1131J-987D01*
G02X1036107Y215468I-1502J0D01*
G02X1035252Y215735I0J1502D01*
G01X1035218Y215758D01*
X1035137Y215775D01*
X1034770Y215695D01*
X1034703Y215647D01*
X1034682Y215612D01*
G02X1033394Y214883I-1288J773D01*
G02Y217887I0J1502D01*
G02X1034249Y217620I0J-1502D01*
G01X1034283Y217597D01*
X1034364Y217580D01*
X1034731Y217660D01*
X1034798Y217708D01*
X1034819Y217743D01*
G02X1034975Y217956I1285J-777D01*
G03X1034976Y217958I-173J88D01*
G03X1035024Y218088I-152J130D01*
G01Y218352D01*
G03X1034976Y218482I-200J0D01*
G01X1034975Y218483D01*
G02Y220457I1131J987D01*
G01Y220458D01*
X1034976D01*
G03X1035024Y220588I-152J130D01*
G01Y220852D01*
G03X1034976Y220982I-200J0D01*
G01X1034975Y220983D01*
G02X1034605Y221970I1131J987D01*
G37*
G36*
G01X1136967D02*
G02X1139971I1502J0D01*
G02X1139601Y220983I-1501J0D01*
G01Y220982D01*
X1139600D01*
G03X1139552Y220852I152J-130D01*
G01Y220588D01*
G03X1139600Y220458I200J0D01*
G01X1139601Y220457D01*
G02Y218483I-1131J-987D01*
G01Y218482D01*
X1139600D01*
G03X1139552Y218352I152J-130D01*
G01Y218088D01*
G03X1139600Y217958I200J0D01*
G01X1139601Y217957D01*
G02X1139971Y216970I-1131J-987D01*
G02X1138469Y215468I-1502J0D01*
G02X1137614Y215735I0J1502D01*
G01X1137580Y215758D01*
X1137499Y215775D01*
X1137132Y215695D01*
X1137065Y215647D01*
X1137044Y215612D01*
G02X1135756Y214883I-1288J773D01*
G02Y217887I0J1502D01*
G02X1136611Y217620I0J-1502D01*
G01X1136645Y217597D01*
X1136726Y217580D01*
X1137093Y217660D01*
X1137160Y217708D01*
X1137181Y217743D01*
G02X1137337Y217956I1285J-777D01*
G03X1137338Y217958I-173J88D01*
G03X1137386Y218088I-152J130D01*
G01Y218352D01*
G03X1137338Y218482I-200J0D01*
G01X1137337Y218483D01*
G02Y220457I1131J987D01*
G01Y220458D01*
X1137338D01*
G03X1137386Y220588I-152J130D01*
G01Y220852D01*
G03X1137338Y220982I-200J0D01*
G01X1137337Y220983D01*
G02X1136967Y221970I1131J987D01*
G37*
G36*
G01X1239329D02*
G02X1242333I1502J0D01*
G02X1241963Y220983I-1501J0D01*
G01Y220982D01*
X1241962D01*
G03X1241914Y220852I152J-130D01*
G01Y220588D01*
G03X1241962Y220458I200J0D01*
G01X1241963Y220457D01*
G02Y218483I-1131J-987D01*
G01Y218482D01*
X1241962D01*
G03X1241914Y218352I152J-130D01*
G01Y218088D01*
G03X1241962Y217958I200J0D01*
G01X1241963Y217957D01*
G02X1242333Y216970I-1131J-987D01*
G02X1240831Y215468I-1502J0D01*
G02X1239976Y215735I0J1502D01*
G01X1239942Y215758D01*
X1239861Y215775D01*
X1239494Y215695D01*
X1239427Y215647D01*
X1239406Y215612D01*
G02X1238118Y214883I-1288J773D01*
G02Y217887I0J1502D01*
G02X1238973Y217620I0J-1502D01*
G01X1239007Y217597D01*
X1239088Y217580D01*
X1239455Y217660D01*
X1239522Y217708D01*
X1239543Y217743D01*
G02X1239699Y217956I1285J-777D01*
G03X1239700Y217958I-173J88D01*
G03X1239748Y218088I-152J130D01*
G01Y218352D01*
G03X1239700Y218482I-200J0D01*
G01X1239699Y218483D01*
G02Y220457I1131J987D01*
G01Y220458D01*
X1239700D01*
G03X1239748Y220588I-152J130D01*
G01Y220852D01*
G03X1239700Y220982I-200J0D01*
G01X1239699Y220983D01*
G02X1239329Y221970I1131J987D01*
G37*
G36*
G01X1389330D02*
G02X1392334I1502J0D01*
G02X1391964Y220983I-1501J0D01*
G01Y220982D01*
X1391963D01*
G03X1391915Y220852I152J-130D01*
G01Y220588D01*
G03X1391963Y220458I200J0D01*
G01X1391964Y220457D01*
G02Y218483I-1131J-987D01*
G01Y218482D01*
X1391963D01*
G03X1391915Y218352I152J-130D01*
G01Y218088D01*
G03X1391963Y217958I200J0D01*
G01X1391964Y217957D01*
G02X1392334Y216970I-1131J-987D01*
G02X1390832Y215468I-1502J0D01*
G02X1389977Y215735I0J1502D01*
G01X1389943Y215758D01*
X1389862Y215775D01*
X1389495Y215695D01*
X1389428Y215647D01*
X1389407Y215612D01*
G02X1388119Y214883I-1288J773D01*
G02Y217887I0J1502D01*
G02X1388974Y217620I0J-1502D01*
G01X1389008Y217597D01*
X1389089Y217580D01*
X1389456Y217660D01*
X1389523Y217708D01*
X1389544Y217743D01*
G02X1389700Y217956I1285J-777D01*
G03X1389701Y217958I-173J88D01*
G03X1389749Y218088I-152J130D01*
G01Y218352D01*
G03X1389701Y218482I-200J0D01*
G01X1389700Y218483D01*
G02Y220457I1131J987D01*
G01Y220458D01*
X1389701D01*
G03X1389749Y220588I-152J130D01*
G01Y220852D01*
G03X1389701Y220982I-200J0D01*
G01X1389700Y220983D01*
G02X1389330Y221970I1131J987D01*
G37*
G36*
G01X1491692D02*
G02X1494696I1502J0D01*
G02X1494326Y220983I-1501J0D01*
G01Y220982D01*
X1494325D01*
G03X1494277Y220852I152J-130D01*
G01Y220588D01*
G03X1494325Y220458I200J0D01*
G01X1494326Y220457D01*
G02Y218483I-1131J-987D01*
G01Y218482D01*
X1494325D01*
G03X1494277Y218352I152J-130D01*
G01Y218088D01*
G03X1494325Y217958I200J0D01*
G01X1494326Y217957D01*
G02X1494696Y216970I-1131J-987D01*
G02X1493194Y215468I-1502J0D01*
G02X1492339Y215735I0J1502D01*
G01X1492305Y215758D01*
X1492224Y215775D01*
X1491857Y215695D01*
X1491790Y215647D01*
X1491769Y215612D01*
G02X1490481Y214883I-1288J773D01*
G02Y217887I0J1502D01*
G02X1491336Y217620I0J-1502D01*
G01X1491370Y217597D01*
X1491451Y217580D01*
X1491818Y217660D01*
X1491885Y217708D01*
X1491906Y217743D01*
G02X1492062Y217956I1285J-777D01*
G03X1492063Y217958I-173J88D01*
G03X1492111Y218088I-152J130D01*
G01Y218352D01*
G03X1492063Y218482I-200J0D01*
G01X1492062Y218483D01*
G02Y220457I1131J987D01*
G01Y220458D01*
X1492063D01*
G03X1492111Y220588I-152J130D01*
G01Y220852D01*
G03X1492063Y220982I-200J0D01*
G01X1492062Y220983D01*
G02X1491692Y221970I1131J987D01*
G37*
G36*
G01X1594054D02*
G02X1597058I1502J0D01*
G02X1596688Y220983I-1501J0D01*
G01Y220982D01*
X1596687D01*
G03X1596639Y220852I152J-130D01*
G01Y220588D01*
G03X1596687Y220458I200J0D01*
G01X1596688Y220457D01*
G02Y218483I-1131J-987D01*
G01Y218482D01*
X1596687D01*
G03X1596639Y218352I152J-130D01*
G01Y218088D01*
G03X1596687Y217958I200J0D01*
G01X1596688Y217957D01*
G02X1597058Y216970I-1131J-987D01*
G02X1595556Y215468I-1502J0D01*
G02X1594701Y215735I0J1502D01*
G01X1594667Y215758D01*
X1594586Y215775D01*
X1594219Y215695D01*
X1594152Y215647D01*
X1594131Y215612D01*
G02X1592843Y214883I-1288J773D01*
G02Y217887I0J1502D01*
G02X1593698Y217620I0J-1502D01*
G01X1593732Y217597D01*
X1593813Y217580D01*
X1594180Y217660D01*
X1594247Y217708D01*
X1594268Y217743D01*
G02X1594424Y217956I1285J-777D01*
G03X1594425Y217958I-173J88D01*
G03X1594473Y218088I-152J130D01*
G01Y218352D01*
G03X1594425Y218482I-200J0D01*
G01X1594424Y218483D01*
G02Y220457I1131J987D01*
G01Y220458D01*
X1594425D01*
G03X1594473Y220588I-152J130D01*
G01Y220852D01*
G03X1594425Y220982I-200J0D01*
G01X1594424Y220983D01*
G02X1594054Y221970I1131J987D01*
G37*
G36*
G01X1696416D02*
G02X1699420I1502J0D01*
G02X1699050Y220983I-1501J0D01*
G01Y220982D01*
X1699049D01*
G03X1699001Y220852I152J-130D01*
G01Y220588D01*
G03X1699049Y220458I200J0D01*
G01X1699050Y220457D01*
G02Y218483I-1131J-987D01*
G01Y218482D01*
X1699049D01*
G03X1699001Y218352I152J-130D01*
G01Y218088D01*
G03X1699049Y217958I200J0D01*
G01X1699050Y217957D01*
G02X1699420Y216970I-1131J-987D01*
G02X1697918Y215468I-1502J0D01*
G02X1697063Y215735I0J1502D01*
G01X1697029Y215758D01*
X1696948Y215775D01*
X1696581Y215695D01*
X1696514Y215647D01*
X1696493Y215612D01*
G02X1695205Y214883I-1288J773D01*
G02Y217887I0J1502D01*
G02X1696060Y217620I0J-1502D01*
G01X1696094Y217597D01*
X1696175Y217580D01*
X1696542Y217660D01*
X1696609Y217708D01*
X1696630Y217743D01*
G02X1696786Y217956I1285J-777D01*
G03X1696787Y217958I-173J88D01*
G03X1696835Y218088I-152J130D01*
G01Y218352D01*
G03X1696787Y218482I-200J0D01*
G01X1696786Y218483D01*
G02Y220457I1131J987D01*
G01Y220458D01*
X1696787D01*
G03X1696835Y220588I-152J130D01*
G01Y220852D01*
G03X1696787Y220982I-200J0D01*
G01X1696786Y220983D01*
G02X1696416Y221970I1131J987D01*
G37*
G36*
G01X84896Y224421D02*
G02X87900I1502J0D01*
G02X87633Y223566I-1502J0D01*
G01X87610Y223532D01*
X87593Y223451D01*
X87673Y223084D01*
X87721Y223017D01*
X87756Y222996D01*
G02X87969Y222840I-777J-1285D01*
G03X87971Y222839I88J173D01*
G03X88101Y222791I130J152D01*
G01X88365D01*
G03X88495Y222839I0J200D01*
G01X88496Y222840D01*
G02X90470I987J-1131D01*
G01X90471D01*
Y222839D01*
G03X90601Y222791I130J152D01*
G01X90865D01*
G03X90995Y222839I0J200D01*
G01X90996Y222840D01*
G02X91983Y223210I987J-1131D01*
G02Y220206I0J-1502D01*
G02X90996Y220576I0J1501D01*
G01X90995D01*
Y220577D01*
G03X90865Y220625I-130J-152D01*
G01X90601D01*
G03X90471Y220577I0J-200D01*
G01X90470Y220576D01*
G02X88496I-987J1131D01*
G01X88495D01*
Y220577D01*
G03X88365Y220625I-130J-152D01*
G01X88101D01*
G03X87971Y220577I0J-200D01*
G01X87970Y220576D01*
G02X86983Y220206I-987J1131D01*
G02X85481Y221708I0J1502D01*
G02X85748Y222563I1502J0D01*
G01X85771Y222597D01*
X85788Y222678D01*
X85708Y223045D01*
X85660Y223112D01*
X85625Y223133D01*
G02X84896Y224421I773J1288D01*
G37*
G36*
G01X187258D02*
G02X190262I1502J0D01*
G02X189995Y223566I-1502J0D01*
G01X189972Y223532D01*
X189955Y223451D01*
X190035Y223084D01*
X190083Y223017D01*
X190118Y222996D01*
G02X190331Y222840I-777J-1285D01*
G03X190333Y222839I88J173D01*
G03X190463Y222791I130J152D01*
G01X190727D01*
G03X190857Y222839I0J200D01*
G01X190858Y222840D01*
G02X192832I987J-1131D01*
G01X192833D01*
Y222839D01*
G03X192963Y222791I130J152D01*
G01X193227D01*
G03X193357Y222839I0J200D01*
G01X193358Y222840D01*
G02X194345Y223210I987J-1131D01*
G02Y220206I0J-1502D01*
G02X193358Y220576I0J1501D01*
G01X193357D01*
Y220577D01*
G03X193227Y220625I-130J-152D01*
G01X192963D01*
G03X192833Y220577I0J-200D01*
G01X192832Y220576D01*
G02X190858I-987J1131D01*
G01X190857D01*
Y220577D01*
G03X190727Y220625I-130J-152D01*
G01X190463D01*
G03X190333Y220577I0J-200D01*
G01X190332Y220576D01*
G02X189345Y220206I-987J1131D01*
G02X187843Y221708I0J1502D01*
G02X188110Y222563I1502J0D01*
G01X188133Y222597D01*
X188150Y222678D01*
X188070Y223045D01*
X188022Y223112D01*
X187987Y223133D01*
G02X187258Y224421I773J1288D01*
G37*
G36*
G01X289620D02*
G02X292624I1502J0D01*
G02X292357Y223566I-1502J0D01*
G01X292334Y223532D01*
X292317Y223451D01*
X292397Y223084D01*
X292445Y223017D01*
X292480Y222996D01*
G02X292693Y222840I-777J-1285D01*
G03X292695Y222839I88J173D01*
G03X292825Y222791I130J152D01*
G01X293089D01*
G03X293219Y222839I0J200D01*
G01X293220Y222840D01*
G02X295194I987J-1131D01*
G01X295195D01*
Y222839D01*
G03X295325Y222791I130J152D01*
G01X295589D01*
G03X295719Y222839I0J200D01*
G01X295720Y222840D01*
G02X296707Y223210I987J-1131D01*
G02Y220206I0J-1502D01*
G02X295720Y220576I0J1501D01*
G01X295719D01*
Y220577D01*
G03X295589Y220625I-130J-152D01*
G01X295325D01*
G03X295195Y220577I0J-200D01*
G01X295194Y220576D01*
G02X293220I-987J1131D01*
G01X293219D01*
Y220577D01*
G03X293089Y220625I-130J-152D01*
G01X292825D01*
G03X292695Y220577I0J-200D01*
G01X292694Y220576D01*
G02X291707Y220206I-987J1131D01*
G02X290205Y221708I0J1502D01*
G02X290472Y222563I1502J0D01*
G01X290495Y222597D01*
X290512Y222678D01*
X290432Y223045D01*
X290384Y223112D01*
X290349Y223133D01*
G02X289620Y224421I773J1288D01*
G37*
G36*
G01X391982D02*
G02X394986I1502J0D01*
G02X394719Y223566I-1502J0D01*
G01X394696Y223532D01*
X394679Y223451D01*
X394759Y223084D01*
X394807Y223017D01*
X394842Y222996D01*
G02X395055Y222840I-777J-1285D01*
G03X395057Y222839I88J173D01*
G03X395187Y222791I130J152D01*
G01X395451D01*
G03X395581Y222839I0J200D01*
G01X395582Y222840D01*
G02X397556I987J-1131D01*
G01X397557D01*
Y222839D01*
G03X397687Y222791I130J152D01*
G01X397951D01*
G03X398081Y222839I0J200D01*
G01X398082Y222840D01*
G02X399069Y223210I987J-1131D01*
G02Y220206I0J-1502D01*
G02X398082Y220576I0J1501D01*
G01X398081D01*
Y220577D01*
G03X397951Y220625I-130J-152D01*
G01X397687D01*
G03X397557Y220577I0J-200D01*
G01X397556Y220576D01*
G02X395582I-987J1131D01*
G01X395581D01*
Y220577D01*
G03X395451Y220625I-130J-152D01*
G01X395187D01*
G03X395057Y220577I0J-200D01*
G01X395056Y220576D01*
G02X394069Y220206I-987J1131D01*
G02X392567Y221708I0J1502D01*
G02X392834Y222563I1502J0D01*
G01X392857Y222597D01*
X392874Y222678D01*
X392794Y223045D01*
X392746Y223112D01*
X392711Y223133D01*
G02X391982Y224421I773J1288D01*
G37*
G36*
G01X541983D02*
G02X544987I1502J0D01*
G02X544720Y223566I-1502J0D01*
G01X544697Y223532D01*
X544680Y223451D01*
X544760Y223084D01*
X544808Y223017D01*
X544843Y222996D01*
G02X545056Y222840I-777J-1285D01*
G03X545058Y222839I88J173D01*
G03X545188Y222791I130J152D01*
G01X545452D01*
G03X545582Y222839I0J200D01*
G01X545583Y222840D01*
G02X547557I987J-1131D01*
G01X547558D01*
Y222839D01*
G03X547688Y222791I130J152D01*
G01X547952D01*
G03X548082Y222839I0J200D01*
G01X548083Y222840D01*
G02X549070Y223210I987J-1131D01*
G02Y220206I0J-1502D01*
G02X548083Y220576I0J1501D01*
G01X548082D01*
Y220577D01*
G03X547952Y220625I-130J-152D01*
G01X547688D01*
G03X547558Y220577I0J-200D01*
G01X547557Y220576D01*
G02X545583I-987J1131D01*
G01X545582D01*
Y220577D01*
G03X545452Y220625I-130J-152D01*
G01X545188D01*
G03X545058Y220577I0J-200D01*
G01X545057Y220576D01*
G02X544070Y220206I-987J1131D01*
G02X542568Y221708I0J1502D01*
G02X542835Y222563I1502J0D01*
G01X542858Y222597D01*
X542875Y222678D01*
X542795Y223045D01*
X542747Y223112D01*
X542712Y223133D01*
G02X541983Y224421I773J1288D01*
G37*
G36*
G01X644345D02*
G02X647349I1502J0D01*
G02X647082Y223566I-1502J0D01*
G01X647059Y223532D01*
X647042Y223451D01*
X647122Y223084D01*
X647170Y223017D01*
X647205Y222996D01*
G02X647418Y222840I-777J-1285D01*
G03X647420Y222839I88J173D01*
G03X647550Y222791I130J152D01*
G01X647814D01*
G03X647944Y222839I0J200D01*
G01X647945Y222840D01*
G02X649919I987J-1131D01*
G01X649920D01*
Y222839D01*
G03X650050Y222791I130J152D01*
G01X650314D01*
G03X650444Y222839I0J200D01*
G01X650445Y222840D01*
G02X651432Y223210I987J-1131D01*
G02Y220206I0J-1502D01*
G02X650445Y220576I0J1501D01*
G01X650444D01*
Y220577D01*
G03X650314Y220625I-130J-152D01*
G01X650050D01*
G03X649920Y220577I0J-200D01*
G01X649919Y220576D01*
G02X647945I-987J1131D01*
G01X647944D01*
Y220577D01*
G03X647814Y220625I-130J-152D01*
G01X647550D01*
G03X647420Y220577I0J-200D01*
G01X647419Y220576D01*
G02X646432Y220206I-987J1131D01*
G02X644930Y221708I0J1502D01*
G02X645197Y222563I1502J0D01*
G01X645220Y222597D01*
X645237Y222678D01*
X645157Y223045D01*
X645109Y223112D01*
X645074Y223133D01*
G02X644345Y224421I773J1288D01*
G37*
G36*
G01X746707D02*
G02X749711I1502J0D01*
G02X749444Y223566I-1502J0D01*
G01X749421Y223532D01*
X749404Y223451D01*
X749484Y223084D01*
X749532Y223017D01*
X749567Y222996D01*
G02X749780Y222840I-777J-1285D01*
G03X749782Y222839I88J173D01*
G03X749912Y222791I130J152D01*
G01X750176D01*
G03X750306Y222839I0J200D01*
G01X750307Y222840D01*
G02X752281I987J-1131D01*
G01X752282D01*
Y222839D01*
G03X752412Y222791I130J152D01*
G01X752676D01*
G03X752806Y222839I0J200D01*
G01X752807Y222840D01*
G02X753794Y223210I987J-1131D01*
G02Y220206I0J-1502D01*
G02X752807Y220576I0J1501D01*
G01X752806D01*
Y220577D01*
G03X752676Y220625I-130J-152D01*
G01X752412D01*
G03X752282Y220577I0J-200D01*
G01X752281Y220576D01*
G02X750307I-987J1131D01*
G01X750306D01*
Y220577D01*
G03X750176Y220625I-130J-152D01*
G01X749912D01*
G03X749782Y220577I0J-200D01*
G01X749781Y220576D01*
G02X748794Y220206I-987J1131D01*
G02X747292Y221708I0J1502D01*
G02X747559Y222563I1502J0D01*
G01X747582Y222597D01*
X747599Y222678D01*
X747519Y223045D01*
X747471Y223112D01*
X747436Y223133D01*
G02X746707Y224421I773J1288D01*
G37*
G36*
G01X849069D02*
G02X852073I1502J0D01*
G02X851806Y223566I-1502J0D01*
G01X851783Y223532D01*
X851766Y223451D01*
X851846Y223084D01*
X851894Y223017D01*
X851929Y222996D01*
G02X852142Y222840I-777J-1285D01*
G03X852144Y222839I88J173D01*
G03X852274Y222791I130J152D01*
G01X852538D01*
G03X852668Y222839I0J200D01*
G01X852669Y222840D01*
G02X854643I987J-1131D01*
G01X854644D01*
Y222839D01*
G03X854774Y222791I130J152D01*
G01X855038D01*
G03X855168Y222839I0J200D01*
G01X855169Y222840D01*
G02X856156Y223210I987J-1131D01*
G02Y220206I0J-1502D01*
G02X855169Y220576I0J1501D01*
G01X855168D01*
Y220577D01*
G03X855038Y220625I-130J-152D01*
G01X854774D01*
G03X854644Y220577I0J-200D01*
G01X854643Y220576D01*
G02X852669I-987J1131D01*
G01X852668D01*
Y220577D01*
G03X852538Y220625I-130J-152D01*
G01X852274D01*
G03X852144Y220577I0J-200D01*
G01X852143Y220576D01*
G02X851156Y220206I-987J1131D01*
G02X849654Y221708I0J1502D01*
G02X849921Y222563I1502J0D01*
G01X849944Y222597D01*
X849961Y222678D01*
X849881Y223045D01*
X849833Y223112D01*
X849798Y223133D01*
G02X849069Y224421I773J1288D01*
G37*
G36*
G01X999069D02*
G02X1002073I1502J0D01*
G02X1001806Y223566I-1502J0D01*
G01X1001783Y223532D01*
X1001766Y223451D01*
X1001846Y223084D01*
X1001894Y223017D01*
X1001929Y222996D01*
G02X1002142Y222840I-777J-1285D01*
G03X1002144Y222839I88J173D01*
G03X1002274Y222791I130J152D01*
G01X1002538D01*
G03X1002668Y222839I0J200D01*
G01X1002669Y222840D01*
G02X1004643I987J-1131D01*
G01X1004644D01*
Y222839D01*
G03X1004774Y222791I130J152D01*
G01X1005038D01*
G03X1005168Y222839I0J200D01*
G01X1005169Y222840D01*
G02X1006156Y223210I987J-1131D01*
G02Y220206I0J-1502D01*
G02X1005169Y220576I0J1501D01*
G01X1005168D01*
Y220577D01*
G03X1005038Y220625I-130J-152D01*
G01X1004774D01*
G03X1004644Y220577I0J-200D01*
G01X1004643Y220576D01*
G02X1002669I-987J1131D01*
G01X1002668D01*
Y220577D01*
G03X1002538Y220625I-130J-152D01*
G01X1002274D01*
G03X1002144Y220577I0J-200D01*
G01X1002143Y220576D01*
G02X1001156Y220206I-987J1131D01*
G02X999654Y221708I0J1502D01*
G02X999921Y222563I1502J0D01*
G01X999944Y222597D01*
X999961Y222678D01*
X999881Y223045D01*
X999833Y223112D01*
X999798Y223133D01*
G02X999069Y224421I773J1288D01*
G37*
G36*
G01X1101431D02*
G02X1104435I1502J0D01*
G02X1104168Y223566I-1502J0D01*
G01X1104145Y223532D01*
X1104128Y223451D01*
X1104208Y223084D01*
X1104256Y223017D01*
X1104291Y222996D01*
G02X1104504Y222840I-777J-1285D01*
G03X1104506Y222839I88J173D01*
G03X1104636Y222791I130J152D01*
G01X1104900D01*
G03X1105030Y222839I0J200D01*
G01X1105031Y222840D01*
G02X1107005I987J-1131D01*
G01X1107006D01*
Y222839D01*
G03X1107136Y222791I130J152D01*
G01X1107400D01*
G03X1107530Y222839I0J200D01*
G01X1107531Y222840D01*
G02X1108518Y223210I987J-1131D01*
G02Y220206I0J-1502D01*
G02X1107531Y220576I0J1501D01*
G01X1107530D01*
Y220577D01*
G03X1107400Y220625I-130J-152D01*
G01X1107136D01*
G03X1107006Y220577I0J-200D01*
G01X1107005Y220576D01*
G02X1105031I-987J1131D01*
G01X1105030D01*
Y220577D01*
G03X1104900Y220625I-130J-152D01*
G01X1104636D01*
G03X1104506Y220577I0J-200D01*
G01X1104505Y220576D01*
G02X1103518Y220206I-987J1131D01*
G02X1102016Y221708I0J1502D01*
G02X1102283Y222563I1502J0D01*
G01X1102306Y222597D01*
X1102323Y222678D01*
X1102243Y223045D01*
X1102195Y223112D01*
X1102160Y223133D01*
G02X1101431Y224421I773J1288D01*
G37*
G36*
G01X1203793D02*
G02X1206797I1502J0D01*
G02X1206530Y223566I-1502J0D01*
G01X1206507Y223532D01*
X1206490Y223451D01*
X1206570Y223084D01*
X1206618Y223017D01*
X1206653Y222996D01*
G02X1206866Y222840I-777J-1285D01*
G03X1206868Y222839I88J173D01*
G03X1206998Y222791I130J152D01*
G01X1207262D01*
G03X1207392Y222839I0J200D01*
G01X1207393Y222840D01*
G02X1209367I987J-1131D01*
G01X1209368D01*
Y222839D01*
G03X1209498Y222791I130J152D01*
G01X1209762D01*
G03X1209892Y222839I0J200D01*
G01X1209893Y222840D01*
G02X1210880Y223210I987J-1131D01*
G02Y220206I0J-1502D01*
G02X1209893Y220576I0J1501D01*
G01X1209892D01*
Y220577D01*
G03X1209762Y220625I-130J-152D01*
G01X1209498D01*
G03X1209368Y220577I0J-200D01*
G01X1209367Y220576D01*
G02X1207393I-987J1131D01*
G01X1207392D01*
Y220577D01*
G03X1207262Y220625I-130J-152D01*
G01X1206998D01*
G03X1206868Y220577I0J-200D01*
G01X1206867Y220576D01*
G02X1205880Y220206I-987J1131D01*
G02X1204378Y221708I0J1502D01*
G02X1204645Y222563I1502J0D01*
G01X1204668Y222597D01*
X1204685Y222678D01*
X1204605Y223045D01*
X1204557Y223112D01*
X1204522Y223133D01*
G02X1203793Y224421I773J1288D01*
G37*
G36*
G01X1306155D02*
G02X1309159I1502J0D01*
G02X1308892Y223566I-1502J0D01*
G01X1308869Y223532D01*
X1308852Y223451D01*
X1308932Y223084D01*
X1308980Y223017D01*
X1309015Y222996D01*
G02X1309228Y222840I-777J-1285D01*
G03X1309230Y222839I88J173D01*
G03X1309360Y222791I130J152D01*
G01X1309624D01*
G03X1309754Y222839I0J200D01*
G01X1309755Y222840D01*
G02X1311729I987J-1131D01*
G01X1311730D01*
Y222839D01*
G03X1311860Y222791I130J152D01*
G01X1312124D01*
G03X1312254Y222839I0J200D01*
G01X1312255Y222840D01*
G02X1313242Y223210I987J-1131D01*
G02Y220206I0J-1502D01*
G02X1312255Y220576I0J1501D01*
G01X1312254D01*
Y220577D01*
G03X1312124Y220625I-130J-152D01*
G01X1311860D01*
G03X1311730Y220577I0J-200D01*
G01X1311729Y220576D01*
G02X1309755I-987J1131D01*
G01X1309754D01*
Y220577D01*
G03X1309624Y220625I-130J-152D01*
G01X1309360D01*
G03X1309230Y220577I0J-200D01*
G01X1309229Y220576D01*
G02X1308242Y220206I-987J1131D01*
G02X1306740Y221708I0J1502D01*
G02X1307007Y222563I1502J0D01*
G01X1307030Y222597D01*
X1307047Y222678D01*
X1306967Y223045D01*
X1306919Y223112D01*
X1306884Y223133D01*
G02X1306155Y224421I773J1288D01*
G37*
G36*
G01X1456156D02*
G02X1459160I1502J0D01*
G02X1458893Y223566I-1502J0D01*
G01X1458870Y223532D01*
X1458853Y223451D01*
X1458933Y223084D01*
X1458981Y223017D01*
X1459016Y222996D01*
G02X1459229Y222840I-777J-1285D01*
G03X1459231Y222839I88J173D01*
G03X1459361Y222791I130J152D01*
G01X1459625D01*
G03X1459755Y222839I0J200D01*
G01X1459756Y222840D01*
G02X1461730I987J-1131D01*
G01X1461731D01*
Y222839D01*
G03X1461861Y222791I130J152D01*
G01X1462125D01*
G03X1462255Y222839I0J200D01*
G01X1462256Y222840D01*
G02X1463243Y223210I987J-1131D01*
G02Y220206I0J-1502D01*
G02X1462256Y220576I0J1501D01*
G01X1462255D01*
Y220577D01*
G03X1462125Y220625I-130J-152D01*
G01X1461861D01*
G03X1461731Y220577I0J-200D01*
G01X1461730Y220576D01*
G02X1459756I-987J1131D01*
G01X1459755D01*
Y220577D01*
G03X1459625Y220625I-130J-152D01*
G01X1459361D01*
G03X1459231Y220577I0J-200D01*
G01X1459230Y220576D01*
G02X1458243Y220206I-987J1131D01*
G02X1456741Y221708I0J1502D01*
G02X1457008Y222563I1502J0D01*
G01X1457031Y222597D01*
X1457048Y222678D01*
X1456968Y223045D01*
X1456920Y223112D01*
X1456885Y223133D01*
G02X1456156Y224421I773J1288D01*
G37*
G36*
G01X1558518D02*
G02X1561522I1502J0D01*
G02X1561255Y223566I-1502J0D01*
G01X1561232Y223532D01*
X1561215Y223451D01*
X1561295Y223084D01*
X1561343Y223017D01*
X1561378Y222996D01*
G02X1561591Y222840I-777J-1285D01*
G03X1561593Y222839I88J173D01*
G03X1561723Y222791I130J152D01*
G01X1561987D01*
G03X1562117Y222839I0J200D01*
G01X1562118Y222840D01*
G02X1564092I987J-1131D01*
G01X1564093D01*
Y222839D01*
G03X1564223Y222791I130J152D01*
G01X1564487D01*
G03X1564617Y222839I0J200D01*
G01X1564618Y222840D01*
G02X1565605Y223210I987J-1131D01*
G02Y220206I0J-1502D01*
G02X1564618Y220576I0J1501D01*
G01X1564617D01*
Y220577D01*
G03X1564487Y220625I-130J-152D01*
G01X1564223D01*
G03X1564093Y220577I0J-200D01*
G01X1564092Y220576D01*
G02X1562118I-987J1131D01*
G01X1562117D01*
Y220577D01*
G03X1561987Y220625I-130J-152D01*
G01X1561723D01*
G03X1561593Y220577I0J-200D01*
G01X1561592Y220576D01*
G02X1560605Y220206I-987J1131D01*
G02X1559103Y221708I0J1502D01*
G02X1559370Y222563I1502J0D01*
G01X1559393Y222597D01*
X1559410Y222678D01*
X1559330Y223045D01*
X1559282Y223112D01*
X1559247Y223133D01*
G02X1558518Y224421I773J1288D01*
G37*
G36*
G01X1660880D02*
G02X1663884I1502J0D01*
G02X1663617Y223566I-1502J0D01*
G01X1663594Y223532D01*
X1663577Y223451D01*
X1663657Y223084D01*
X1663705Y223017D01*
X1663740Y222996D01*
G02X1663953Y222840I-777J-1285D01*
G03X1663955Y222839I88J173D01*
G03X1664085Y222791I130J152D01*
G01X1664349D01*
G03X1664479Y222839I0J200D01*
G01X1664480Y222840D01*
G02X1666454I987J-1131D01*
G01X1666455D01*
Y222839D01*
G03X1666585Y222791I130J152D01*
G01X1666849D01*
G03X1666979Y222839I0J200D01*
G01X1666980Y222840D01*
G02X1667967Y223210I987J-1131D01*
G02Y220206I0J-1502D01*
G02X1666980Y220576I0J1501D01*
G01X1666979D01*
Y220577D01*
G03X1666849Y220625I-130J-152D01*
G01X1666585D01*
G03X1666455Y220577I0J-200D01*
G01X1666454Y220576D01*
G02X1664480I-987J1131D01*
G01X1664479D01*
Y220577D01*
G03X1664349Y220625I-130J-152D01*
G01X1664085D01*
G03X1663955Y220577I0J-200D01*
G01X1663954Y220576D01*
G02X1662967Y220206I-987J1131D01*
G02X1661465Y221708I0J1502D01*
G02X1661732Y222563I1502J0D01*
G01X1661755Y222597D01*
X1661772Y222678D01*
X1661692Y223045D01*
X1661644Y223112D01*
X1661609Y223133D01*
G02X1660880Y224421I773J1288D01*
G37*
G36*
G01X1763242D02*
G02X1766246I1502J0D01*
G02X1765979Y223566I-1502J0D01*
G01X1765956Y223532D01*
X1765939Y223451D01*
X1766019Y223084D01*
X1766067Y223017D01*
X1766102Y222996D01*
G02X1766315Y222840I-777J-1285D01*
G03X1766317Y222839I88J173D01*
G03X1766447Y222791I130J152D01*
G01X1766711D01*
G03X1766841Y222839I0J200D01*
G01X1766842Y222840D01*
G02X1768816I987J-1131D01*
G01X1768817D01*
Y222839D01*
G03X1768947Y222791I130J152D01*
G01X1769211D01*
G03X1769341Y222839I0J200D01*
G01X1769342Y222840D01*
G02X1770329Y223210I987J-1131D01*
G02Y220206I0J-1502D01*
G02X1769342Y220576I0J1501D01*
G01X1769341D01*
Y220577D01*
G03X1769211Y220625I-130J-152D01*
G01X1768947D01*
G03X1768817Y220577I0J-200D01*
G01X1768816Y220576D01*
G02X1766842I-987J1131D01*
G01X1766841D01*
Y220577D01*
G03X1766711Y220625I-130J-152D01*
G01X1766447D01*
G03X1766317Y220577I0J-200D01*
G01X1766316Y220576D01*
G02X1765329Y220206I-987J1131D01*
G02X1763827Y221708I0J1502D01*
G02X1764094Y222563I1502J0D01*
G01X1764117Y222597D01*
X1764134Y222678D01*
X1764054Y223045D01*
X1764006Y223112D01*
X1763971Y223133D01*
G02X1763242Y224421I773J1288D01*
G37*
G36*
G01X87146Y229474D02*
Y229768D01*
G03X87081Y229915I-200J-1D01*
G02X86596Y231021I1019J1106D01*
G02X89600I1502J0D01*
G02X89115Y229915I-1504J0D01*
G03X89050Y229768I135J-148D01*
G01Y229474D01*
G03X89115Y229327I200J1D01*
G02X89600Y228221I-1019J-1106D01*
G02X86596I-1502J0D01*
G02X87081Y229327I1504J0D01*
G03X87146Y229474I-135J148D01*
G37*
G36*
G01X189508D02*
Y229768D01*
G03X189443Y229915I-200J-1D01*
G02X188958Y231021I1019J1106D01*
G02X191962I1502J0D01*
G02X191477Y229915I-1504J0D01*
G03X191412Y229768I135J-148D01*
G01Y229474D01*
G03X191477Y229327I200J1D01*
G02X191962Y228221I-1019J-1106D01*
G02X188958I-1502J0D01*
G02X189443Y229327I1504J0D01*
G03X189508Y229474I-135J148D01*
G37*
G36*
G01X291870D02*
Y229768D01*
G03X291805Y229915I-200J-1D01*
G02X291320Y231021I1019J1106D01*
G02X294324I1502J0D01*
G02X293839Y229915I-1504J0D01*
G03X293774Y229768I135J-148D01*
G01Y229474D01*
G03X293839Y229327I200J1D01*
G02X294324Y228221I-1019J-1106D01*
G02X291320I-1502J0D01*
G02X291805Y229327I1504J0D01*
G03X291870Y229474I-135J148D01*
G37*
G36*
G01X394232D02*
Y229768D01*
G03X394167Y229915I-200J-1D01*
G02X393682Y231021I1019J1106D01*
G02X396686I1502J0D01*
G02X396201Y229915I-1504J0D01*
G03X396136Y229768I135J-148D01*
G01Y229474D01*
G03X396201Y229327I200J1D01*
G02X396686Y228221I-1019J-1106D01*
G02X393682I-1502J0D01*
G02X394167Y229327I1504J0D01*
G03X394232Y229474I-135J148D01*
G37*
G36*
G01X544233D02*
Y229768D01*
G03X544168Y229915I-200J-1D01*
G02X543683Y231021I1019J1106D01*
G02X546687I1502J0D01*
G02X546202Y229915I-1504J0D01*
G03X546137Y229768I135J-148D01*
G01Y229474D01*
G03X546202Y229327I200J1D01*
G02X546687Y228221I-1019J-1106D01*
G02X543683I-1502J0D01*
G02X544168Y229327I1504J0D01*
G03X544233Y229474I-135J148D01*
G37*
G36*
G01X646595D02*
Y229768D01*
G03X646530Y229915I-200J-1D01*
G02X646045Y231021I1019J1106D01*
G02X649049I1502J0D01*
G02X648564Y229915I-1504J0D01*
G03X648499Y229768I135J-148D01*
G01Y229474D01*
G03X648564Y229327I200J1D01*
G02X649049Y228221I-1019J-1106D01*
G02X646045I-1502J0D01*
G02X646530Y229327I1504J0D01*
G03X646595Y229474I-135J148D01*
G37*
G36*
G01X748957D02*
Y229768D01*
G03X748892Y229915I-200J-1D01*
G02X748407Y231021I1019J1106D01*
G02X751411I1502J0D01*
G02X750926Y229915I-1504J0D01*
G03X750861Y229768I135J-148D01*
G01Y229474D01*
G03X750926Y229327I200J1D01*
G02X751411Y228221I-1019J-1106D01*
G02X748407I-1502J0D01*
G02X748892Y229327I1504J0D01*
G03X748957Y229474I-135J148D01*
G37*
G36*
G01X851319D02*
Y229768D01*
G03X851254Y229915I-200J-1D01*
G02X850769Y231021I1019J1106D01*
G02X853773I1502J0D01*
G02X853288Y229915I-1504J0D01*
G03X853223Y229768I135J-148D01*
G01Y229474D01*
G03X853288Y229327I200J1D01*
G02X853773Y228221I-1019J-1106D01*
G02X850769I-1502J0D01*
G02X851254Y229327I1504J0D01*
G03X851319Y229474I-135J148D01*
G37*
G36*
G01X1001319D02*
Y229768D01*
G03X1001254Y229915I-200J-1D01*
G02X1000769Y231021I1019J1106D01*
G02X1003773I1502J0D01*
G02X1003288Y229915I-1504J0D01*
G03X1003223Y229768I135J-148D01*
G01Y229474D01*
G03X1003288Y229327I200J1D01*
G02X1003773Y228221I-1019J-1106D01*
G02X1000769I-1502J0D01*
G02X1001254Y229327I1504J0D01*
G03X1001319Y229474I-135J148D01*
G37*
G36*
G01X1103681D02*
Y229768D01*
G03X1103616Y229915I-200J-1D01*
G02X1103131Y231021I1019J1106D01*
G02X1106135I1502J0D01*
G02X1105650Y229915I-1504J0D01*
G03X1105585Y229768I135J-148D01*
G01Y229474D01*
G03X1105650Y229327I200J1D01*
G02X1106135Y228221I-1019J-1106D01*
G02X1103131I-1502J0D01*
G02X1103616Y229327I1504J0D01*
G03X1103681Y229474I-135J148D01*
G37*
G36*
G01X1206043D02*
Y229768D01*
G03X1205978Y229915I-200J-1D01*
G02X1205493Y231021I1019J1106D01*
G02X1208497I1502J0D01*
G02X1208012Y229915I-1504J0D01*
G03X1207947Y229768I135J-148D01*
G01Y229474D01*
G03X1208012Y229327I200J1D01*
G02X1208497Y228221I-1019J-1106D01*
G02X1205493I-1502J0D01*
G02X1205978Y229327I1504J0D01*
G03X1206043Y229474I-135J148D01*
G37*
G36*
G01X1308405D02*
Y229768D01*
G03X1308340Y229915I-200J-1D01*
G02X1307855Y231021I1019J1106D01*
G02X1310859I1502J0D01*
G02X1310374Y229915I-1504J0D01*
G03X1310309Y229768I135J-148D01*
G01Y229474D01*
G03X1310374Y229327I200J1D01*
G02X1310859Y228221I-1019J-1106D01*
G02X1307855I-1502J0D01*
G02X1308340Y229327I1504J0D01*
G03X1308405Y229474I-135J148D01*
G37*
G36*
G01X1458406D02*
Y229768D01*
G03X1458341Y229915I-200J-1D01*
G02X1457856Y231021I1019J1106D01*
G02X1460860I1502J0D01*
G02X1460375Y229915I-1504J0D01*
G03X1460310Y229768I135J-148D01*
G01Y229474D01*
G03X1460375Y229327I200J1D01*
G02X1460860Y228221I-1019J-1106D01*
G02X1457856I-1502J0D01*
G02X1458341Y229327I1504J0D01*
G03X1458406Y229474I-135J148D01*
G37*
G36*
G01X1560768D02*
Y229768D01*
G03X1560703Y229915I-200J-1D01*
G02X1560218Y231021I1019J1106D01*
G02X1563222I1502J0D01*
G02X1562737Y229915I-1504J0D01*
G03X1562672Y229768I135J-148D01*
G01Y229474D01*
G03X1562737Y229327I200J1D01*
G02X1563222Y228221I-1019J-1106D01*
G02X1560218I-1502J0D01*
G02X1560703Y229327I1504J0D01*
G03X1560768Y229474I-135J148D01*
G37*
G36*
G01X1663130D02*
Y229768D01*
G03X1663065Y229915I-200J-1D01*
G02X1662580Y231021I1019J1106D01*
G02X1665584I1502J0D01*
G02X1665099Y229915I-1504J0D01*
G03X1665034Y229768I135J-148D01*
G01Y229474D01*
G03X1665099Y229327I200J1D01*
G02X1665584Y228221I-1019J-1106D01*
G02X1662580I-1502J0D01*
G02X1663065Y229327I1504J0D01*
G03X1663130Y229474I-135J148D01*
G37*
G36*
G01X1765492D02*
Y229768D01*
G03X1765427Y229915I-200J-1D01*
G02X1764942Y231021I1019J1106D01*
G02X1767946I1502J0D01*
G02X1767461Y229915I-1504J0D01*
G03X1767396Y229768I135J-148D01*
G01Y229474D01*
G03X1767461Y229327I200J1D01*
G02X1767946Y228221I-1019J-1106D01*
G02X1764942I-1502J0D01*
G02X1765427Y229327I1504J0D01*
G03X1765492Y229474I-135J148D01*
G37*
G36*
G01X92136Y237321D02*
X92137Y237320D01*
G03X92267Y237272I130J152D01*
G01X92531D01*
G03X92661Y237320I0J200D01*
G01X92662Y237321D01*
G02X93649Y237691I987J-1131D01*
G02Y234687I0J-1502D01*
G02X92662Y235057I0J1501D01*
G01X92661D01*
Y235058D01*
G03X92531Y235106I-130J-152D01*
G01X92267D01*
G03X92137Y235058I0J-200D01*
G01X92136Y235057D01*
G02X90162I-987J1131D01*
G01X90161D01*
Y235058D01*
G03X90031Y235106I-130J-152D01*
G01X89767D01*
G03X89637Y235058I0J-200D01*
G01X89636Y235057D01*
G02X88649Y234687I-987J1131D01*
G02Y237691I0J1502D01*
G02X89636Y237321I0J-1501D01*
G01X89637D01*
Y237320D01*
G03X89767Y237272I130J152D01*
G01X90031D01*
G03X90161Y237320I0J200D01*
G01X90162Y237321D01*
G02X92136I987J-1131D01*
G37*
G36*
G01X194498D02*
X194499Y237320D01*
G03X194629Y237272I130J152D01*
G01X194893D01*
G03X195023Y237320I0J200D01*
G01X195024Y237321D01*
G02X196011Y237691I987J-1131D01*
G02Y234687I0J-1502D01*
G02X195024Y235057I0J1501D01*
G01X195023D01*
Y235058D01*
G03X194893Y235106I-130J-152D01*
G01X194629D01*
G03X194499Y235058I0J-200D01*
G01X194498Y235057D01*
G02X192524I-987J1131D01*
G01X192523D01*
Y235058D01*
G03X192393Y235106I-130J-152D01*
G01X192129D01*
G03X191999Y235058I0J-200D01*
G01X191998Y235057D01*
G02X191011Y234687I-987J1131D01*
G02Y237691I0J1502D01*
G02X191998Y237321I0J-1501D01*
G01X191999D01*
Y237320D01*
G03X192129Y237272I130J152D01*
G01X192393D01*
G03X192523Y237320I0J200D01*
G01X192524Y237321D01*
G02X194498I987J-1131D01*
G37*
G36*
G01X296860D02*
X296861Y237320D01*
G03X296991Y237272I130J152D01*
G01X297255D01*
G03X297385Y237320I0J200D01*
G01X297386Y237321D01*
G02X298373Y237691I987J-1131D01*
G02Y234687I0J-1502D01*
G02X297386Y235057I0J1501D01*
G01X297385D01*
Y235058D01*
G03X297255Y235106I-130J-152D01*
G01X296991D01*
G03X296861Y235058I0J-200D01*
G01X296860Y235057D01*
G02X294886I-987J1131D01*
G01X294885D01*
Y235058D01*
G03X294755Y235106I-130J-152D01*
G01X294491D01*
G03X294361Y235058I0J-200D01*
G01X294360Y235057D01*
G02X293373Y234687I-987J1131D01*
G02Y237691I0J1502D01*
G02X294360Y237321I0J-1501D01*
G01X294361D01*
Y237320D01*
G03X294491Y237272I130J152D01*
G01X294755D01*
G03X294885Y237320I0J200D01*
G01X294886Y237321D01*
G02X296860I987J-1131D01*
G37*
G36*
G01X399222D02*
X399223Y237320D01*
G03X399353Y237272I130J152D01*
G01X399617D01*
G03X399747Y237320I0J200D01*
G01X399748Y237321D01*
G02X400735Y237691I987J-1131D01*
G02Y234687I0J-1502D01*
G02X399748Y235057I0J1501D01*
G01X399747D01*
Y235058D01*
G03X399617Y235106I-130J-152D01*
G01X399353D01*
G03X399223Y235058I0J-200D01*
G01X399222Y235057D01*
G02X397248I-987J1131D01*
G01X397247D01*
Y235058D01*
G03X397117Y235106I-130J-152D01*
G01X396853D01*
G03X396723Y235058I0J-200D01*
G01X396722Y235057D01*
G02X395735Y234687I-987J1131D01*
G02Y237691I0J1502D01*
G02X396722Y237321I0J-1501D01*
G01X396723D01*
Y237320D01*
G03X396853Y237272I130J152D01*
G01X397117D01*
G03X397247Y237320I0J200D01*
G01X397248Y237321D01*
G02X399222I987J-1131D01*
G37*
G36*
G01X549223D02*
X549224Y237320D01*
G03X549354Y237272I130J152D01*
G01X549618D01*
G03X549748Y237320I0J200D01*
G01X549749Y237321D01*
G02X550736Y237691I987J-1131D01*
G02Y234687I0J-1502D01*
G02X549749Y235057I0J1501D01*
G01X549748D01*
Y235058D01*
G03X549618Y235106I-130J-152D01*
G01X549354D01*
G03X549224Y235058I0J-200D01*
G01X549223Y235057D01*
G02X547249I-987J1131D01*
G01X547248D01*
Y235058D01*
G03X547118Y235106I-130J-152D01*
G01X546854D01*
G03X546724Y235058I0J-200D01*
G01X546723Y235057D01*
G02X545736Y234687I-987J1131D01*
G02Y237691I0J1502D01*
G02X546723Y237321I0J-1501D01*
G01X546724D01*
Y237320D01*
G03X546854Y237272I130J152D01*
G01X547118D01*
G03X547248Y237320I0J200D01*
G01X547249Y237321D01*
G02X549223I987J-1131D01*
G37*
G36*
G01X651585D02*
X651586Y237320D01*
G03X651716Y237272I130J152D01*
G01X651980D01*
G03X652110Y237320I0J200D01*
G01X652111Y237321D01*
G02X653098Y237691I987J-1131D01*
G02Y234687I0J-1502D01*
G02X652111Y235057I0J1501D01*
G01X652110D01*
Y235058D01*
G03X651980Y235106I-130J-152D01*
G01X651716D01*
G03X651586Y235058I0J-200D01*
G01X651585Y235057D01*
G02X649611I-987J1131D01*
G01X649610D01*
Y235058D01*
G03X649480Y235106I-130J-152D01*
G01X649216D01*
G03X649086Y235058I0J-200D01*
G01X649085Y235057D01*
G02X648098Y234687I-987J1131D01*
G02Y237691I0J1502D01*
G02X649085Y237321I0J-1501D01*
G01X649086D01*
Y237320D01*
G03X649216Y237272I130J152D01*
G01X649480D01*
G03X649610Y237320I0J200D01*
G01X649611Y237321D01*
G02X651585I987J-1131D01*
G37*
G36*
G01X753947D02*
X753948Y237320D01*
G03X754078Y237272I130J152D01*
G01X754342D01*
G03X754472Y237320I0J200D01*
G01X754473Y237321D01*
G02X755460Y237691I987J-1131D01*
G02Y234687I0J-1502D01*
G02X754473Y235057I0J1501D01*
G01X754472D01*
Y235058D01*
G03X754342Y235106I-130J-152D01*
G01X754078D01*
G03X753948Y235058I0J-200D01*
G01X753947Y235057D01*
G02X751973I-987J1131D01*
G01X751972D01*
Y235058D01*
G03X751842Y235106I-130J-152D01*
G01X751578D01*
G03X751448Y235058I0J-200D01*
G01X751447Y235057D01*
G02X750460Y234687I-987J1131D01*
G02Y237691I0J1502D01*
G02X751447Y237321I0J-1501D01*
G01X751448D01*
Y237320D01*
G03X751578Y237272I130J152D01*
G01X751842D01*
G03X751972Y237320I0J200D01*
G01X751973Y237321D01*
G02X753947I987J-1131D01*
G37*
G36*
G01X856309D02*
X856310Y237320D01*
G03X856440Y237272I130J152D01*
G01X856704D01*
G03X856834Y237320I0J200D01*
G01X856835Y237321D01*
G02X857822Y237691I987J-1131D01*
G02Y234687I0J-1502D01*
G02X856835Y235057I0J1501D01*
G01X856834D01*
Y235058D01*
G03X856704Y235106I-130J-152D01*
G01X856440D01*
G03X856310Y235058I0J-200D01*
G01X856309Y235057D01*
G02X854335I-987J1131D01*
G01X854334D01*
Y235058D01*
G03X854204Y235106I-130J-152D01*
G01X853940D01*
G03X853810Y235058I0J-200D01*
G01X853809Y235057D01*
G02X852822Y234687I-987J1131D01*
G02Y237691I0J1502D01*
G02X853809Y237321I0J-1501D01*
G01X853810D01*
Y237320D01*
G03X853940Y237272I130J152D01*
G01X854204D01*
G03X854334Y237320I0J200D01*
G01X854335Y237321D01*
G02X856309I987J-1131D01*
G37*
G36*
G01X1006309D02*
X1006310Y237320D01*
G03X1006440Y237272I130J152D01*
G01X1006704D01*
G03X1006834Y237320I0J200D01*
G01X1006835Y237321D01*
G02X1007822Y237691I987J-1131D01*
G02Y234687I0J-1502D01*
G02X1006835Y235057I0J1501D01*
G01X1006834D01*
Y235058D01*
G03X1006704Y235106I-130J-152D01*
G01X1006440D01*
G03X1006310Y235058I0J-200D01*
G01X1006309Y235057D01*
G02X1004335I-987J1131D01*
G01X1004334D01*
Y235058D01*
G03X1004204Y235106I-130J-152D01*
G01X1003940D01*
G03X1003810Y235058I0J-200D01*
G01X1003809Y235057D01*
G02X1002822Y234687I-987J1131D01*
G02Y237691I0J1502D01*
G02X1003809Y237321I0J-1501D01*
G01X1003810D01*
Y237320D01*
G03X1003940Y237272I130J152D01*
G01X1004204D01*
G03X1004334Y237320I0J200D01*
G01X1004335Y237321D01*
G02X1006309I987J-1131D01*
G37*
G36*
G01X1108671D02*
X1108672Y237320D01*
G03X1108802Y237272I130J152D01*
G01X1109066D01*
G03X1109196Y237320I0J200D01*
G01X1109197Y237321D01*
G02X1110184Y237691I987J-1131D01*
G02Y234687I0J-1502D01*
G02X1109197Y235057I0J1501D01*
G01X1109196D01*
Y235058D01*
G03X1109066Y235106I-130J-152D01*
G01X1108802D01*
G03X1108672Y235058I0J-200D01*
G01X1108671Y235057D01*
G02X1106697I-987J1131D01*
G01X1106696D01*
Y235058D01*
G03X1106566Y235106I-130J-152D01*
G01X1106302D01*
G03X1106172Y235058I0J-200D01*
G01X1106171Y235057D01*
G02X1105184Y234687I-987J1131D01*
G02Y237691I0J1502D01*
G02X1106171Y237321I0J-1501D01*
G01X1106172D01*
Y237320D01*
G03X1106302Y237272I130J152D01*
G01X1106566D01*
G03X1106696Y237320I0J200D01*
G01X1106697Y237321D01*
G02X1108671I987J-1131D01*
G37*
G36*
G01X1211033D02*
X1211034Y237320D01*
G03X1211164Y237272I130J152D01*
G01X1211428D01*
G03X1211558Y237320I0J200D01*
G01X1211559Y237321D01*
G02X1212546Y237691I987J-1131D01*
G02Y234687I0J-1502D01*
G02X1211559Y235057I0J1501D01*
G01X1211558D01*
Y235058D01*
G03X1211428Y235106I-130J-152D01*
G01X1211164D01*
G03X1211034Y235058I0J-200D01*
G01X1211033Y235057D01*
G02X1209059I-987J1131D01*
G01X1209058D01*
Y235058D01*
G03X1208928Y235106I-130J-152D01*
G01X1208664D01*
G03X1208534Y235058I0J-200D01*
G01X1208533Y235057D01*
G02X1207546Y234687I-987J1131D01*
G02Y237691I0J1502D01*
G02X1208533Y237321I0J-1501D01*
G01X1208534D01*
Y237320D01*
G03X1208664Y237272I130J152D01*
G01X1208928D01*
G03X1209058Y237320I0J200D01*
G01X1209059Y237321D01*
G02X1211033I987J-1131D01*
G37*
G36*
G01X1313395D02*
X1313396Y237320D01*
G03X1313526Y237272I130J152D01*
G01X1313790D01*
G03X1313920Y237320I0J200D01*
G01X1313921Y237321D01*
G02X1314908Y237691I987J-1131D01*
G02Y234687I0J-1502D01*
G02X1313921Y235057I0J1501D01*
G01X1313920D01*
Y235058D01*
G03X1313790Y235106I-130J-152D01*
G01X1313526D01*
G03X1313396Y235058I0J-200D01*
G01X1313395Y235057D01*
G02X1311421I-987J1131D01*
G01X1311420D01*
Y235058D01*
G03X1311290Y235106I-130J-152D01*
G01X1311026D01*
G03X1310896Y235058I0J-200D01*
G01X1310895Y235057D01*
G02X1309908Y234687I-987J1131D01*
G02Y237691I0J1502D01*
G02X1310895Y237321I0J-1501D01*
G01X1310896D01*
Y237320D01*
G03X1311026Y237272I130J152D01*
G01X1311290D01*
G03X1311420Y237320I0J200D01*
G01X1311421Y237321D01*
G02X1313395I987J-1131D01*
G37*
G36*
G01X1463396D02*
X1463397Y237320D01*
G03X1463527Y237272I130J152D01*
G01X1463791D01*
G03X1463921Y237320I0J200D01*
G01X1463922Y237321D01*
G02X1464909Y237691I987J-1131D01*
G02Y234687I0J-1502D01*
G02X1463922Y235057I0J1501D01*
G01X1463921D01*
Y235058D01*
G03X1463791Y235106I-130J-152D01*
G01X1463527D01*
G03X1463397Y235058I0J-200D01*
G01X1463396Y235057D01*
G02X1461422I-987J1131D01*
G01X1461421D01*
Y235058D01*
G03X1461291Y235106I-130J-152D01*
G01X1461027D01*
G03X1460897Y235058I0J-200D01*
G01X1460896Y235057D01*
G02X1459909Y234687I-987J1131D01*
G02Y237691I0J1502D01*
G02X1460896Y237321I0J-1501D01*
G01X1460897D01*
Y237320D01*
G03X1461027Y237272I130J152D01*
G01X1461291D01*
G03X1461421Y237320I0J200D01*
G01X1461422Y237321D01*
G02X1463396I987J-1131D01*
G37*
G36*
G01X1565758D02*
X1565759Y237320D01*
G03X1565889Y237272I130J152D01*
G01X1566153D01*
G03X1566283Y237320I0J200D01*
G01X1566284Y237321D01*
G02X1567271Y237691I987J-1131D01*
G02Y234687I0J-1502D01*
G02X1566284Y235057I0J1501D01*
G01X1566283D01*
Y235058D01*
G03X1566153Y235106I-130J-152D01*
G01X1565889D01*
G03X1565759Y235058I0J-200D01*
G01X1565758Y235057D01*
G02X1563784I-987J1131D01*
G01X1563783D01*
Y235058D01*
G03X1563653Y235106I-130J-152D01*
G01X1563389D01*
G03X1563259Y235058I0J-200D01*
G01X1563258Y235057D01*
G02X1562271Y234687I-987J1131D01*
G02Y237691I0J1502D01*
G02X1563258Y237321I0J-1501D01*
G01X1563259D01*
Y237320D01*
G03X1563389Y237272I130J152D01*
G01X1563653D01*
G03X1563783Y237320I0J200D01*
G01X1563784Y237321D01*
G02X1565758I987J-1131D01*
G37*
G36*
G01X1668120D02*
X1668121Y237320D01*
G03X1668251Y237272I130J152D01*
G01X1668515D01*
G03X1668645Y237320I0J200D01*
G01X1668646Y237321D01*
G02X1669633Y237691I987J-1131D01*
G02Y234687I0J-1502D01*
G02X1668646Y235057I0J1501D01*
G01X1668645D01*
Y235058D01*
G03X1668515Y235106I-130J-152D01*
G01X1668251D01*
G03X1668121Y235058I0J-200D01*
G01X1668120Y235057D01*
G02X1666146I-987J1131D01*
G01X1666145D01*
Y235058D01*
G03X1666015Y235106I-130J-152D01*
G01X1665751D01*
G03X1665621Y235058I0J-200D01*
G01X1665620Y235057D01*
G02X1664633Y234687I-987J1131D01*
G02Y237691I0J1502D01*
G02X1665620Y237321I0J-1501D01*
G01X1665621D01*
Y237320D01*
G03X1665751Y237272I130J152D01*
G01X1666015D01*
G03X1666145Y237320I0J200D01*
G01X1666146Y237321D01*
G02X1668120I987J-1131D01*
G37*
G36*
G01X1770482D02*
X1770483Y237320D01*
G03X1770613Y237272I130J152D01*
G01X1770877D01*
G03X1771007Y237320I0J200D01*
G01X1771008Y237321D01*
G02X1771995Y237691I987J-1131D01*
G02Y234687I0J-1502D01*
G02X1771008Y235057I0J1501D01*
G01X1771007D01*
Y235058D01*
G03X1770877Y235106I-130J-152D01*
G01X1770613D01*
G03X1770483Y235058I0J-200D01*
G01X1770482Y235057D01*
G02X1768508I-987J1131D01*
G01X1768507D01*
Y235058D01*
G03X1768377Y235106I-130J-152D01*
G01X1768113D01*
G03X1767983Y235058I0J-200D01*
G01X1767982Y235057D01*
G02X1766995Y234687I-987J1131D01*
G02Y237691I0J1502D01*
G02X1767982Y237321I0J-1501D01*
G01X1767983D01*
Y237320D01*
G03X1768113Y237272I130J152D01*
G01X1768377D01*
G03X1768507Y237320I0J200D01*
G01X1768508Y237321D01*
G02X1770482I987J-1131D01*
G37*
G36*
G01X92077Y249897D02*
X92078Y249896D01*
G03X92208Y249848I130J152D01*
G01X92472D01*
G03X92602Y249896I0J200D01*
G01X92603Y249897D01*
G02X93590Y250267I987J-1131D01*
G02Y247263I0J-1502D01*
G02X92603Y247633I0J1501D01*
G01X92602D01*
Y247634D01*
G03X92472Y247682I-130J-152D01*
G01X92208D01*
G03X92078Y247634I0J-200D01*
G01X92077Y247633D01*
G02X90103I-987J1131D01*
G01X90102D01*
Y247634D01*
G03X89972Y247682I-130J-152D01*
G01X89708D01*
G03X89578Y247634I0J-200D01*
G01X89577Y247633D01*
G02X88590Y247263I-987J1131D01*
G02Y250267I0J1502D01*
G02X89577Y249897I0J-1501D01*
G01X89578D01*
Y249896D01*
G03X89708Y249848I130J152D01*
G01X89972D01*
G03X90102Y249896I0J200D01*
G01X90103Y249897D01*
G02X92077I987J-1131D01*
G37*
G36*
G01X194439D02*
X194440Y249896D01*
G03X194570Y249848I130J152D01*
G01X194834D01*
G03X194964Y249896I0J200D01*
G01X194965Y249897D01*
G02X195952Y250267I987J-1131D01*
G02Y247263I0J-1502D01*
G02X194965Y247633I0J1501D01*
G01X194964D01*
Y247634D01*
G03X194834Y247682I-130J-152D01*
G01X194570D01*
G03X194440Y247634I0J-200D01*
G01X194439Y247633D01*
G02X192465I-987J1131D01*
G01X192464D01*
Y247634D01*
G03X192334Y247682I-130J-152D01*
G01X192070D01*
G03X191940Y247634I0J-200D01*
G01X191939Y247633D01*
G02X190952Y247263I-987J1131D01*
G02Y250267I0J1502D01*
G02X191939Y249897I0J-1501D01*
G01X191940D01*
Y249896D01*
G03X192070Y249848I130J152D01*
G01X192334D01*
G03X192464Y249896I0J200D01*
G01X192465Y249897D01*
G02X194439I987J-1131D01*
G37*
G36*
G01X296801D02*
X296802Y249896D01*
G03X296932Y249848I130J152D01*
G01X297196D01*
G03X297326Y249896I0J200D01*
G01X297327Y249897D01*
G02X298314Y250267I987J-1131D01*
G02Y247263I0J-1502D01*
G02X297327Y247633I0J1501D01*
G01X297326D01*
Y247634D01*
G03X297196Y247682I-130J-152D01*
G01X296932D01*
G03X296802Y247634I0J-200D01*
G01X296801Y247633D01*
G02X294827I-987J1131D01*
G01X294826D01*
Y247634D01*
G03X294696Y247682I-130J-152D01*
G01X294432D01*
G03X294302Y247634I0J-200D01*
G01X294301Y247633D01*
G02X293314Y247263I-987J1131D01*
G02Y250267I0J1502D01*
G02X294301Y249897I0J-1501D01*
G01X294302D01*
Y249896D01*
G03X294432Y249848I130J152D01*
G01X294696D01*
G03X294826Y249896I0J200D01*
G01X294827Y249897D01*
G02X296801I987J-1131D01*
G37*
G36*
G01X399163D02*
X399164Y249896D01*
G03X399294Y249848I130J152D01*
G01X399558D01*
G03X399688Y249896I0J200D01*
G01X399689Y249897D01*
G02X400676Y250267I987J-1131D01*
G02Y247263I0J-1502D01*
G02X399689Y247633I0J1501D01*
G01X399688D01*
Y247634D01*
G03X399558Y247682I-130J-152D01*
G01X399294D01*
G03X399164Y247634I0J-200D01*
G01X399163Y247633D01*
G02X397189I-987J1131D01*
G01X397188D01*
Y247634D01*
G03X397058Y247682I-130J-152D01*
G01X396794D01*
G03X396664Y247634I0J-200D01*
G01X396663Y247633D01*
G02X395676Y247263I-987J1131D01*
G02Y250267I0J1502D01*
G02X396663Y249897I0J-1501D01*
G01X396664D01*
Y249896D01*
G03X396794Y249848I130J152D01*
G01X397058D01*
G03X397188Y249896I0J200D01*
G01X397189Y249897D01*
G02X399163I987J-1131D01*
G37*
G36*
G01X549164D02*
X549165Y249896D01*
G03X549295Y249848I130J152D01*
G01X549559D01*
G03X549689Y249896I0J200D01*
G01X549690Y249897D01*
G02X550677Y250267I987J-1131D01*
G02Y247263I0J-1502D01*
G02X549690Y247633I0J1501D01*
G01X549689D01*
Y247634D01*
G03X549559Y247682I-130J-152D01*
G01X549295D01*
G03X549165Y247634I0J-200D01*
G01X549164Y247633D01*
G02X547190I-987J1131D01*
G01X547189D01*
Y247634D01*
G03X547059Y247682I-130J-152D01*
G01X546795D01*
G03X546665Y247634I0J-200D01*
G01X546664Y247633D01*
G02X545677Y247263I-987J1131D01*
G02Y250267I0J1502D01*
G02X546664Y249897I0J-1501D01*
G01X546665D01*
Y249896D01*
G03X546795Y249848I130J152D01*
G01X547059D01*
G03X547189Y249896I0J200D01*
G01X547190Y249897D01*
G02X549164I987J-1131D01*
G37*
G36*
G01X651526D02*
X651527Y249896D01*
G03X651657Y249848I130J152D01*
G01X651921D01*
G03X652051Y249896I0J200D01*
G01X652052Y249897D01*
G02X653039Y250267I987J-1131D01*
G02Y247263I0J-1502D01*
G02X652052Y247633I0J1501D01*
G01X652051D01*
Y247634D01*
G03X651921Y247682I-130J-152D01*
G01X651657D01*
G03X651527Y247634I0J-200D01*
G01X651526Y247633D01*
G02X649552I-987J1131D01*
G01X649551D01*
Y247634D01*
G03X649421Y247682I-130J-152D01*
G01X649157D01*
G03X649027Y247634I0J-200D01*
G01X649026Y247633D01*
G02X648039Y247263I-987J1131D01*
G02Y250267I0J1502D01*
G02X649026Y249897I0J-1501D01*
G01X649027D01*
Y249896D01*
G03X649157Y249848I130J152D01*
G01X649421D01*
G03X649551Y249896I0J200D01*
G01X649552Y249897D01*
G02X651526I987J-1131D01*
G37*
G36*
G01X753888D02*
X753889Y249896D01*
G03X754019Y249848I130J152D01*
G01X754283D01*
G03X754413Y249896I0J200D01*
G01X754414Y249897D01*
G02X755401Y250267I987J-1131D01*
G02Y247263I0J-1502D01*
G02X754414Y247633I0J1501D01*
G01X754413D01*
Y247634D01*
G03X754283Y247682I-130J-152D01*
G01X754019D01*
G03X753889Y247634I0J-200D01*
G01X753888Y247633D01*
G02X751914I-987J1131D01*
G01X751913D01*
Y247634D01*
G03X751783Y247682I-130J-152D01*
G01X751519D01*
G03X751389Y247634I0J-200D01*
G01X751388Y247633D01*
G02X750401Y247263I-987J1131D01*
G02Y250267I0J1502D01*
G02X751388Y249897I0J-1501D01*
G01X751389D01*
Y249896D01*
G03X751519Y249848I130J152D01*
G01X751783D01*
G03X751913Y249896I0J200D01*
G01X751914Y249897D01*
G02X753888I987J-1131D01*
G37*
G36*
G01X856250D02*
X856251Y249896D01*
G03X856381Y249848I130J152D01*
G01X856645D01*
G03X856775Y249896I0J200D01*
G01X856776Y249897D01*
G02X857763Y250267I987J-1131D01*
G02Y247263I0J-1502D01*
G02X856776Y247633I0J1501D01*
G01X856775D01*
Y247634D01*
G03X856645Y247682I-130J-152D01*
G01X856381D01*
G03X856251Y247634I0J-200D01*
G01X856250Y247633D01*
G02X854276I-987J1131D01*
G01X854275D01*
Y247634D01*
G03X854145Y247682I-130J-152D01*
G01X853881D01*
G03X853751Y247634I0J-200D01*
G01X853750Y247633D01*
G02X852763Y247263I-987J1131D01*
G02Y250267I0J1502D01*
G02X853750Y249897I0J-1501D01*
G01X853751D01*
Y249896D01*
G03X853881Y249848I130J152D01*
G01X854145D01*
G03X854275Y249896I0J200D01*
G01X854276Y249897D01*
G02X856250I987J-1131D01*
G37*
G36*
G01X1006250D02*
X1006251Y249896D01*
G03X1006381Y249848I130J152D01*
G01X1006645D01*
G03X1006775Y249896I0J200D01*
G01X1006776Y249897D01*
G02X1007763Y250267I987J-1131D01*
G02Y247263I0J-1502D01*
G02X1006776Y247633I0J1501D01*
G01X1006775D01*
Y247634D01*
G03X1006645Y247682I-130J-152D01*
G01X1006381D01*
G03X1006251Y247634I0J-200D01*
G01X1006250Y247633D01*
G02X1004276I-987J1131D01*
G01X1004275D01*
Y247634D01*
G03X1004145Y247682I-130J-152D01*
G01X1003881D01*
G03X1003751Y247634I0J-200D01*
G01X1003750Y247633D01*
G02X1002763Y247263I-987J1131D01*
G02Y250267I0J1502D01*
G02X1003750Y249897I0J-1501D01*
G01X1003751D01*
Y249896D01*
G03X1003881Y249848I130J152D01*
G01X1004145D01*
G03X1004275Y249896I0J200D01*
G01X1004276Y249897D01*
G02X1006250I987J-1131D01*
G37*
G36*
G01X1108612D02*
X1108613Y249896D01*
G03X1108743Y249848I130J152D01*
G01X1109007D01*
G03X1109137Y249896I0J200D01*
G01X1109138Y249897D01*
G02X1110125Y250267I987J-1131D01*
G02Y247263I0J-1502D01*
G02X1109138Y247633I0J1501D01*
G01X1109137D01*
Y247634D01*
G03X1109007Y247682I-130J-152D01*
G01X1108743D01*
G03X1108613Y247634I0J-200D01*
G01X1108612Y247633D01*
G02X1106638I-987J1131D01*
G01X1106637D01*
Y247634D01*
G03X1106507Y247682I-130J-152D01*
G01X1106243D01*
G03X1106113Y247634I0J-200D01*
G01X1106112Y247633D01*
G02X1105125Y247263I-987J1131D01*
G02Y250267I0J1502D01*
G02X1106112Y249897I0J-1501D01*
G01X1106113D01*
Y249896D01*
G03X1106243Y249848I130J152D01*
G01X1106507D01*
G03X1106637Y249896I0J200D01*
G01X1106638Y249897D01*
G02X1108612I987J-1131D01*
G37*
G36*
G01X1210974D02*
X1210975Y249896D01*
G03X1211105Y249848I130J152D01*
G01X1211369D01*
G03X1211499Y249896I0J200D01*
G01X1211500Y249897D01*
G02X1212487Y250267I987J-1131D01*
G02Y247263I0J-1502D01*
G02X1211500Y247633I0J1501D01*
G01X1211499D01*
Y247634D01*
G03X1211369Y247682I-130J-152D01*
G01X1211105D01*
G03X1210975Y247634I0J-200D01*
G01X1210974Y247633D01*
G02X1209000I-987J1131D01*
G01X1208999D01*
Y247634D01*
G03X1208869Y247682I-130J-152D01*
G01X1208605D01*
G03X1208475Y247634I0J-200D01*
G01X1208474Y247633D01*
G02X1207487Y247263I-987J1131D01*
G02Y250267I0J1502D01*
G02X1208474Y249897I0J-1501D01*
G01X1208475D01*
Y249896D01*
G03X1208605Y249848I130J152D01*
G01X1208869D01*
G03X1208999Y249896I0J200D01*
G01X1209000Y249897D01*
G02X1210974I987J-1131D01*
G37*
G36*
G01X1313336D02*
X1313337Y249896D01*
G03X1313467Y249848I130J152D01*
G01X1313731D01*
G03X1313861Y249896I0J200D01*
G01X1313862Y249897D01*
G02X1314849Y250267I987J-1131D01*
G02Y247263I0J-1502D01*
G02X1313862Y247633I0J1501D01*
G01X1313861D01*
Y247634D01*
G03X1313731Y247682I-130J-152D01*
G01X1313467D01*
G03X1313337Y247634I0J-200D01*
G01X1313336Y247633D01*
G02X1311362I-987J1131D01*
G01X1311361D01*
Y247634D01*
G03X1311231Y247682I-130J-152D01*
G01X1310967D01*
G03X1310837Y247634I0J-200D01*
G01X1310836Y247633D01*
G02X1309849Y247263I-987J1131D01*
G02Y250267I0J1502D01*
G02X1310836Y249897I0J-1501D01*
G01X1310837D01*
Y249896D01*
G03X1310967Y249848I130J152D01*
G01X1311231D01*
G03X1311361Y249896I0J200D01*
G01X1311362Y249897D01*
G02X1313336I987J-1131D01*
G37*
G36*
G01X1463337D02*
X1463338Y249896D01*
G03X1463468Y249848I130J152D01*
G01X1463732D01*
G03X1463862Y249896I0J200D01*
G01X1463863Y249897D01*
G02X1464850Y250267I987J-1131D01*
G02Y247263I0J-1502D01*
G02X1463863Y247633I0J1501D01*
G01X1463862D01*
Y247634D01*
G03X1463732Y247682I-130J-152D01*
G01X1463468D01*
G03X1463338Y247634I0J-200D01*
G01X1463337Y247633D01*
G02X1461363I-987J1131D01*
G01X1461362D01*
Y247634D01*
G03X1461232Y247682I-130J-152D01*
G01X1460968D01*
G03X1460838Y247634I0J-200D01*
G01X1460837Y247633D01*
G02X1459850Y247263I-987J1131D01*
G02Y250267I0J1502D01*
G02X1460837Y249897I0J-1501D01*
G01X1460838D01*
Y249896D01*
G03X1460968Y249848I130J152D01*
G01X1461232D01*
G03X1461362Y249896I0J200D01*
G01X1461363Y249897D01*
G02X1463337I987J-1131D01*
G37*
G36*
G01X1565699D02*
X1565700Y249896D01*
G03X1565830Y249848I130J152D01*
G01X1566094D01*
G03X1566224Y249896I0J200D01*
G01X1566225Y249897D01*
G02X1567212Y250267I987J-1131D01*
G02Y247263I0J-1502D01*
G02X1566225Y247633I0J1501D01*
G01X1566224D01*
Y247634D01*
G03X1566094Y247682I-130J-152D01*
G01X1565830D01*
G03X1565700Y247634I0J-200D01*
G01X1565699Y247633D01*
G02X1563725I-987J1131D01*
G01X1563724D01*
Y247634D01*
G03X1563594Y247682I-130J-152D01*
G01X1563330D01*
G03X1563200Y247634I0J-200D01*
G01X1563199Y247633D01*
G02X1562212Y247263I-987J1131D01*
G02Y250267I0J1502D01*
G02X1563199Y249897I0J-1501D01*
G01X1563200D01*
Y249896D01*
G03X1563330Y249848I130J152D01*
G01X1563594D01*
G03X1563724Y249896I0J200D01*
G01X1563725Y249897D01*
G02X1565699I987J-1131D01*
G37*
G36*
G01X1668061D02*
X1668062Y249896D01*
G03X1668192Y249848I130J152D01*
G01X1668456D01*
G03X1668586Y249896I0J200D01*
G01X1668587Y249897D01*
G02X1669574Y250267I987J-1131D01*
G02Y247263I0J-1502D01*
G02X1668587Y247633I0J1501D01*
G01X1668586D01*
Y247634D01*
G03X1668456Y247682I-130J-152D01*
G01X1668192D01*
G03X1668062Y247634I0J-200D01*
G01X1668061Y247633D01*
G02X1666087I-987J1131D01*
G01X1666086D01*
Y247634D01*
G03X1665956Y247682I-130J-152D01*
G01X1665692D01*
G03X1665562Y247634I0J-200D01*
G01X1665561Y247633D01*
G02X1664574Y247263I-987J1131D01*
G02Y250267I0J1502D01*
G02X1665561Y249897I0J-1501D01*
G01X1665562D01*
Y249896D01*
G03X1665692Y249848I130J152D01*
G01X1665956D01*
G03X1666086Y249896I0J200D01*
G01X1666087Y249897D01*
G02X1668061I987J-1131D01*
G37*
G36*
G01X1770423D02*
X1770424Y249896D01*
G03X1770554Y249848I130J152D01*
G01X1770818D01*
G03X1770948Y249896I0J200D01*
G01X1770949Y249897D01*
G02X1771936Y250267I987J-1131D01*
G02Y247263I0J-1502D01*
G02X1770949Y247633I0J1501D01*
G01X1770948D01*
Y247634D01*
G03X1770818Y247682I-130J-152D01*
G01X1770554D01*
G03X1770424Y247634I0J-200D01*
G01X1770423Y247633D01*
G02X1768449I-987J1131D01*
G01X1768448D01*
Y247634D01*
G03X1768318Y247682I-130J-152D01*
G01X1768054D01*
G03X1767924Y247634I0J-200D01*
G01X1767923Y247633D01*
G02X1766936Y247263I-987J1131D01*
G02Y250267I0J1502D01*
G02X1767923Y249897I0J-1501D01*
G01X1767924D01*
Y249896D01*
G03X1768054Y249848I130J152D01*
G01X1768318D01*
G03X1768448Y249896I0J200D01*
G01X1768449Y249897D01*
G02X1770423I987J-1131D01*
G37*
G36*
G01X262786Y262678D02*
G02Y265682I0J1502D01*
G02X263773Y265312I0J-1501D01*
G01X263774D01*
Y265311D01*
G03X263904Y265263I130J152D01*
G01X264168D01*
G03X264298Y265311I0J200D01*
G01X264299Y265312D01*
G02X265286Y265682I987J-1131D01*
G02Y262678I0J-1502D01*
G02X264299Y263048I0J1501D01*
G01X264298D01*
Y263049D01*
G03X264168Y263097I-130J-152D01*
G01X263904D01*
G03X263774Y263049I0J-200D01*
G01X263773Y263048D01*
G02X262786Y262678I-987J1131D01*
G37*
G36*
G01X365148D02*
G02Y265682I0J1502D01*
G02X366135Y265312I0J-1501D01*
G01X366136D01*
Y265311D01*
G03X366266Y265263I130J152D01*
G01X366530D01*
G03X366660Y265311I0J200D01*
G01X366661Y265312D01*
G02X367648Y265682I987J-1131D01*
G02Y262678I0J-1502D01*
G02X366661Y263048I0J1501D01*
G01X366660D01*
Y263049D01*
G03X366530Y263097I-130J-152D01*
G01X366266D01*
G03X366136Y263049I0J-200D01*
G01X366135Y263048D01*
G02X365148Y262678I-987J1131D01*
G37*
G36*
G01X719873D02*
G02Y265682I0J1502D01*
G02X720860Y265312I0J-1501D01*
G01X720861D01*
Y265311D01*
G03X720991Y265263I130J152D01*
G01X721255D01*
G03X721385Y265311I0J200D01*
G01X721386Y265312D01*
G02X722373Y265682I987J-1131D01*
G02Y262678I0J-1502D01*
G02X721386Y263048I0J1501D01*
G01X721385D01*
Y263049D01*
G03X721255Y263097I-130J-152D01*
G01X720991D01*
G03X720861Y263049I0J-200D01*
G01X720860Y263048D01*
G02X719873Y262678I-987J1131D01*
G37*
G36*
G01X822235D02*
G02Y265682I0J1502D01*
G02X823222Y265312I0J-1501D01*
G01X823223D01*
Y265311D01*
G03X823353Y265263I130J152D01*
G01X823617D01*
G03X823747Y265311I0J200D01*
G01X823748Y265312D01*
G02X824735Y265682I987J-1131D01*
G02Y262678I0J-1502D01*
G02X823748Y263048I0J1501D01*
G01X823747D01*
Y263049D01*
G03X823617Y263097I-130J-152D01*
G01X823353D01*
G03X823223Y263049I0J-200D01*
G01X823222Y263048D01*
G02X822235Y262678I-987J1131D01*
G37*
G36*
G01X1176959D02*
G02Y265682I0J1502D01*
G02X1177946Y265312I0J-1501D01*
G01X1177947D01*
Y265311D01*
G03X1178077Y265263I130J152D01*
G01X1178341D01*
G03X1178471Y265311I0J200D01*
G01X1178472Y265312D01*
G02X1179459Y265682I987J-1131D01*
G02Y262678I0J-1502D01*
G02X1178472Y263048I0J1501D01*
G01X1178471D01*
Y263049D01*
G03X1178341Y263097I-130J-152D01*
G01X1178077D01*
G03X1177947Y263049I0J-200D01*
G01X1177946Y263048D01*
G02X1176959Y262678I-987J1131D01*
G37*
G36*
G01X1279321D02*
G02Y265682I0J1502D01*
G02X1280308Y265312I0J-1501D01*
G01X1280309D01*
Y265311D01*
G03X1280439Y265263I130J152D01*
G01X1280703D01*
G03X1280833Y265311I0J200D01*
G01X1280834Y265312D01*
G02X1281821Y265682I987J-1131D01*
G02Y262678I0J-1502D01*
G02X1280834Y263048I0J1501D01*
G01X1280833D01*
Y263049D01*
G03X1280703Y263097I-130J-152D01*
G01X1280439D01*
G03X1280309Y263049I0J-200D01*
G01X1280308Y263048D01*
G02X1279321Y262678I-987J1131D01*
G37*
G36*
G01X1634046D02*
G02Y265682I0J1502D01*
G02X1635033Y265312I0J-1501D01*
G01X1635034D01*
Y265311D01*
G03X1635164Y265263I130J152D01*
G01X1635428D01*
G03X1635558Y265311I0J200D01*
G01X1635559Y265312D01*
G02X1636546Y265682I987J-1131D01*
G02Y262678I0J-1502D01*
G02X1635559Y263048I0J1501D01*
G01X1635558D01*
Y263049D01*
G03X1635428Y263097I-130J-152D01*
G01X1635164D01*
G03X1635034Y263049I0J-200D01*
G01X1635033Y263048D01*
G02X1634046Y262678I-987J1131D01*
G37*
G36*
G01X1736408D02*
G02Y265682I0J1502D01*
G02X1737395Y265312I0J-1501D01*
G01X1737396D01*
Y265311D01*
G03X1737526Y265263I130J152D01*
G01X1737790D01*
G03X1737920Y265311I0J200D01*
G01X1737921Y265312D01*
G02X1738908Y265682I987J-1131D01*
G02Y262678I0J-1502D01*
G02X1737921Y263048I0J1501D01*
G01X1737920D01*
Y263049D01*
G03X1737790Y263097I-130J-152D01*
G01X1737526D01*
G03X1737396Y263049I0J-200D01*
G01X1737395Y263048D01*
G02X1736408Y262678I-987J1131D01*
G37*
G36*
G01X97747Y264395D02*
G02Y267399I0J1502D01*
G02X98734Y267029I0J-1501D01*
G01X98735D01*
Y267028D01*
G03X98865Y266980I130J152D01*
G01X99129D01*
G03X99259Y267028I0J200D01*
G01X99260Y267029D01*
G02X100247Y267399I987J-1131D01*
G02Y264395I0J-1502D01*
G02X99260Y264765I0J1501D01*
G01X99259D01*
Y264766D01*
G03X99129Y264814I-130J-152D01*
G01X98865D01*
G03X98735Y264766I0J-200D01*
G01X98734Y264765D01*
G02X97747Y264395I-987J1131D01*
G37*
G36*
G01X200109D02*
G02Y267399I0J1502D01*
G02X201096Y267029I0J-1501D01*
G01X201097D01*
Y267028D01*
G03X201227Y266980I130J152D01*
G01X201491D01*
G03X201621Y267028I0J200D01*
G01X201622Y267029D01*
G02X202609Y267399I987J-1131D01*
G02Y264395I0J-1502D01*
G02X201622Y264765I0J1501D01*
G01X201621D01*
Y264766D01*
G03X201491Y264814I-130J-152D01*
G01X201227D01*
G03X201097Y264766I0J-200D01*
G01X201096Y264765D01*
G02X200109Y264395I-987J1131D01*
G37*
G36*
G01X302471D02*
G02Y267399I0J1502D01*
G02X303458Y267029I0J-1501D01*
G01X303459D01*
Y267028D01*
G03X303589Y266980I130J152D01*
G01X303853D01*
G03X303983Y267028I0J200D01*
G01X303984Y267029D01*
G02X304971Y267399I987J-1131D01*
G02Y264395I0J-1502D01*
G02X303984Y264765I0J1501D01*
G01X303983D01*
Y264766D01*
G03X303853Y264814I-130J-152D01*
G01X303589D01*
G03X303459Y264766I0J-200D01*
G01X303458Y264765D01*
G02X302471Y264395I-987J1131D01*
G37*
G36*
G01X404833D02*
G02Y267399I0J1502D01*
G02X405820Y267029I0J-1501D01*
G01X405821D01*
Y267028D01*
G03X405951Y266980I130J152D01*
G01X406215D01*
G03X406345Y267028I0J200D01*
G01X406346Y267029D01*
G02X407333Y267399I987J-1131D01*
G02Y264395I0J-1502D01*
G02X406346Y264765I0J1501D01*
G01X406345D01*
Y264766D01*
G03X406215Y264814I-130J-152D01*
G01X405951D01*
G03X405821Y264766I0J-200D01*
G01X405820Y264765D01*
G02X404833Y264395I-987J1131D01*
G37*
G36*
G01X554834D02*
G02Y267399I0J1502D01*
G02X555821Y267029I0J-1501D01*
G01X555822D01*
Y267028D01*
G03X555952Y266980I130J152D01*
G01X556216D01*
G03X556346Y267028I0J200D01*
G01X556347Y267029D01*
G02X557334Y267399I987J-1131D01*
G02Y264395I0J-1502D01*
G02X556347Y264765I0J1501D01*
G01X556346D01*
Y264766D01*
G03X556216Y264814I-130J-152D01*
G01X555952D01*
G03X555822Y264766I0J-200D01*
G01X555821Y264765D01*
G02X554834Y264395I-987J1131D01*
G37*
G36*
G01X657196D02*
G02Y267399I0J1502D01*
G02X658183Y267029I0J-1501D01*
G01X658184D01*
Y267028D01*
G03X658314Y266980I130J152D01*
G01X658578D01*
G03X658708Y267028I0J200D01*
G01X658709Y267029D01*
G02X659696Y267399I987J-1131D01*
G02Y264395I0J-1502D01*
G02X658709Y264765I0J1501D01*
G01X658708D01*
Y264766D01*
G03X658578Y264814I-130J-152D01*
G01X658314D01*
G03X658184Y264766I0J-200D01*
G01X658183Y264765D01*
G02X657196Y264395I-987J1131D01*
G37*
G36*
G01X759558D02*
G02Y267399I0J1502D01*
G02X760545Y267029I0J-1501D01*
G01X760546D01*
Y267028D01*
G03X760676Y266980I130J152D01*
G01X760940D01*
G03X761070Y267028I0J200D01*
G01X761071Y267029D01*
G02X762058Y267399I987J-1131D01*
G02Y264395I0J-1502D01*
G02X761071Y264765I0J1501D01*
G01X761070D01*
Y264766D01*
G03X760940Y264814I-130J-152D01*
G01X760676D01*
G03X760546Y264766I0J-200D01*
G01X760545Y264765D01*
G02X759558Y264395I-987J1131D01*
G37*
G36*
G01X861920D02*
G02Y267399I0J1502D01*
G02X862907Y267029I0J-1501D01*
G01X862908D01*
Y267028D01*
G03X863038Y266980I130J152D01*
G01X863302D01*
G03X863432Y267028I0J200D01*
G01X863433Y267029D01*
G02X864420Y267399I987J-1131D01*
G02Y264395I0J-1502D01*
G02X863433Y264765I0J1501D01*
G01X863432D01*
Y264766D01*
G03X863302Y264814I-130J-152D01*
G01X863038D01*
G03X862908Y264766I0J-200D01*
G01X862907Y264765D01*
G02X861920Y264395I-987J1131D01*
G37*
G36*
G01X1011920D02*
G02Y267399I0J1502D01*
G02X1012907Y267029I0J-1501D01*
G01X1012908D01*
Y267028D01*
G03X1013038Y266980I130J152D01*
G01X1013302D01*
G03X1013432Y267028I0J200D01*
G01X1013433Y267029D01*
G02X1014420Y267399I987J-1131D01*
G02Y264395I0J-1502D01*
G02X1013433Y264765I0J1501D01*
G01X1013432D01*
Y264766D01*
G03X1013302Y264814I-130J-152D01*
G01X1013038D01*
G03X1012908Y264766I0J-200D01*
G01X1012907Y264765D01*
G02X1011920Y264395I-987J1131D01*
G37*
G36*
G01X1114282D02*
G02Y267399I0J1502D01*
G02X1115269Y267029I0J-1501D01*
G01X1115270D01*
Y267028D01*
G03X1115400Y266980I130J152D01*
G01X1115664D01*
G03X1115794Y267028I0J200D01*
G01X1115795Y267029D01*
G02X1116782Y267399I987J-1131D01*
G02Y264395I0J-1502D01*
G02X1115795Y264765I0J1501D01*
G01X1115794D01*
Y264766D01*
G03X1115664Y264814I-130J-152D01*
G01X1115400D01*
G03X1115270Y264766I0J-200D01*
G01X1115269Y264765D01*
G02X1114282Y264395I-987J1131D01*
G37*
G36*
G01X1216644D02*
G02Y267399I0J1502D01*
G02X1217631Y267029I0J-1501D01*
G01X1217632D01*
Y267028D01*
G03X1217762Y266980I130J152D01*
G01X1218026D01*
G03X1218156Y267028I0J200D01*
G01X1218157Y267029D01*
G02X1219144Y267399I987J-1131D01*
G02Y264395I0J-1502D01*
G02X1218157Y264765I0J1501D01*
G01X1218156D01*
Y264766D01*
G03X1218026Y264814I-130J-152D01*
G01X1217762D01*
G03X1217632Y264766I0J-200D01*
G01X1217631Y264765D01*
G02X1216644Y264395I-987J1131D01*
G37*
G36*
G01X1319006D02*
G02Y267399I0J1502D01*
G02X1319993Y267029I0J-1501D01*
G01X1319994D01*
Y267028D01*
G03X1320124Y266980I130J152D01*
G01X1320388D01*
G03X1320518Y267028I0J200D01*
G01X1320519Y267029D01*
G02X1321506Y267399I987J-1131D01*
G02Y264395I0J-1502D01*
G02X1320519Y264765I0J1501D01*
G01X1320518D01*
Y264766D01*
G03X1320388Y264814I-130J-152D01*
G01X1320124D01*
G03X1319994Y264766I0J-200D01*
G01X1319993Y264765D01*
G02X1319006Y264395I-987J1131D01*
G37*
G36*
G01X1469007D02*
G02Y267399I0J1502D01*
G02X1469994Y267029I0J-1501D01*
G01X1469995D01*
Y267028D01*
G03X1470125Y266980I130J152D01*
G01X1470389D01*
G03X1470519Y267028I0J200D01*
G01X1470520Y267029D01*
G02X1471507Y267399I987J-1131D01*
G02Y264395I0J-1502D01*
G02X1470520Y264765I0J1501D01*
G01X1470519D01*
Y264766D01*
G03X1470389Y264814I-130J-152D01*
G01X1470125D01*
G03X1469995Y264766I0J-200D01*
G01X1469994Y264765D01*
G02X1469007Y264395I-987J1131D01*
G37*
G36*
G01X1571369D02*
G02Y267399I0J1502D01*
G02X1572356Y267029I0J-1501D01*
G01X1572357D01*
Y267028D01*
G03X1572487Y266980I130J152D01*
G01X1572751D01*
G03X1572881Y267028I0J200D01*
G01X1572882Y267029D01*
G02X1573869Y267399I987J-1131D01*
G02Y264395I0J-1502D01*
G02X1572882Y264765I0J1501D01*
G01X1572881D01*
Y264766D01*
G03X1572751Y264814I-130J-152D01*
G01X1572487D01*
G03X1572357Y264766I0J-200D01*
G01X1572356Y264765D01*
G02X1571369Y264395I-987J1131D01*
G37*
G36*
G01X1673731D02*
G02Y267399I0J1502D01*
G02X1674718Y267029I0J-1501D01*
G01X1674719D01*
Y267028D01*
G03X1674849Y266980I130J152D01*
G01X1675113D01*
G03X1675243Y267028I0J200D01*
G01X1675244Y267029D01*
G02X1676231Y267399I987J-1131D01*
G02Y264395I0J-1502D01*
G02X1675244Y264765I0J1501D01*
G01X1675243D01*
Y264766D01*
G03X1675113Y264814I-130J-152D01*
G01X1674849D01*
G03X1674719Y264766I0J-200D01*
G01X1674718Y264765D01*
G02X1673731Y264395I-987J1131D01*
G37*
G36*
G01X1776093D02*
G02Y267399I0J1502D01*
G02X1777080Y267029I0J-1501D01*
G01X1777081D01*
Y267028D01*
G03X1777211Y266980I130J152D01*
G01X1777475D01*
G03X1777605Y267028I0J200D01*
G01X1777606Y267029D01*
G02X1778593Y267399I987J-1131D01*
G02Y264395I0J-1502D01*
G02X1777606Y264765I0J1501D01*
G01X1777605D01*
Y264766D01*
G03X1777475Y264814I-130J-152D01*
G01X1777211D01*
G03X1777081Y264766I0J-200D01*
G01X1777080Y264765D01*
G02X1776093Y264395I-987J1131D01*
G37*
G36*
G01X68209Y270978D02*
X68503D01*
G03X68650Y271043I-1J200D01*
G02X69756Y271528I1106J-1019D01*
G02X70743Y271158I0J-1501D01*
G01X70744D01*
Y271157D01*
G03X70874Y271109I130J152D01*
G01X71138D01*
G03X71268Y271157I0J200D01*
G01X71269Y271158D01*
G02X72256Y271528I987J-1131D01*
G02X73758Y270026I0J-1502D01*
G02X73388Y269039I-1501J0D01*
G01Y269038D01*
X73387D01*
G03X73339Y268908I152J-130D01*
G01Y268644D01*
G03X73387Y268514I200J0D01*
G01X73388Y268513D01*
G02X73758Y267526I-1131J-987D01*
G02X72256Y266024I-1502J0D01*
G02X71269Y266394I0J1501D01*
G01X71268D01*
Y266395D01*
G03X71138Y266443I-130J-152D01*
G01X70874D01*
G03X70744Y266395I0J-200D01*
G01X70743Y266394D01*
G02X69756Y266024I-987J1131D01*
G02X68650Y266509I0J1504D01*
G03X68503Y266574I-148J-135D01*
G01X68209D01*
G03X68062Y266509I1J-200D01*
G02X66956Y266024I-1106J1019D01*
G02X65454Y267526I0J1502D01*
G02X65824Y268513I1501J0D01*
G01Y268514D01*
X65825D01*
G03X65873Y268644I-152J130D01*
G01Y268908D01*
G03X65825Y269038I-200J0D01*
G01X65824Y269039D01*
G02X65454Y270026I1131J987D01*
G02X66956Y271528I1502J0D01*
G02X68062Y271043I0J-1504D01*
G03X68209Y270978I148J135D01*
G37*
G36*
G01X170571D02*
X170865D01*
G03X171012Y271043I-1J200D01*
G02X172118Y271528I1106J-1019D01*
G02X173105Y271158I0J-1501D01*
G01X173106D01*
Y271157D01*
G03X173236Y271109I130J152D01*
G01X173500D01*
G03X173630Y271157I0J200D01*
G01X173631Y271158D01*
G02X174618Y271528I987J-1131D01*
G02X176120Y270026I0J-1502D01*
G02X175750Y269039I-1501J0D01*
G01Y269038D01*
X175749D01*
G03X175701Y268908I152J-130D01*
G01Y268644D01*
G03X175749Y268514I200J0D01*
G01X175750Y268513D01*
G02X176120Y267526I-1131J-987D01*
G02X174618Y266024I-1502J0D01*
G02X173631Y266394I0J1501D01*
G01X173630D01*
Y266395D01*
G03X173500Y266443I-130J-152D01*
G01X173236D01*
G03X173106Y266395I0J-200D01*
G01X173105Y266394D01*
G02X172118Y266024I-987J1131D01*
G02X171012Y266509I0J1504D01*
G03X170865Y266574I-148J-135D01*
G01X170571D01*
G03X170424Y266509I1J-200D01*
G02X169318Y266024I-1106J1019D01*
G02X167816Y267526I0J1502D01*
G02X168186Y268513I1501J0D01*
G01Y268514D01*
X168187D01*
G03X168235Y268644I-152J130D01*
G01Y268908D01*
G03X168187Y269038I-200J0D01*
G01X168186Y269039D01*
G02X167816Y270026I1131J987D01*
G02X169318Y271528I1502J0D01*
G02X170424Y271043I0J-1504D01*
G03X170571Y270978I148J135D01*
G37*
G36*
G01X272933D02*
X273227D01*
G03X273374Y271043I-1J200D01*
G02X274480Y271528I1106J-1019D01*
G02X275467Y271158I0J-1501D01*
G01X275468D01*
Y271157D01*
G03X275598Y271109I130J152D01*
G01X275862D01*
G03X275992Y271157I0J200D01*
G01X275993Y271158D01*
G02X276980Y271528I987J-1131D01*
G02X278482Y270026I0J-1502D01*
G02X278112Y269039I-1501J0D01*
G01Y269038D01*
X278111D01*
G03X278063Y268908I152J-130D01*
G01Y268644D01*
G03X278111Y268514I200J0D01*
G01X278112Y268513D01*
G02X278482Y267526I-1131J-987D01*
G02X276980Y266024I-1502J0D01*
G02X275993Y266394I0J1501D01*
G01X275992D01*
Y266395D01*
G03X275862Y266443I-130J-152D01*
G01X275598D01*
G03X275468Y266395I0J-200D01*
G01X275467Y266394D01*
G02X274480Y266024I-987J1131D01*
G02X273374Y266509I0J1504D01*
G03X273227Y266574I-148J-135D01*
G01X272933D01*
G03X272786Y266509I1J-200D01*
G02X271680Y266024I-1106J1019D01*
G02X270178Y267526I0J1502D01*
G02X270548Y268513I1501J0D01*
G01Y268514D01*
X270549D01*
G03X270597Y268644I-152J130D01*
G01Y268908D01*
G03X270549Y269038I-200J0D01*
G01X270548Y269039D01*
G02X270178Y270026I1131J987D01*
G02X271680Y271528I1502J0D01*
G02X272786Y271043I0J-1504D01*
G03X272933Y270978I148J135D01*
G37*
G36*
G01X375295D02*
X375589D01*
G03X375736Y271043I-1J200D01*
G02X376842Y271528I1106J-1019D01*
G02X377829Y271158I0J-1501D01*
G01X377830D01*
Y271157D01*
G03X377960Y271109I130J152D01*
G01X378224D01*
G03X378354Y271157I0J200D01*
G01X378355Y271158D01*
G02X379342Y271528I987J-1131D01*
G02X380844Y270026I0J-1502D01*
G02X380474Y269039I-1501J0D01*
G01Y269038D01*
X380473D01*
G03X380425Y268908I152J-130D01*
G01Y268644D01*
G03X380473Y268514I200J0D01*
G01X380474Y268513D01*
G02X380844Y267526I-1131J-987D01*
G02X379342Y266024I-1502J0D01*
G02X378355Y266394I0J1501D01*
G01X378354D01*
Y266395D01*
G03X378224Y266443I-130J-152D01*
G01X377960D01*
G03X377830Y266395I0J-200D01*
G01X377829Y266394D01*
G02X376842Y266024I-987J1131D01*
G02X375736Y266509I0J1504D01*
G03X375589Y266574I-148J-135D01*
G01X375295D01*
G03X375148Y266509I1J-200D01*
G02X374042Y266024I-1106J1019D01*
G02X372540Y267526I0J1502D01*
G02X372910Y268513I1501J0D01*
G01Y268514D01*
X372911D01*
G03X372959Y268644I-152J130D01*
G01Y268908D01*
G03X372911Y269038I-200J0D01*
G01X372910Y269039D01*
G02X372540Y270026I1131J987D01*
G02X374042Y271528I1502J0D01*
G02X375148Y271043I0J-1504D01*
G03X375295Y270978I148J135D01*
G37*
G36*
G01X525296D02*
X525590D01*
G03X525737Y271043I-1J200D01*
G02X526843Y271528I1106J-1019D01*
G02X527830Y271158I0J-1501D01*
G01X527831D01*
Y271157D01*
G03X527961Y271109I130J152D01*
G01X528225D01*
G03X528355Y271157I0J200D01*
G01X528356Y271158D01*
G02X529343Y271528I987J-1131D01*
G02X530845Y270026I0J-1502D01*
G02X530475Y269039I-1501J0D01*
G01Y269038D01*
X530474D01*
G03X530426Y268908I152J-130D01*
G01Y268644D01*
G03X530474Y268514I200J0D01*
G01X530475Y268513D01*
G02X530845Y267526I-1131J-987D01*
G02X529343Y266024I-1502J0D01*
G02X528356Y266394I0J1501D01*
G01X528355D01*
Y266395D01*
G03X528225Y266443I-130J-152D01*
G01X527961D01*
G03X527831Y266395I0J-200D01*
G01X527830Y266394D01*
G02X526843Y266024I-987J1131D01*
G02X525737Y266509I0J1504D01*
G03X525590Y266574I-148J-135D01*
G01X525296D01*
G03X525149Y266509I1J-200D01*
G02X524043Y266024I-1106J1019D01*
G02X522541Y267526I0J1502D01*
G02X522911Y268513I1501J0D01*
G01Y268514D01*
X522912D01*
G03X522960Y268644I-152J130D01*
G01Y268908D01*
G03X522912Y269038I-200J0D01*
G01X522911Y269039D01*
G02X522541Y270026I1131J987D01*
G02X524043Y271528I1502J0D01*
G02X525149Y271043I0J-1504D01*
G03X525296Y270978I148J135D01*
G37*
G36*
G01X627658D02*
X627952D01*
G03X628099Y271043I-1J200D01*
G02X629205Y271528I1106J-1019D01*
G02X630192Y271158I0J-1501D01*
G01X630193D01*
Y271157D01*
G03X630323Y271109I130J152D01*
G01X630587D01*
G03X630717Y271157I0J200D01*
G01X630718Y271158D01*
G02X631705Y271528I987J-1131D01*
G02X633207Y270026I0J-1502D01*
G02X632837Y269039I-1501J0D01*
G01Y269038D01*
X632836D01*
G03X632788Y268908I152J-130D01*
G01Y268644D01*
G03X632836Y268514I200J0D01*
G01X632837Y268513D01*
G02X633207Y267526I-1131J-987D01*
G02X631705Y266024I-1502J0D01*
G02X630718Y266394I0J1501D01*
G01X630717D01*
Y266395D01*
G03X630587Y266443I-130J-152D01*
G01X630323D01*
G03X630193Y266395I0J-200D01*
G01X630192Y266394D01*
G02X629205Y266024I-987J1131D01*
G02X628099Y266509I0J1504D01*
G03X627952Y266574I-148J-135D01*
G01X627658D01*
G03X627511Y266509I1J-200D01*
G02X626405Y266024I-1106J1019D01*
G02X624903Y267526I0J1502D01*
G02X625273Y268513I1501J0D01*
G01Y268514D01*
X625274D01*
G03X625322Y268644I-152J130D01*
G01Y268908D01*
G03X625274Y269038I-200J0D01*
G01X625273Y269039D01*
G02X624903Y270026I1131J987D01*
G02X626405Y271528I1502J0D01*
G02X627511Y271043I0J-1504D01*
G03X627658Y270978I148J135D01*
G37*
G36*
G01X730020D02*
X730314D01*
G03X730461Y271043I-1J200D01*
G02X731567Y271528I1106J-1019D01*
G02X732554Y271158I0J-1501D01*
G01X732555D01*
Y271157D01*
G03X732685Y271109I130J152D01*
G01X732949D01*
G03X733079Y271157I0J200D01*
G01X733080Y271158D01*
G02X734067Y271528I987J-1131D01*
G02X735569Y270026I0J-1502D01*
G02X735199Y269039I-1501J0D01*
G01Y269038D01*
X735198D01*
G03X735150Y268908I152J-130D01*
G01Y268644D01*
G03X735198Y268514I200J0D01*
G01X735199Y268513D01*
G02X735569Y267526I-1131J-987D01*
G02X734067Y266024I-1502J0D01*
G02X733080Y266394I0J1501D01*
G01X733079D01*
Y266395D01*
G03X732949Y266443I-130J-152D01*
G01X732685D01*
G03X732555Y266395I0J-200D01*
G01X732554Y266394D01*
G02X731567Y266024I-987J1131D01*
G02X730461Y266509I0J1504D01*
G03X730314Y266574I-148J-135D01*
G01X730020D01*
G03X729873Y266509I1J-200D01*
G02X728767Y266024I-1106J1019D01*
G02X727265Y267526I0J1502D01*
G02X727635Y268513I1501J0D01*
G01Y268514D01*
X727636D01*
G03X727684Y268644I-152J130D01*
G01Y268908D01*
G03X727636Y269038I-200J0D01*
G01X727635Y269039D01*
G02X727265Y270026I1131J987D01*
G02X728767Y271528I1502J0D01*
G02X729873Y271043I0J-1504D01*
G03X730020Y270978I148J135D01*
G37*
G36*
G01X832382D02*
X832676D01*
G03X832823Y271043I-1J200D01*
G02X833929Y271528I1106J-1019D01*
G02X834916Y271158I0J-1501D01*
G01X834917D01*
Y271157D01*
G03X835047Y271109I130J152D01*
G01X835311D01*
G03X835441Y271157I0J200D01*
G01X835442Y271158D01*
G02X836429Y271528I987J-1131D01*
G02X837931Y270026I0J-1502D01*
G02X837561Y269039I-1501J0D01*
G01Y269038D01*
X837560D01*
G03X837512Y268908I152J-130D01*
G01Y268644D01*
G03X837560Y268514I200J0D01*
G01X837561Y268513D01*
G02X837931Y267526I-1131J-987D01*
G02X836429Y266024I-1502J0D01*
G02X835442Y266394I0J1501D01*
G01X835441D01*
Y266395D01*
G03X835311Y266443I-130J-152D01*
G01X835047D01*
G03X834917Y266395I0J-200D01*
G01X834916Y266394D01*
G02X833929Y266024I-987J1131D01*
G02X832823Y266509I0J1504D01*
G03X832676Y266574I-148J-135D01*
G01X832382D01*
G03X832235Y266509I1J-200D01*
G02X831129Y266024I-1106J1019D01*
G02X829627Y267526I0J1502D01*
G02X829997Y268513I1501J0D01*
G01Y268514D01*
X829998D01*
G03X830046Y268644I-152J130D01*
G01Y268908D01*
G03X829998Y269038I-200J0D01*
G01X829997Y269039D01*
G02X829627Y270026I1131J987D01*
G02X831129Y271528I1502J0D01*
G02X832235Y271043I0J-1504D01*
G03X832382Y270978I148J135D01*
G37*
G36*
G01X982382D02*
X982676D01*
G03X982823Y271043I-1J200D01*
G02X983929Y271528I1106J-1019D01*
G02X984916Y271158I0J-1501D01*
G01X984917D01*
Y271157D01*
G03X985047Y271109I130J152D01*
G01X985311D01*
G03X985441Y271157I0J200D01*
G01X985442Y271158D01*
G02X986429Y271528I987J-1131D01*
G02X987931Y270026I0J-1502D01*
G02X987561Y269039I-1501J0D01*
G01Y269038D01*
X987560D01*
G03X987512Y268908I152J-130D01*
G01Y268644D01*
G03X987560Y268514I200J0D01*
G01X987561Y268513D01*
G02X987931Y267526I-1131J-987D01*
G02X986429Y266024I-1502J0D01*
G02X985442Y266394I0J1501D01*
G01X985441D01*
Y266395D01*
G03X985311Y266443I-130J-152D01*
G01X985047D01*
G03X984917Y266395I0J-200D01*
G01X984916Y266394D01*
G02X983929Y266024I-987J1131D01*
G02X982823Y266509I0J1504D01*
G03X982676Y266574I-148J-135D01*
G01X982382D01*
G03X982235Y266509I1J-200D01*
G02X981129Y266024I-1106J1019D01*
G02X979627Y267526I0J1502D01*
G02X979997Y268513I1501J0D01*
G01Y268514D01*
X979998D01*
G03X980046Y268644I-152J130D01*
G01Y268908D01*
G03X979998Y269038I-200J0D01*
G01X979997Y269039D01*
G02X979627Y270026I1131J987D01*
G02X981129Y271528I1502J0D01*
G02X982235Y271043I0J-1504D01*
G03X982382Y270978I148J135D01*
G37*
G36*
G01X1084744D02*
X1085038D01*
G03X1085185Y271043I-1J200D01*
G02X1086291Y271528I1106J-1019D01*
G02X1087278Y271158I0J-1501D01*
G01X1087279D01*
Y271157D01*
G03X1087409Y271109I130J152D01*
G01X1087673D01*
G03X1087803Y271157I0J200D01*
G01X1087804Y271158D01*
G02X1088791Y271528I987J-1131D01*
G02X1090293Y270026I0J-1502D01*
G02X1089923Y269039I-1501J0D01*
G01Y269038D01*
X1089922D01*
G03X1089874Y268908I152J-130D01*
G01Y268644D01*
G03X1089922Y268514I200J0D01*
G01X1089923Y268513D01*
G02X1090293Y267526I-1131J-987D01*
G02X1088791Y266024I-1502J0D01*
G02X1087804Y266394I0J1501D01*
G01X1087803D01*
Y266395D01*
G03X1087673Y266443I-130J-152D01*
G01X1087409D01*
G03X1087279Y266395I0J-200D01*
G01X1087278Y266394D01*
G02X1086291Y266024I-987J1131D01*
G02X1085185Y266509I0J1504D01*
G03X1085038Y266574I-148J-135D01*
G01X1084744D01*
G03X1084597Y266509I1J-200D01*
G02X1083491Y266024I-1106J1019D01*
G02X1081989Y267526I0J1502D01*
G02X1082359Y268513I1501J0D01*
G01Y268514D01*
X1082360D01*
G03X1082408Y268644I-152J130D01*
G01Y268908D01*
G03X1082360Y269038I-200J0D01*
G01X1082359Y269039D01*
G02X1081989Y270026I1131J987D01*
G02X1083491Y271528I1502J0D01*
G02X1084597Y271043I0J-1504D01*
G03X1084744Y270978I148J135D01*
G37*
G36*
G01X1187106D02*
X1187400D01*
G03X1187547Y271043I-1J200D01*
G02X1188653Y271528I1106J-1019D01*
G02X1189640Y271158I0J-1501D01*
G01X1189641D01*
Y271157D01*
G03X1189771Y271109I130J152D01*
G01X1190035D01*
G03X1190165Y271157I0J200D01*
G01X1190166Y271158D01*
G02X1191153Y271528I987J-1131D01*
G02X1192655Y270026I0J-1502D01*
G02X1192285Y269039I-1501J0D01*
G01Y269038D01*
X1192284D01*
G03X1192236Y268908I152J-130D01*
G01Y268644D01*
G03X1192284Y268514I200J0D01*
G01X1192285Y268513D01*
G02X1192655Y267526I-1131J-987D01*
G02X1191153Y266024I-1502J0D01*
G02X1190166Y266394I0J1501D01*
G01X1190165D01*
Y266395D01*
G03X1190035Y266443I-130J-152D01*
G01X1189771D01*
G03X1189641Y266395I0J-200D01*
G01X1189640Y266394D01*
G02X1188653Y266024I-987J1131D01*
G02X1187547Y266509I0J1504D01*
G03X1187400Y266574I-148J-135D01*
G01X1187106D01*
G03X1186959Y266509I1J-200D01*
G02X1185853Y266024I-1106J1019D01*
G02X1184351Y267526I0J1502D01*
G02X1184721Y268513I1501J0D01*
G01Y268514D01*
X1184722D01*
G03X1184770Y268644I-152J130D01*
G01Y268908D01*
G03X1184722Y269038I-200J0D01*
G01X1184721Y269039D01*
G02X1184351Y270026I1131J987D01*
G02X1185853Y271528I1502J0D01*
G02X1186959Y271043I0J-1504D01*
G03X1187106Y270978I148J135D01*
G37*
G36*
G01X1289468D02*
X1289762D01*
G03X1289909Y271043I-1J200D01*
G02X1291015Y271528I1106J-1019D01*
G02X1292002Y271158I0J-1501D01*
G01X1292003D01*
Y271157D01*
G03X1292133Y271109I130J152D01*
G01X1292397D01*
G03X1292527Y271157I0J200D01*
G01X1292528Y271158D01*
G02X1293515Y271528I987J-1131D01*
G02X1295017Y270026I0J-1502D01*
G02X1294647Y269039I-1501J0D01*
G01Y269038D01*
X1294646D01*
G03X1294598Y268908I152J-130D01*
G01Y268644D01*
G03X1294646Y268514I200J0D01*
G01X1294647Y268513D01*
G02X1295017Y267526I-1131J-987D01*
G02X1293515Y266024I-1502J0D01*
G02X1292528Y266394I0J1501D01*
G01X1292527D01*
Y266395D01*
G03X1292397Y266443I-130J-152D01*
G01X1292133D01*
G03X1292003Y266395I0J-200D01*
G01X1292002Y266394D01*
G02X1291015Y266024I-987J1131D01*
G02X1289909Y266509I0J1504D01*
G03X1289762Y266574I-148J-135D01*
G01X1289468D01*
G03X1289321Y266509I1J-200D01*
G02X1288215Y266024I-1106J1019D01*
G02X1286713Y267526I0J1502D01*
G02X1287083Y268513I1501J0D01*
G01Y268514D01*
X1287084D01*
G03X1287132Y268644I-152J130D01*
G01Y268908D01*
G03X1287084Y269038I-200J0D01*
G01X1287083Y269039D01*
G02X1286713Y270026I1131J987D01*
G02X1288215Y271528I1502J0D01*
G02X1289321Y271043I0J-1504D01*
G03X1289468Y270978I148J135D01*
G37*
G36*
G01X1439469D02*
X1439763D01*
G03X1439910Y271043I-1J200D01*
G02X1441016Y271528I1106J-1019D01*
G02X1442003Y271158I0J-1501D01*
G01X1442004D01*
Y271157D01*
G03X1442134Y271109I130J152D01*
G01X1442398D01*
G03X1442528Y271157I0J200D01*
G01X1442529Y271158D01*
G02X1443516Y271528I987J-1131D01*
G02X1445018Y270026I0J-1502D01*
G02X1444648Y269039I-1501J0D01*
G01Y269038D01*
X1444647D01*
G03X1444599Y268908I152J-130D01*
G01Y268644D01*
G03X1444647Y268514I200J0D01*
G01X1444648Y268513D01*
G02X1445018Y267526I-1131J-987D01*
G02X1443516Y266024I-1502J0D01*
G02X1442529Y266394I0J1501D01*
G01X1442528D01*
Y266395D01*
G03X1442398Y266443I-130J-152D01*
G01X1442134D01*
G03X1442004Y266395I0J-200D01*
G01X1442003Y266394D01*
G02X1441016Y266024I-987J1131D01*
G02X1439910Y266509I0J1504D01*
G03X1439763Y266574I-148J-135D01*
G01X1439469D01*
G03X1439322Y266509I1J-200D01*
G02X1438216Y266024I-1106J1019D01*
G02X1436714Y267526I0J1502D01*
G02X1437084Y268513I1501J0D01*
G01Y268514D01*
X1437085D01*
G03X1437133Y268644I-152J130D01*
G01Y268908D01*
G03X1437085Y269038I-200J0D01*
G01X1437084Y269039D01*
G02X1436714Y270026I1131J987D01*
G02X1438216Y271528I1502J0D01*
G02X1439322Y271043I0J-1504D01*
G03X1439469Y270978I148J135D01*
G37*
G36*
G01X1541831D02*
X1542125D01*
G03X1542272Y271043I-1J200D01*
G02X1543378Y271528I1106J-1019D01*
G02X1544365Y271158I0J-1501D01*
G01X1544366D01*
Y271157D01*
G03X1544496Y271109I130J152D01*
G01X1544760D01*
G03X1544890Y271157I0J200D01*
G01X1544891Y271158D01*
G02X1545878Y271528I987J-1131D01*
G02X1547380Y270026I0J-1502D01*
G02X1547010Y269039I-1501J0D01*
G01Y269038D01*
X1547009D01*
G03X1546961Y268908I152J-130D01*
G01Y268644D01*
G03X1547009Y268514I200J0D01*
G01X1547010Y268513D01*
G02X1547380Y267526I-1131J-987D01*
G02X1545878Y266024I-1502J0D01*
G02X1544891Y266394I0J1501D01*
G01X1544890D01*
Y266395D01*
G03X1544760Y266443I-130J-152D01*
G01X1544496D01*
G03X1544366Y266395I0J-200D01*
G01X1544365Y266394D01*
G02X1543378Y266024I-987J1131D01*
G02X1542272Y266509I0J1504D01*
G03X1542125Y266574I-148J-135D01*
G01X1541831D01*
G03X1541684Y266509I1J-200D01*
G02X1540578Y266024I-1106J1019D01*
G02X1539076Y267526I0J1502D01*
G02X1539446Y268513I1501J0D01*
G01Y268514D01*
X1539447D01*
G03X1539495Y268644I-152J130D01*
G01Y268908D01*
G03X1539447Y269038I-200J0D01*
G01X1539446Y269039D01*
G02X1539076Y270026I1131J987D01*
G02X1540578Y271528I1502J0D01*
G02X1541684Y271043I0J-1504D01*
G03X1541831Y270978I148J135D01*
G37*
G36*
G01X1644193D02*
X1644487D01*
G03X1644634Y271043I-1J200D01*
G02X1645740Y271528I1106J-1019D01*
G02X1646727Y271158I0J-1501D01*
G01X1646728D01*
Y271157D01*
G03X1646858Y271109I130J152D01*
G01X1647122D01*
G03X1647252Y271157I0J200D01*
G01X1647253Y271158D01*
G02X1648240Y271528I987J-1131D01*
G02X1649742Y270026I0J-1502D01*
G02X1649372Y269039I-1501J0D01*
G01Y269038D01*
X1649371D01*
G03X1649323Y268908I152J-130D01*
G01Y268644D01*
G03X1649371Y268514I200J0D01*
G01X1649372Y268513D01*
G02X1649742Y267526I-1131J-987D01*
G02X1648240Y266024I-1502J0D01*
G02X1647253Y266394I0J1501D01*
G01X1647252D01*
Y266395D01*
G03X1647122Y266443I-130J-152D01*
G01X1646858D01*
G03X1646728Y266395I0J-200D01*
G01X1646727Y266394D01*
G02X1645740Y266024I-987J1131D01*
G02X1644634Y266509I0J1504D01*
G03X1644487Y266574I-148J-135D01*
G01X1644193D01*
G03X1644046Y266509I1J-200D01*
G02X1642940Y266024I-1106J1019D01*
G02X1641438Y267526I0J1502D01*
G02X1641808Y268513I1501J0D01*
G01Y268514D01*
X1641809D01*
G03X1641857Y268644I-152J130D01*
G01Y268908D01*
G03X1641809Y269038I-200J0D01*
G01X1641808Y269039D01*
G02X1641438Y270026I1131J987D01*
G02X1642940Y271528I1502J0D01*
G02X1644046Y271043I0J-1504D01*
G03X1644193Y270978I148J135D01*
G37*
G36*
G01X1746555D02*
X1746849D01*
G03X1746996Y271043I-1J200D01*
G02X1748102Y271528I1106J-1019D01*
G02X1749089Y271158I0J-1501D01*
G01X1749090D01*
Y271157D01*
G03X1749220Y271109I130J152D01*
G01X1749484D01*
G03X1749614Y271157I0J200D01*
G01X1749615Y271158D01*
G02X1750602Y271528I987J-1131D01*
G02X1752104Y270026I0J-1502D01*
G02X1751734Y269039I-1501J0D01*
G01Y269038D01*
X1751733D01*
G03X1751685Y268908I152J-130D01*
G01Y268644D01*
G03X1751733Y268514I200J0D01*
G01X1751734Y268513D01*
G02X1752104Y267526I-1131J-987D01*
G02X1750602Y266024I-1502J0D01*
G02X1749615Y266394I0J1501D01*
G01X1749614D01*
Y266395D01*
G03X1749484Y266443I-130J-152D01*
G01X1749220D01*
G03X1749090Y266395I0J-200D01*
G01X1749089Y266394D01*
G02X1748102Y266024I-987J1131D01*
G02X1746996Y266509I0J1504D01*
G03X1746849Y266574I-148J-135D01*
G01X1746555D01*
G03X1746408Y266509I1J-200D01*
G02X1745302Y266024I-1106J1019D01*
G02X1743800Y267526I0J1502D01*
G02X1744170Y268513I1501J0D01*
G01Y268514D01*
X1744171D01*
G03X1744219Y268644I-152J130D01*
G01Y268908D01*
G03X1744171Y269038I-200J0D01*
G01X1744170Y269039D01*
G02X1743800Y270026I1131J987D01*
G02X1745302Y271528I1502J0D01*
G02X1746408Y271043I0J-1504D01*
G03X1746555Y270978I148J135D01*
G37*
G36*
G01X91287Y272197D02*
G02X92393Y271712I0J-1504D01*
G03X92540Y271647I148J135D01*
G01X92834D01*
G03X92981Y271712I-1J200D01*
G02X94087Y272197I1106J-1019D01*
G02X95589Y270695I0J-1502D01*
G02X95219Y269708I-1501J0D01*
G01Y269707D01*
X95218D01*
G03X95170Y269577I152J-130D01*
G01Y269313D01*
G03X95218Y269183I200J0D01*
G01X95219Y269182D01*
G02X95589Y268195I-1131J-987D01*
G02X94087Y266693I-1502J0D01*
G02X92981Y267178I0J1504D01*
G03X92834Y267243I-148J-135D01*
G01X92540D01*
G03X92393Y267178I1J-200D01*
G02X91287Y266693I-1106J1019D01*
G02X90300Y267063I0J1501D01*
G01X90299D01*
Y267064D01*
G03X90169Y267112I-130J-152D01*
G01X89905D01*
G03X89775Y267064I0J-200D01*
G01X89774Y267063D01*
G02X88787Y266693I-987J1131D01*
G02X87285Y268195I0J1502D01*
G02X87655Y269182I1501J0D01*
G01Y269183D01*
X87656D01*
G03X87704Y269313I-152J130D01*
G01Y269577D01*
G03X87656Y269707I-200J0D01*
G01X87655Y269708D01*
G02X87285Y270695I1131J987D01*
G02X88787Y272197I1502J0D01*
G02X89774Y271827I0J-1501D01*
G01X89775D01*
Y271826D01*
G03X89905Y271778I130J152D01*
G01X90169D01*
G03X90299Y271826I0J200D01*
G01X90300Y271827D01*
G02X91287Y272197I987J-1131D01*
G37*
G36*
G01X193649D02*
G02X194755Y271712I0J-1504D01*
G03X194902Y271647I148J135D01*
G01X195196D01*
G03X195343Y271712I-1J200D01*
G02X196449Y272197I1106J-1019D01*
G02X197951Y270695I0J-1502D01*
G02X197581Y269708I-1501J0D01*
G01Y269707D01*
X197580D01*
G03X197532Y269577I152J-130D01*
G01Y269313D01*
G03X197580Y269183I200J0D01*
G01X197581Y269182D01*
G02X197951Y268195I-1131J-987D01*
G02X196449Y266693I-1502J0D01*
G02X195343Y267178I0J1504D01*
G03X195196Y267243I-148J-135D01*
G01X194902D01*
G03X194755Y267178I1J-200D01*
G02X193649Y266693I-1106J1019D01*
G02X192662Y267063I0J1501D01*
G01X192661D01*
Y267064D01*
G03X192531Y267112I-130J-152D01*
G01X192267D01*
G03X192137Y267064I0J-200D01*
G01X192136Y267063D01*
G02X191149Y266693I-987J1131D01*
G02X189647Y268195I0J1502D01*
G02X190017Y269182I1501J0D01*
G01Y269183D01*
X190018D01*
G03X190066Y269313I-152J130D01*
G01Y269577D01*
G03X190018Y269707I-200J0D01*
G01X190017Y269708D01*
G02X189647Y270695I1131J987D01*
G02X191149Y272197I1502J0D01*
G02X192136Y271827I0J-1501D01*
G01X192137D01*
Y271826D01*
G03X192267Y271778I130J152D01*
G01X192531D01*
G03X192661Y271826I0J200D01*
G01X192662Y271827D01*
G02X193649Y272197I987J-1131D01*
G37*
G36*
G01X296011D02*
G02X297117Y271712I0J-1504D01*
G03X297264Y271647I148J135D01*
G01X297558D01*
G03X297705Y271712I-1J200D01*
G02X298811Y272197I1106J-1019D01*
G02X300313Y270695I0J-1502D01*
G02X299943Y269708I-1501J0D01*
G01Y269707D01*
X299942D01*
G03X299894Y269577I152J-130D01*
G01Y269313D01*
G03X299942Y269183I200J0D01*
G01X299943Y269182D01*
G02X300313Y268195I-1131J-987D01*
G02X298811Y266693I-1502J0D01*
G02X297705Y267178I0J1504D01*
G03X297558Y267243I-148J-135D01*
G01X297264D01*
G03X297117Y267178I1J-200D01*
G02X296011Y266693I-1106J1019D01*
G02X295024Y267063I0J1501D01*
G01X295023D01*
Y267064D01*
G03X294893Y267112I-130J-152D01*
G01X294629D01*
G03X294499Y267064I0J-200D01*
G01X294498Y267063D01*
G02X293511Y266693I-987J1131D01*
G02X292009Y268195I0J1502D01*
G02X292379Y269182I1501J0D01*
G01Y269183D01*
X292380D01*
G03X292428Y269313I-152J130D01*
G01Y269577D01*
G03X292380Y269707I-200J0D01*
G01X292379Y269708D01*
G02X292009Y270695I1131J987D01*
G02X293511Y272197I1502J0D01*
G02X294498Y271827I0J-1501D01*
G01X294499D01*
Y271826D01*
G03X294629Y271778I130J152D01*
G01X294893D01*
G03X295023Y271826I0J200D01*
G01X295024Y271827D01*
G02X296011Y272197I987J-1131D01*
G37*
G36*
G01X398373D02*
G02X399479Y271712I0J-1504D01*
G03X399626Y271647I148J135D01*
G01X399920D01*
G03X400067Y271712I-1J200D01*
G02X401173Y272197I1106J-1019D01*
G02X402675Y270695I0J-1502D01*
G02X402305Y269708I-1501J0D01*
G01Y269707D01*
X402304D01*
G03X402256Y269577I152J-130D01*
G01Y269313D01*
G03X402304Y269183I200J0D01*
G01X402305Y269182D01*
G02X402675Y268195I-1131J-987D01*
G02X401173Y266693I-1502J0D01*
G02X400067Y267178I0J1504D01*
G03X399920Y267243I-148J-135D01*
G01X399626D01*
G03X399479Y267178I1J-200D01*
G02X398373Y266693I-1106J1019D01*
G02X397386Y267063I0J1501D01*
G01X397385D01*
Y267064D01*
G03X397255Y267112I-130J-152D01*
G01X396991D01*
G03X396861Y267064I0J-200D01*
G01X396860Y267063D01*
G02X395873Y266693I-987J1131D01*
G02X394371Y268195I0J1502D01*
G02X394741Y269182I1501J0D01*
G01Y269183D01*
X394742D01*
G03X394790Y269313I-152J130D01*
G01Y269577D01*
G03X394742Y269707I-200J0D01*
G01X394741Y269708D01*
G02X394371Y270695I1131J987D01*
G02X395873Y272197I1502J0D01*
G02X396860Y271827I0J-1501D01*
G01X396861D01*
Y271826D01*
G03X396991Y271778I130J152D01*
G01X397255D01*
G03X397385Y271826I0J200D01*
G01X397386Y271827D01*
G02X398373Y272197I987J-1131D01*
G37*
G36*
G01X548374D02*
G02X549480Y271712I0J-1504D01*
G03X549627Y271647I148J135D01*
G01X549921D01*
G03X550068Y271712I-1J200D01*
G02X551174Y272197I1106J-1019D01*
G02X552676Y270695I0J-1502D01*
G02X552306Y269708I-1501J0D01*
G01Y269707D01*
X552305D01*
G03X552257Y269577I152J-130D01*
G01Y269313D01*
G03X552305Y269183I200J0D01*
G01X552306Y269182D01*
G02X552676Y268195I-1131J-987D01*
G02X551174Y266693I-1502J0D01*
G02X550068Y267178I0J1504D01*
G03X549921Y267243I-148J-135D01*
G01X549627D01*
G03X549480Y267178I1J-200D01*
G02X548374Y266693I-1106J1019D01*
G02X547387Y267063I0J1501D01*
G01X547386D01*
Y267064D01*
G03X547256Y267112I-130J-152D01*
G01X546992D01*
G03X546862Y267064I0J-200D01*
G01X546861Y267063D01*
G02X545874Y266693I-987J1131D01*
G02X544372Y268195I0J1502D01*
G02X544742Y269182I1501J0D01*
G01Y269183D01*
X544743D01*
G03X544791Y269313I-152J130D01*
G01Y269577D01*
G03X544743Y269707I-200J0D01*
G01X544742Y269708D01*
G02X544372Y270695I1131J987D01*
G02X545874Y272197I1502J0D01*
G02X546861Y271827I0J-1501D01*
G01X546862D01*
Y271826D01*
G03X546992Y271778I130J152D01*
G01X547256D01*
G03X547386Y271826I0J200D01*
G01X547387Y271827D01*
G02X548374Y272197I987J-1131D01*
G37*
G36*
G01X650736D02*
G02X651842Y271712I0J-1504D01*
G03X651989Y271647I148J135D01*
G01X652283D01*
G03X652430Y271712I-1J200D01*
G02X653536Y272197I1106J-1019D01*
G02X655038Y270695I0J-1502D01*
G02X654668Y269708I-1501J0D01*
G01Y269707D01*
X654667D01*
G03X654619Y269577I152J-130D01*
G01Y269313D01*
G03X654667Y269183I200J0D01*
G01X654668Y269182D01*
G02X655038Y268195I-1131J-987D01*
G02X653536Y266693I-1502J0D01*
G02X652430Y267178I0J1504D01*
G03X652283Y267243I-148J-135D01*
G01X651989D01*
G03X651842Y267178I1J-200D01*
G02X650736Y266693I-1106J1019D01*
G02X649749Y267063I0J1501D01*
G01X649748D01*
Y267064D01*
G03X649618Y267112I-130J-152D01*
G01X649354D01*
G03X649224Y267064I0J-200D01*
G01X649223Y267063D01*
G02X648236Y266693I-987J1131D01*
G02X646734Y268195I0J1502D01*
G02X647104Y269182I1501J0D01*
G01Y269183D01*
X647105D01*
G03X647153Y269313I-152J130D01*
G01Y269577D01*
G03X647105Y269707I-200J0D01*
G01X647104Y269708D01*
G02X646734Y270695I1131J987D01*
G02X648236Y272197I1502J0D01*
G02X649223Y271827I0J-1501D01*
G01X649224D01*
Y271826D01*
G03X649354Y271778I130J152D01*
G01X649618D01*
G03X649748Y271826I0J200D01*
G01X649749Y271827D01*
G02X650736Y272197I987J-1131D01*
G37*
G36*
G01X753098D02*
G02X754204Y271712I0J-1504D01*
G03X754351Y271647I148J135D01*
G01X754645D01*
G03X754792Y271712I-1J200D01*
G02X755898Y272197I1106J-1019D01*
G02X757400Y270695I0J-1502D01*
G02X757030Y269708I-1501J0D01*
G01Y269707D01*
X757029D01*
G03X756981Y269577I152J-130D01*
G01Y269313D01*
G03X757029Y269183I200J0D01*
G01X757030Y269182D01*
G02X757400Y268195I-1131J-987D01*
G02X755898Y266693I-1502J0D01*
G02X754792Y267178I0J1504D01*
G03X754645Y267243I-148J-135D01*
G01X754351D01*
G03X754204Y267178I1J-200D01*
G02X753098Y266693I-1106J1019D01*
G02X752111Y267063I0J1501D01*
G01X752110D01*
Y267064D01*
G03X751980Y267112I-130J-152D01*
G01X751716D01*
G03X751586Y267064I0J-200D01*
G01X751585Y267063D01*
G02X750598Y266693I-987J1131D01*
G02X749096Y268195I0J1502D01*
G02X749466Y269182I1501J0D01*
G01Y269183D01*
X749467D01*
G03X749515Y269313I-152J130D01*
G01Y269577D01*
G03X749467Y269707I-200J0D01*
G01X749466Y269708D01*
G02X749096Y270695I1131J987D01*
G02X750598Y272197I1502J0D01*
G02X751585Y271827I0J-1501D01*
G01X751586D01*
Y271826D01*
G03X751716Y271778I130J152D01*
G01X751980D01*
G03X752110Y271826I0J200D01*
G01X752111Y271827D01*
G02X753098Y272197I987J-1131D01*
G37*
G36*
G01X855460D02*
G02X856566Y271712I0J-1504D01*
G03X856713Y271647I148J135D01*
G01X857007D01*
G03X857154Y271712I-1J200D01*
G02X858260Y272197I1106J-1019D01*
G02X859762Y270695I0J-1502D01*
G02X859392Y269708I-1501J0D01*
G01Y269707D01*
X859391D01*
G03X859343Y269577I152J-130D01*
G01Y269313D01*
G03X859391Y269183I200J0D01*
G01X859392Y269182D01*
G02X859762Y268195I-1131J-987D01*
G02X858260Y266693I-1502J0D01*
G02X857154Y267178I0J1504D01*
G03X857007Y267243I-148J-135D01*
G01X856713D01*
G03X856566Y267178I1J-200D01*
G02X855460Y266693I-1106J1019D01*
G02X854473Y267063I0J1501D01*
G01X854472D01*
Y267064D01*
G03X854342Y267112I-130J-152D01*
G01X854078D01*
G03X853948Y267064I0J-200D01*
G01X853947Y267063D01*
G02X852960Y266693I-987J1131D01*
G02X851458Y268195I0J1502D01*
G02X851828Y269182I1501J0D01*
G01Y269183D01*
X851829D01*
G03X851877Y269313I-152J130D01*
G01Y269577D01*
G03X851829Y269707I-200J0D01*
G01X851828Y269708D01*
G02X851458Y270695I1131J987D01*
G02X852960Y272197I1502J0D01*
G02X853947Y271827I0J-1501D01*
G01X853948D01*
Y271826D01*
G03X854078Y271778I130J152D01*
G01X854342D01*
G03X854472Y271826I0J200D01*
G01X854473Y271827D01*
G02X855460Y272197I987J-1131D01*
G37*
G36*
G01X1005460D02*
G02X1006566Y271712I0J-1504D01*
G03X1006713Y271647I148J135D01*
G01X1007007D01*
G03X1007154Y271712I-1J200D01*
G02X1008260Y272197I1106J-1019D01*
G02X1009762Y270695I0J-1502D01*
G02X1009392Y269708I-1501J0D01*
G01Y269707D01*
X1009391D01*
G03X1009343Y269577I152J-130D01*
G01Y269313D01*
G03X1009391Y269183I200J0D01*
G01X1009392Y269182D01*
G02X1009762Y268195I-1131J-987D01*
G02X1008260Y266693I-1502J0D01*
G02X1007154Y267178I0J1504D01*
G03X1007007Y267243I-148J-135D01*
G01X1006713D01*
G03X1006566Y267178I1J-200D01*
G02X1005460Y266693I-1106J1019D01*
G02X1004473Y267063I0J1501D01*
G01X1004472D01*
Y267064D01*
G03X1004342Y267112I-130J-152D01*
G01X1004078D01*
G03X1003948Y267064I0J-200D01*
G01X1003947Y267063D01*
G02X1002960Y266693I-987J1131D01*
G02X1001458Y268195I0J1502D01*
G02X1001828Y269182I1501J0D01*
G01Y269183D01*
X1001829D01*
G03X1001877Y269313I-152J130D01*
G01Y269577D01*
G03X1001829Y269707I-200J0D01*
G01X1001828Y269708D01*
G02X1001458Y270695I1131J987D01*
G02X1002960Y272197I1502J0D01*
G02X1003947Y271827I0J-1501D01*
G01X1003948D01*
Y271826D01*
G03X1004078Y271778I130J152D01*
G01X1004342D01*
G03X1004472Y271826I0J200D01*
G01X1004473Y271827D01*
G02X1005460Y272197I987J-1131D01*
G37*
G36*
G01X1107822D02*
G02X1108928Y271712I0J-1504D01*
G03X1109075Y271647I148J135D01*
G01X1109369D01*
G03X1109516Y271712I-1J200D01*
G02X1110622Y272197I1106J-1019D01*
G02X1112124Y270695I0J-1502D01*
G02X1111754Y269708I-1501J0D01*
G01Y269707D01*
X1111753D01*
G03X1111705Y269577I152J-130D01*
G01Y269313D01*
G03X1111753Y269183I200J0D01*
G01X1111754Y269182D01*
G02X1112124Y268195I-1131J-987D01*
G02X1110622Y266693I-1502J0D01*
G02X1109516Y267178I0J1504D01*
G03X1109369Y267243I-148J-135D01*
G01X1109075D01*
G03X1108928Y267178I1J-200D01*
G02X1107822Y266693I-1106J1019D01*
G02X1106835Y267063I0J1501D01*
G01X1106834D01*
Y267064D01*
G03X1106704Y267112I-130J-152D01*
G01X1106440D01*
G03X1106310Y267064I0J-200D01*
G01X1106309Y267063D01*
G02X1105322Y266693I-987J1131D01*
G02X1103820Y268195I0J1502D01*
G02X1104190Y269182I1501J0D01*
G01Y269183D01*
X1104191D01*
G03X1104239Y269313I-152J130D01*
G01Y269577D01*
G03X1104191Y269707I-200J0D01*
G01X1104190Y269708D01*
G02X1103820Y270695I1131J987D01*
G02X1105322Y272197I1502J0D01*
G02X1106309Y271827I0J-1501D01*
G01X1106310D01*
Y271826D01*
G03X1106440Y271778I130J152D01*
G01X1106704D01*
G03X1106834Y271826I0J200D01*
G01X1106835Y271827D01*
G02X1107822Y272197I987J-1131D01*
G37*
G36*
G01X1210184D02*
G02X1211290Y271712I0J-1504D01*
G03X1211437Y271647I148J135D01*
G01X1211731D01*
G03X1211878Y271712I-1J200D01*
G02X1212984Y272197I1106J-1019D01*
G02X1214486Y270695I0J-1502D01*
G02X1214116Y269708I-1501J0D01*
G01Y269707D01*
X1214115D01*
G03X1214067Y269577I152J-130D01*
G01Y269313D01*
G03X1214115Y269183I200J0D01*
G01X1214116Y269182D01*
G02X1214486Y268195I-1131J-987D01*
G02X1212984Y266693I-1502J0D01*
G02X1211878Y267178I0J1504D01*
G03X1211731Y267243I-148J-135D01*
G01X1211437D01*
G03X1211290Y267178I1J-200D01*
G02X1210184Y266693I-1106J1019D01*
G02X1209197Y267063I0J1501D01*
G01X1209196D01*
Y267064D01*
G03X1209066Y267112I-130J-152D01*
G01X1208802D01*
G03X1208672Y267064I0J-200D01*
G01X1208671Y267063D01*
G02X1207684Y266693I-987J1131D01*
G02X1206182Y268195I0J1502D01*
G02X1206552Y269182I1501J0D01*
G01Y269183D01*
X1206553D01*
G03X1206601Y269313I-152J130D01*
G01Y269577D01*
G03X1206553Y269707I-200J0D01*
G01X1206552Y269708D01*
G02X1206182Y270695I1131J987D01*
G02X1207684Y272197I1502J0D01*
G02X1208671Y271827I0J-1501D01*
G01X1208672D01*
Y271826D01*
G03X1208802Y271778I130J152D01*
G01X1209066D01*
G03X1209196Y271826I0J200D01*
G01X1209197Y271827D01*
G02X1210184Y272197I987J-1131D01*
G37*
G36*
G01X1312546D02*
G02X1313652Y271712I0J-1504D01*
G03X1313799Y271647I148J135D01*
G01X1314093D01*
G03X1314240Y271712I-1J200D01*
G02X1315346Y272197I1106J-1019D01*
G02X1316848Y270695I0J-1502D01*
G02X1316478Y269708I-1501J0D01*
G01Y269707D01*
X1316477D01*
G03X1316429Y269577I152J-130D01*
G01Y269313D01*
G03X1316477Y269183I200J0D01*
G01X1316478Y269182D01*
G02X1316848Y268195I-1131J-987D01*
G02X1315346Y266693I-1502J0D01*
G02X1314240Y267178I0J1504D01*
G03X1314093Y267243I-148J-135D01*
G01X1313799D01*
G03X1313652Y267178I1J-200D01*
G02X1312546Y266693I-1106J1019D01*
G02X1311559Y267063I0J1501D01*
G01X1311558D01*
Y267064D01*
G03X1311428Y267112I-130J-152D01*
G01X1311164D01*
G03X1311034Y267064I0J-200D01*
G01X1311033Y267063D01*
G02X1310046Y266693I-987J1131D01*
G02X1308544Y268195I0J1502D01*
G02X1308914Y269182I1501J0D01*
G01Y269183D01*
X1308915D01*
G03X1308963Y269313I-152J130D01*
G01Y269577D01*
G03X1308915Y269707I-200J0D01*
G01X1308914Y269708D01*
G02X1308544Y270695I1131J987D01*
G02X1310046Y272197I1502J0D01*
G02X1311033Y271827I0J-1501D01*
G01X1311034D01*
Y271826D01*
G03X1311164Y271778I130J152D01*
G01X1311428D01*
G03X1311558Y271826I0J200D01*
G01X1311559Y271827D01*
G02X1312546Y272197I987J-1131D01*
G37*
G36*
G01X1462547D02*
G02X1463653Y271712I0J-1504D01*
G03X1463800Y271647I148J135D01*
G01X1464094D01*
G03X1464241Y271712I-1J200D01*
G02X1465347Y272197I1106J-1019D01*
G02X1466849Y270695I0J-1502D01*
G02X1466479Y269708I-1501J0D01*
G01Y269707D01*
X1466478D01*
G03X1466430Y269577I152J-130D01*
G01Y269313D01*
G03X1466478Y269183I200J0D01*
G01X1466479Y269182D01*
G02X1466849Y268195I-1131J-987D01*
G02X1465347Y266693I-1502J0D01*
G02X1464241Y267178I0J1504D01*
G03X1464094Y267243I-148J-135D01*
G01X1463800D01*
G03X1463653Y267178I1J-200D01*
G02X1462547Y266693I-1106J1019D01*
G02X1461560Y267063I0J1501D01*
G01X1461559D01*
Y267064D01*
G03X1461429Y267112I-130J-152D01*
G01X1461165D01*
G03X1461035Y267064I0J-200D01*
G01X1461034Y267063D01*
G02X1460047Y266693I-987J1131D01*
G02X1458545Y268195I0J1502D01*
G02X1458915Y269182I1501J0D01*
G01Y269183D01*
X1458916D01*
G03X1458964Y269313I-152J130D01*
G01Y269577D01*
G03X1458916Y269707I-200J0D01*
G01X1458915Y269708D01*
G02X1458545Y270695I1131J987D01*
G02X1460047Y272197I1502J0D01*
G02X1461034Y271827I0J-1501D01*
G01X1461035D01*
Y271826D01*
G03X1461165Y271778I130J152D01*
G01X1461429D01*
G03X1461559Y271826I0J200D01*
G01X1461560Y271827D01*
G02X1462547Y272197I987J-1131D01*
G37*
G36*
G01X1564909D02*
G02X1566015Y271712I0J-1504D01*
G03X1566162Y271647I148J135D01*
G01X1566456D01*
G03X1566603Y271712I-1J200D01*
G02X1567709Y272197I1106J-1019D01*
G02X1569211Y270695I0J-1502D01*
G02X1568841Y269708I-1501J0D01*
G01Y269707D01*
X1568840D01*
G03X1568792Y269577I152J-130D01*
G01Y269313D01*
G03X1568840Y269183I200J0D01*
G01X1568841Y269182D01*
G02X1569211Y268195I-1131J-987D01*
G02X1567709Y266693I-1502J0D01*
G02X1566603Y267178I0J1504D01*
G03X1566456Y267243I-148J-135D01*
G01X1566162D01*
G03X1566015Y267178I1J-200D01*
G02X1564909Y266693I-1106J1019D01*
G02X1563922Y267063I0J1501D01*
G01X1563921D01*
Y267064D01*
G03X1563791Y267112I-130J-152D01*
G01X1563527D01*
G03X1563397Y267064I0J-200D01*
G01X1563396Y267063D01*
G02X1562409Y266693I-987J1131D01*
G02X1560907Y268195I0J1502D01*
G02X1561277Y269182I1501J0D01*
G01Y269183D01*
X1561278D01*
G03X1561326Y269313I-152J130D01*
G01Y269577D01*
G03X1561278Y269707I-200J0D01*
G01X1561277Y269708D01*
G02X1560907Y270695I1131J987D01*
G02X1562409Y272197I1502J0D01*
G02X1563396Y271827I0J-1501D01*
G01X1563397D01*
Y271826D01*
G03X1563527Y271778I130J152D01*
G01X1563791D01*
G03X1563921Y271826I0J200D01*
G01X1563922Y271827D01*
G02X1564909Y272197I987J-1131D01*
G37*
G36*
G01X1667271D02*
G02X1668377Y271712I0J-1504D01*
G03X1668524Y271647I148J135D01*
G01X1668818D01*
G03X1668965Y271712I-1J200D01*
G02X1670071Y272197I1106J-1019D01*
G02X1671573Y270695I0J-1502D01*
G02X1671203Y269708I-1501J0D01*
G01Y269707D01*
X1671202D01*
G03X1671154Y269577I152J-130D01*
G01Y269313D01*
G03X1671202Y269183I200J0D01*
G01X1671203Y269182D01*
G02X1671573Y268195I-1131J-987D01*
G02X1670071Y266693I-1502J0D01*
G02X1668965Y267178I0J1504D01*
G03X1668818Y267243I-148J-135D01*
G01X1668524D01*
G03X1668377Y267178I1J-200D01*
G02X1667271Y266693I-1106J1019D01*
G02X1666284Y267063I0J1501D01*
G01X1666283D01*
Y267064D01*
G03X1666153Y267112I-130J-152D01*
G01X1665889D01*
G03X1665759Y267064I0J-200D01*
G01X1665758Y267063D01*
G02X1664771Y266693I-987J1131D01*
G02X1663269Y268195I0J1502D01*
G02X1663639Y269182I1501J0D01*
G01Y269183D01*
X1663640D01*
G03X1663688Y269313I-152J130D01*
G01Y269577D01*
G03X1663640Y269707I-200J0D01*
G01X1663639Y269708D01*
G02X1663269Y270695I1131J987D01*
G02X1664771Y272197I1502J0D01*
G02X1665758Y271827I0J-1501D01*
G01X1665759D01*
Y271826D01*
G03X1665889Y271778I130J152D01*
G01X1666153D01*
G03X1666283Y271826I0J200D01*
G01X1666284Y271827D01*
G02X1667271Y272197I987J-1131D01*
G37*
G36*
G01X1769633D02*
G02X1770739Y271712I0J-1504D01*
G03X1770886Y271647I148J135D01*
G01X1771180D01*
G03X1771327Y271712I-1J200D01*
G02X1772433Y272197I1106J-1019D01*
G02X1773935Y270695I0J-1502D01*
G02X1773565Y269708I-1501J0D01*
G01Y269707D01*
X1773564D01*
G03X1773516Y269577I152J-130D01*
G01Y269313D01*
G03X1773564Y269183I200J0D01*
G01X1773565Y269182D01*
G02X1773935Y268195I-1131J-987D01*
G02X1772433Y266693I-1502J0D01*
G02X1771327Y267178I0J1504D01*
G03X1771180Y267243I-148J-135D01*
G01X1770886D01*
G03X1770739Y267178I1J-200D01*
G02X1769633Y266693I-1106J1019D01*
G02X1768646Y267063I0J1501D01*
G01X1768645D01*
Y267064D01*
G03X1768515Y267112I-130J-152D01*
G01X1768251D01*
G03X1768121Y267064I0J-200D01*
G01X1768120Y267063D01*
G02X1767133Y266693I-987J1131D01*
G02X1765631Y268195I0J1502D01*
G02X1766001Y269182I1501J0D01*
G01Y269183D01*
X1766002D01*
G03X1766050Y269313I-152J130D01*
G01Y269577D01*
G03X1766002Y269707I-200J0D01*
G01X1766001Y269708D01*
G02X1765631Y270695I1131J987D01*
G02X1767133Y272197I1502J0D01*
G02X1768120Y271827I0J-1501D01*
G01X1768121D01*
Y271826D01*
G03X1768251Y271778I130J152D01*
G01X1768515D01*
G03X1768645Y271826I0J200D01*
G01X1768646Y271827D01*
G02X1769633Y272197I987J-1131D01*
G37*
G36*
G01X895451Y272012D02*
G02X898455I1502J0D01*
G01Y272011D01*
G02X898306Y271359I-1502J0D01*
G01X898288Y271321D01*
X898285Y271236D01*
X898417Y270919D01*
G03X898535Y270807I185J77D01*
G01X898536D01*
G02X899550Y269387I-487J-1420D01*
G02X896546I-1502J0D01*
G01Y269388D01*
G02X896695Y270040I1502J0D01*
G01X896713Y270078D01*
X896716Y270163D01*
X896584Y270480D01*
G03X896466Y270592I-185J-77D01*
G01X896465D01*
G02X895451Y272012I487J1420D01*
G37*
G36*
G01X403343Y313656D02*
G02Y316660I0J1502D01*
G02X404330Y316290I0J-1501D01*
G01X404331D01*
Y316289D01*
G03X404461Y316241I130J152D01*
G01X404725D01*
G03X404855Y316289I0J200D01*
G01X404856Y316290D01*
G02X405843Y316660I987J-1131D01*
G02Y313656I0J-1502D01*
G02X404856Y314026I0J1501D01*
G01X404855D01*
Y314027D01*
G03X404725Y314075I-130J-152D01*
G01X404461D01*
G03X404331Y314027I0J-200D01*
G01X404330Y314026D01*
G02X403343Y313656I-987J1131D01*
G37*
G36*
G01X1232197Y315462D02*
G02Y318466I0J1502D01*
G02X1233273Y318011I-1J-1502D01*
G03X1233275Y318009I142J140D01*
G03X1233415Y317950I142J141D01*
G01X1233701Y317948D01*
G03X1233843Y318005I2J200D01*
G01X1233844Y318006D01*
G02X1234904Y318444I1060J-1064D01*
G02Y315440I0J-1502D01*
G02X1233828Y315895I1J1502D01*
G03X1233826Y315897I-142J-140D01*
G03X1233686Y315956I-142J-141D01*
G01X1233400Y315958D01*
G03X1233258Y315901I-2J-200D01*
G01X1233257Y315900D01*
G02X1232197Y315462I-1060J1064D01*
G37*
G36*
G01X1305928Y316748D02*
G02Y319752I0J1502D01*
G02X1306915Y319382I0J-1501D01*
G01X1306916D01*
Y319381D01*
G03X1307046Y319333I130J152D01*
G01X1307310D01*
G03X1307440Y319381I0J200D01*
G01X1307441Y319382D01*
G02X1308428Y319752I987J-1131D01*
G02Y316748I0J-1502D01*
G02X1307441Y317118I0J1501D01*
G01X1307440D01*
Y317119D01*
G03X1307310Y317167I-130J-152D01*
G01X1307046D01*
G03X1306916Y317119I0J-200D01*
G01X1306915Y317118D01*
G02X1305928Y316748I-987J1131D01*
G37*
G36*
G01X430361Y324689D02*
G02Y321685I0J-1502D01*
G02X429720Y321829I1J1502D01*
G01X429719D01*
G03X429550Y321830I-86J-181D01*
G01X429231Y321683D01*
X429174Y321615D01*
X429163Y321572D01*
G02X427713Y320463I-1450J393D01*
G02Y323467I0J1502D01*
G02X428354Y323323I-1J-1502D01*
G01X428355D01*
G03X428524Y323322I86J181D01*
G01X428843Y323469D01*
X428900Y323537D01*
X428911Y323580D01*
G02X430361Y324689I1450J-393D01*
G37*
G36*
G01X807988Y333368D02*
G02X810992I1502J0D01*
G01Y333367D01*
G02X810445Y332208I-1502J0D01*
G01X810410Y332179D01*
X810372Y332101D01*
X810368Y331706D01*
X810404Y331625D01*
X810438Y331597D01*
G02X810959Y330459I-982J-1138D01*
G02X807955I-1502J0D01*
G01Y330460D01*
G02X808502Y331619I1502J0D01*
G01X808537Y331648D01*
X808575Y331726D01*
X808579Y332121D01*
X808543Y332202D01*
X808509Y332230D01*
G02X807988Y333368I982J1138D01*
G37*
G36*
G01X1447558Y352361D02*
G02X1450562I1502J0D01*
G02X1449798Y351053I-1502J0D01*
G03X1449698Y350911I97J-175D01*
G01X1449639Y350559D01*
X1449664Y350473D01*
X1449695Y350439D01*
G02X1450074Y349442I-1123J-998D01*
G01Y349441D01*
G02X1447070I-1502J0D01*
G02X1447834Y350749I1502J0D01*
G03X1447934Y350891I-97J175D01*
G01X1447993Y351243D01*
X1447968Y351329D01*
X1447937Y351363D01*
G02X1447558Y352360I1123J998D01*
G01Y352361D01*
G37*
G36*
G01X1372232Y359796D02*
G02Y362800I0J1502D01*
G02X1373328Y362325I0J-1502D01*
G01X1373357Y362294D01*
X1373436Y362260D01*
X1373779Y362270D01*
G03X1373926Y362340I-5J200D01*
G02X1375073Y362873I1147J-968D01*
G02Y359869I0J-1502D01*
G02X1373977Y360344I0J1502D01*
G01X1373948Y360375D01*
X1373869Y360409D01*
X1373526Y360399D01*
G03X1373379Y360329I5J-200D01*
G02X1372232Y359796I-1147J968D01*
G37*
G36*
G01X647411Y379065D02*
X647412D01*
G02Y370659I0J-4203D01*
G01X647411D01*
G02Y379065I0J4203D01*
G37*
G36*
G01X361143Y384277D02*
X360829D01*
G03X360671Y384200I0J-200D01*
G02X359486Y383621I-1185J923D01*
G02Y386625I0J1502D01*
G02X360671Y386046I0J-1502D01*
G03X360829Y385969I158J123D01*
G01X361143D01*
G03X361301Y386046I0J200D01*
G02X362486Y386625I1185J-923D01*
G02Y383621I0J-1502D01*
G02X361301Y384200I0J1502D01*
G03X361143Y384277I-158J-123D01*
G37*
G36*
G01X1275316D02*
X1275002D01*
G03X1274844Y384200I0J-200D01*
G02X1273659Y383621I-1185J923D01*
G02Y386625I0J1502D01*
G02X1274844Y386046I0J-1502D01*
G03X1275002Y385969I158J123D01*
G01X1275316D01*
G03X1275474Y386046I0J200D01*
G02X1276659Y386625I1185J-923D01*
G02Y383621I0J-1502D01*
G02X1275474Y384200I0J1502D01*
G03X1275316Y384277I-158J-123D01*
G37*
G36*
G01X1732403D02*
X1732089D01*
G03X1731931Y384200I0J-200D01*
G02X1730746Y383621I-1185J923D01*
G02Y386625I0J1502D01*
G02X1731931Y386046I0J-1502D01*
G03X1732089Y385969I158J123D01*
G01X1732403D01*
G03X1732561Y386046I0J200D01*
G02X1733746Y386625I1185J-923D01*
G02Y383621I0J-1502D01*
G02X1732561Y384200I0J1502D01*
G03X1732403Y384277I-158J-123D01*
G37*
G36*
G01X1331606Y388069D02*
G02X1332664Y387633I0J-1502D01*
G01X1332692Y387605D01*
X1332765Y387575D01*
X1333126D01*
X1333199Y387605D01*
X1333227Y387633D01*
G02X1334285Y388069I1058J-1066D01*
G02Y385065I0J-1502D01*
G02X1333227Y385501I0J1502D01*
G01X1333199Y385529D01*
X1333126Y385559D01*
X1332765D01*
X1332692Y385529D01*
X1332664Y385501D01*
G02X1331606Y385065I-1058J1066D01*
G02X1330536Y385513I0J1502D01*
G03X1330393Y385573I-143J-140D01*
G01X1330109D01*
G03X1329966Y385513I0J-200D01*
G02X1328896Y385065I-1070J1054D01*
G02Y388069I0J1502D01*
G02X1329966Y387621I0J-1502D01*
G03X1330109Y387561I143J140D01*
G01X1330393D01*
G03X1330536Y387621I0J200D01*
G02X1331606Y388069I1070J-1054D01*
G37*
G36*
G01X404919Y387151D02*
G02X407923I1502J0D01*
G02X407553Y386164I-1501J0D01*
G01Y386163D01*
X407552D01*
G03X407504Y386033I152J-130D01*
G01Y385769D01*
G03X407552Y385639I200J0D01*
G01X407553Y385638D01*
G02Y383664I-1131J-987D01*
G01Y383663D01*
X407552D01*
G03X407504Y383533I152J-130D01*
G01Y383269D01*
G03X407552Y383139I200J0D01*
G01X407553Y383138D01*
G02X407923Y382151I-1131J-987D01*
G02X404919I-1502J0D01*
G02X405289Y383138I1501J0D01*
G01Y383139D01*
X405290D01*
G03X405338Y383269I-152J130D01*
G01Y383533D01*
G03X405290Y383663I-200J0D01*
G01X405289Y383664D01*
G02Y385638I1131J987D01*
G01Y385639D01*
X405290D01*
G03X405338Y385769I-152J130D01*
G01Y386033D01*
G03X405290Y386163I-200J0D01*
G01X405289Y386164D01*
G02X404919Y387151I1131J987D01*
G37*
G36*
G01X1319092D02*
G02X1322096I1502J0D01*
G02X1321726Y386164I-1501J0D01*
G01Y386163D01*
X1321725D01*
G03X1321677Y386033I152J-130D01*
G01Y385769D01*
G03X1321725Y385639I200J0D01*
G01X1321726Y385638D01*
G02Y383664I-1131J-987D01*
G01Y383663D01*
X1321725D01*
G03X1321677Y383533I152J-130D01*
G01Y383269D01*
G03X1321725Y383139I200J0D01*
G01X1321726Y383138D01*
G02X1322096Y382151I-1131J-987D01*
G02X1319092I-1502J0D01*
G02X1319462Y383138I1501J0D01*
G01Y383139D01*
X1319463D01*
G03X1319511Y383269I-152J130D01*
G01Y383533D01*
G03X1319463Y383663I-200J0D01*
G01X1319462Y383664D01*
G02Y385638I1131J987D01*
G01Y385639D01*
X1319463D01*
G03X1319511Y385769I-152J130D01*
G01Y386033D01*
G03X1319463Y386163I-200J0D01*
G01X1319462Y386164D01*
G02X1319092Y387151I1131J987D01*
G37*
G36*
G01X1776179D02*
G02X1779183I1502J0D01*
G02X1778813Y386164I-1501J0D01*
G01Y386163D01*
X1778812D01*
G03X1778764Y386033I152J-130D01*
G01Y385769D01*
G03X1778812Y385639I200J0D01*
G01X1778813Y385638D01*
G02Y383664I-1131J-987D01*
G01Y383663D01*
X1778812D01*
G03X1778764Y383533I152J-130D01*
G01Y383269D01*
G03X1778812Y383139I200J0D01*
G01X1778813Y383138D01*
G02X1779183Y382151I-1131J-987D01*
G02X1776179I-1502J0D01*
G02X1776549Y383138I1501J0D01*
G01Y383139D01*
X1776550D01*
G03X1776598Y383269I-152J130D01*
G01Y383533D01*
G03X1776550Y383663I-200J0D01*
G01X1776549Y383664D01*
G02Y385638I1131J987D01*
G01Y385639D01*
X1776550D01*
G03X1776598Y385769I-152J130D01*
G01Y386033D01*
G03X1776550Y386163I-200J0D01*
G01X1776549Y386164D01*
G02X1776179Y387151I1131J987D01*
G37*
G36*
G01X417495Y387210D02*
G02X420499I1502J0D01*
G02X420129Y386223I-1501J0D01*
G01Y386222D01*
X420128D01*
G03X420080Y386092I152J-130D01*
G01Y385828D01*
G03X420128Y385698I200J0D01*
G01X420129Y385697D01*
G02Y383723I-1131J-987D01*
G01Y383722D01*
X420128D01*
G03X420080Y383592I152J-130D01*
G01Y383328D01*
G03X420128Y383198I200J0D01*
G01X420129Y383197D01*
G02X420499Y382210I-1131J-987D01*
G02X417495I-1502J0D01*
G02X417865Y383197I1501J0D01*
G01Y383198D01*
X417866D01*
G03X417914Y383328I-152J130D01*
G01Y383592D01*
G03X417866Y383722I-200J0D01*
G01X417865Y383723D01*
G02Y385697I1131J987D01*
G01Y385698D01*
X417866D01*
G03X417914Y385828I-152J130D01*
G01Y386092D01*
G03X417866Y386222I-200J0D01*
G01X417865Y386223D01*
G02X417495Y387210I1131J987D01*
G37*
G36*
G01X400000Y386750D02*
X399706D01*
G03X399559Y386685I1J-200D01*
G02X398453Y386200I-1106J1019D01*
G02Y389204I0J1502D01*
G02X399559Y388719I0J-1504D01*
G03X399706Y388654I148J135D01*
G01X400000D01*
G03X400147Y388719I-1J200D01*
G02X401253Y389204I1106J-1019D01*
G02Y386200I0J-1502D01*
G02X400147Y386685I0J1504D01*
G03X400000Y386750I-148J-135D01*
G37*
G36*
G01X1314173D02*
X1313879D01*
G03X1313732Y386685I1J-200D01*
G02X1312626Y386200I-1106J1019D01*
G02Y389204I0J1502D01*
G02X1313732Y388719I0J-1504D01*
G03X1313879Y388654I148J135D01*
G01X1314173D01*
G03X1314320Y388719I-1J200D01*
G02X1315426Y389204I1106J-1019D01*
G02Y386200I0J-1502D01*
G02X1314320Y386685I0J1504D01*
G03X1314173Y386750I-148J-135D01*
G37*
G36*
G01X1771260D02*
X1770966D01*
G03X1770819Y386685I1J-200D01*
G02X1769713Y386200I-1106J1019D01*
G02Y389204I0J1502D01*
G02X1770819Y388719I0J-1504D01*
G03X1770966Y388654I148J135D01*
G01X1771260D01*
G03X1771407Y388719I-1J200D01*
G02X1772513Y389204I1106J-1019D01*
G02Y386200I0J-1502D01*
G02X1771407Y386685I0J1504D01*
G03X1771260Y386750I-148J-135D01*
G37*
G36*
G01X390438Y388817D02*
G02X391940Y390319I1502J0D01*
G02X392795Y390052I0J-1502D01*
G01X392829Y390029D01*
X392910Y390012D01*
X393277Y390092D01*
X393344Y390140D01*
X393365Y390175D01*
G02X394653Y390904I1288J-773D01*
G02Y387900I0J-1502D01*
G02X393798Y388167I0J1502D01*
G01X393764Y388190D01*
X393683Y388207D01*
X393316Y388127D01*
X393249Y388079D01*
X393228Y388044D01*
G02X393072Y387831I-1285J777D01*
G03X393071Y387829I173J-88D01*
G03X393023Y387699I152J-130D01*
G01Y387435D01*
G03X393071Y387305I200J0D01*
G01X393072Y387304D01*
G02Y385330I-1131J-987D01*
G01Y385329D01*
X393071D01*
G03X393023Y385199I152J-130D01*
G01Y384935D01*
G03X393071Y384805I200J0D01*
G01X393072Y384804D01*
G02X393442Y383817I-1131J-987D01*
G02X390438I-1502J0D01*
G02X390808Y384804I1501J0D01*
G01Y384805D01*
X390809D01*
G03X390857Y384935I-152J130D01*
G01Y385199D01*
G03X390809Y385329I-200J0D01*
G01X390808Y385330D01*
G02Y387304I1131J987D01*
G01Y387305D01*
X390809D01*
G03X390857Y387435I-152J130D01*
G01Y387699D01*
G03X390809Y387829I-200J0D01*
G01X390808Y387830D01*
G02X390438Y388817I1131J987D01*
G37*
G36*
G01X1304611D02*
G02X1306113Y390319I1502J0D01*
G02X1306968Y390052I0J-1502D01*
G01X1307002Y390029D01*
X1307083Y390012D01*
X1307450Y390092D01*
X1307517Y390140D01*
X1307538Y390175D01*
G02X1308826Y390904I1288J-773D01*
G02Y387900I0J-1502D01*
G02X1307971Y388167I0J1502D01*
G01X1307937Y388190D01*
X1307856Y388207D01*
X1307489Y388127D01*
X1307422Y388079D01*
X1307401Y388044D01*
G02X1307245Y387831I-1285J777D01*
G03X1307244Y387829I173J-88D01*
G03X1307196Y387699I152J-130D01*
G01Y387435D01*
G03X1307244Y387305I200J0D01*
G01X1307245Y387304D01*
G02Y385330I-1131J-987D01*
G01Y385329D01*
X1307244D01*
G03X1307196Y385199I152J-130D01*
G01Y384935D01*
G03X1307244Y384805I200J0D01*
G01X1307245Y384804D01*
G02X1307615Y383817I-1131J-987D01*
G02X1304611I-1502J0D01*
G02X1304981Y384804I1501J0D01*
G01Y384805D01*
X1304982D01*
G03X1305030Y384935I-152J130D01*
G01Y385199D01*
G03X1304982Y385329I-200J0D01*
G01X1304981Y385330D01*
G02Y387304I1131J987D01*
G01Y387305D01*
X1304982D01*
G03X1305030Y387435I-152J130D01*
G01Y387699D01*
G03X1304982Y387829I-200J0D01*
G01X1304981Y387830D01*
G02X1304611Y388817I1131J987D01*
G37*
G36*
G01X1761698D02*
G02X1763200Y390319I1502J0D01*
G02X1764055Y390052I0J-1502D01*
G01X1764089Y390029D01*
X1764170Y390012D01*
X1764537Y390092D01*
X1764604Y390140D01*
X1764625Y390175D01*
G02X1765913Y390904I1288J-773D01*
G02Y387900I0J-1502D01*
G02X1765058Y388167I0J1502D01*
G01X1765024Y388190D01*
X1764943Y388207D01*
X1764576Y388127D01*
X1764509Y388079D01*
X1764488Y388044D01*
G02X1764332Y387831I-1285J777D01*
G03X1764331Y387829I173J-88D01*
G03X1764283Y387699I152J-130D01*
G01Y387435D01*
G03X1764331Y387305I200J0D01*
G01X1764332Y387304D01*
G02Y385330I-1131J-987D01*
G01Y385329D01*
X1764331D01*
G03X1764283Y385199I152J-130D01*
G01Y384935D01*
G03X1764331Y384805I200J0D01*
G01X1764332Y384804D01*
G02X1764702Y383817I-1131J-987D01*
G02X1761698I-1502J0D01*
G02X1762068Y384804I1501J0D01*
G01Y384805D01*
X1762069D01*
G03X1762117Y384935I-152J130D01*
G01Y385199D01*
G03X1762069Y385329I-200J0D01*
G01X1762068Y385330D01*
G02Y387304I1131J987D01*
G01Y387305D01*
X1762069D01*
G03X1762117Y387435I-152J130D01*
G01Y387699D01*
G03X1762069Y387829I-200J0D01*
G01X1762068Y387830D01*
G02X1761698Y388817I1131J987D01*
G37*
G36*
G01X383364Y396776D02*
G02Y399780I0J1502D01*
G02X384351Y399410I0J-1501D01*
G01X384352D01*
Y399409D01*
G03X384482Y399361I130J152D01*
G01X384746D01*
G03X384876Y399409I0J200D01*
G01X384877Y399410D01*
G02X385864Y399780I987J-1131D01*
G02Y396776I0J-1502D01*
G02X384877Y397146I0J1501D01*
G01X384876D01*
Y397147D01*
G03X384746Y397195I-130J-152D01*
G01X384482D01*
G03X384352Y397147I0J-200D01*
G01X384351Y397146D01*
G02X383364Y396776I-987J1131D01*
G37*
G36*
G01X1297537D02*
G02Y399780I0J1502D01*
G02X1298524Y399410I0J-1501D01*
G01X1298525D01*
Y399409D01*
G03X1298655Y399361I130J152D01*
G01X1298919D01*
G03X1299049Y399409I0J200D01*
G01X1299050Y399410D01*
G02X1300037Y399780I987J-1131D01*
G02Y396776I0J-1502D01*
G02X1299050Y397146I0J1501D01*
G01X1299049D01*
Y397147D01*
G03X1298919Y397195I-130J-152D01*
G01X1298655D01*
G03X1298525Y397147I0J-200D01*
G01X1298524Y397146D01*
G02X1297537Y396776I-987J1131D01*
G37*
G36*
G01X1754624D02*
G02Y399780I0J1502D01*
G02X1755611Y399410I0J-1501D01*
G01X1755612D01*
Y399409D01*
G03X1755742Y399361I130J152D01*
G01X1756006D01*
G03X1756136Y399409I0J200D01*
G01X1756137Y399410D01*
G02X1757124Y399780I987J-1131D01*
G02Y396776I0J-1502D01*
G02X1756137Y397146I0J1501D01*
G01X1756136D01*
Y397147D01*
G03X1756006Y397195I-130J-152D01*
G01X1755742D01*
G03X1755612Y397147I0J-200D01*
G01X1755611Y397146D01*
G02X1754624Y396776I-987J1131D01*
G37*
G36*
G01X381591Y400479D02*
G02Y403483I0J1502D01*
G02X382578Y403113I0J-1501D01*
G01X382579D01*
Y403112D01*
G03X382709Y403064I130J152D01*
G01X382973D01*
G03X383103Y403112I0J200D01*
G01X383104Y403113D01*
G02X384091Y403483I987J-1131D01*
G02Y400479I0J-1502D01*
G02X383104Y400849I0J1501D01*
G01X383103D01*
Y400850D01*
G03X382973Y400898I-130J-152D01*
G01X382709D01*
G03X382579Y400850I0J-200D01*
G01X382578Y400849D01*
G02X381591Y400479I-987J1131D01*
G37*
G36*
G01X1295764D02*
G02Y403483I0J1502D01*
G02X1296751Y403113I0J-1501D01*
G01X1296752D01*
Y403112D01*
G03X1296882Y403064I130J152D01*
G01X1297146D01*
G03X1297276Y403112I0J200D01*
G01X1297277Y403113D01*
G02X1298264Y403483I987J-1131D01*
G02Y400479I0J-1502D01*
G02X1297277Y400849I0J1501D01*
G01X1297276D01*
Y400850D01*
G03X1297146Y400898I-130J-152D01*
G01X1296882D01*
G03X1296752Y400850I0J-200D01*
G01X1296751Y400849D01*
G02X1295764Y400479I-987J1131D01*
G37*
G36*
G01X1752851D02*
G02Y403483I0J1502D01*
G02X1753838Y403113I0J-1501D01*
G01X1753839D01*
Y403112D01*
G03X1753969Y403064I130J152D01*
G01X1754233D01*
G03X1754363Y403112I0J200D01*
G01X1754364Y403113D01*
G02X1755351Y403483I987J-1131D01*
G02Y400479I0J-1502D01*
G02X1754364Y400849I0J1501D01*
G01X1754363D01*
Y400850D01*
G03X1754233Y400898I-130J-152D01*
G01X1753969D01*
G03X1753839Y400850I0J-200D01*
G01X1753838Y400849D01*
G02X1752851Y400479I-987J1131D01*
G37*
G36*
G01X429890Y409056D02*
X430184D01*
G03X430331Y409121I-1J200D01*
G02X432543I1106J-1017D01*
G03X432690Y409056I148J135D01*
G01X432984D01*
G03X433131Y409121I-1J200D01*
G02X434237Y409606I1106J-1019D01*
G02Y406602I0J-1502D01*
G02X433131Y407087I0J1504D01*
G03X432984Y407152I-148J-135D01*
G01X432690D01*
G03X432543Y407087I1J-200D01*
G02X430331I-1106J1017D01*
G03X430184Y407152I-148J-135D01*
G01X429890D01*
G03X429743Y407087I1J-200D01*
G02X428637Y406602I-1106J1019D01*
G02Y409606I0J1502D01*
G02X429743Y409121I0J-1504D01*
G03X429890Y409056I148J135D01*
G37*
G36*
G01X1344063D02*
X1344357D01*
G03X1344504Y409121I-1J200D01*
G02X1346716I1106J-1017D01*
G03X1346863Y409056I148J135D01*
G01X1347157D01*
G03X1347304Y409121I-1J200D01*
G02X1348410Y409606I1106J-1019D01*
G02Y406602I0J-1502D01*
G02X1347304Y407087I0J1504D01*
G03X1347157Y407152I-148J-135D01*
G01X1346863D01*
G03X1346716Y407087I1J-200D01*
G02X1344504I-1106J1017D01*
G03X1344357Y407152I-148J-135D01*
G01X1344063D01*
G03X1343916Y407087I1J-200D01*
G02X1342810Y406602I-1106J1019D01*
G02Y409606I0J1502D01*
G02X1343916Y409121I0J-1504D01*
G03X1344063Y409056I148J135D01*
G37*
G36*
G01X1801150D02*
X1801444D01*
G03X1801591Y409121I-1J200D01*
G02X1803803I1106J-1017D01*
G03X1803950Y409056I148J135D01*
G01X1804244D01*
G03X1804391Y409121I-1J200D01*
G02X1805497Y409606I1106J-1019D01*
G02Y406602I0J-1502D01*
G02X1804391Y407087I0J1504D01*
G03X1804244Y407152I-148J-135D01*
G01X1803950D01*
G03X1803803Y407087I1J-200D01*
G02X1801591I-1106J1017D01*
G03X1801444Y407152I-148J-135D01*
G01X1801150D01*
G03X1801003Y407087I1J-200D01*
G02X1799897Y406602I-1106J1019D01*
G02Y409606I0J1502D01*
G02X1801003Y409121I0J-1504D01*
G03X1801150Y409056I148J135D01*
G37*
G36*
G01X384432Y414743D02*
X384433Y414742D01*
G03X384563Y414694I130J152D01*
G01X384827D01*
G03X384957Y414742I0J200D01*
G01X384958Y414743D01*
G02X385945Y415113I987J-1131D01*
G02Y412109I0J-1502D01*
G02X384958Y412479I0J1501D01*
G01X384957D01*
Y412480D01*
G03X384827Y412528I-130J-152D01*
G01X384563D01*
G03X384433Y412480I0J-200D01*
G01X384432Y412479D01*
G02X382458I-987J1131D01*
G01X382457D01*
Y412480D01*
G03X382327Y412528I-130J-152D01*
G01X382063D01*
G03X381933Y412480I0J-200D01*
G01X381932Y412479D01*
G02X379958I-987J1131D01*
G01X379957D01*
Y412480D01*
G03X379827Y412528I-130J-152D01*
G01X379563D01*
G03X379433Y412480I0J-200D01*
G01X379432Y412479D01*
G02X378445Y412109I-987J1131D01*
G02Y415113I0J1502D01*
G02X379432Y414743I0J-1501D01*
G01X379433D01*
Y414742D01*
G03X379563Y414694I130J152D01*
G01X379827D01*
G03X379957Y414742I0J200D01*
G01X379958Y414743D01*
G02X381932I987J-1131D01*
G01X381933D01*
Y414742D01*
G03X382063Y414694I130J152D01*
G01X382327D01*
G03X382457Y414742I0J200D01*
G01X382458Y414743D01*
G02X384432I987J-1131D01*
G37*
G36*
G01X1298605D02*
X1298606Y414742D01*
G03X1298736Y414694I130J152D01*
G01X1299000D01*
G03X1299130Y414742I0J200D01*
G01X1299131Y414743D01*
G02X1300118Y415113I987J-1131D01*
G02Y412109I0J-1502D01*
G02X1299131Y412479I0J1501D01*
G01X1299130D01*
Y412480D01*
G03X1299000Y412528I-130J-152D01*
G01X1298736D01*
G03X1298606Y412480I0J-200D01*
G01X1298605Y412479D01*
G02X1296631I-987J1131D01*
G01X1296630D01*
Y412480D01*
G03X1296500Y412528I-130J-152D01*
G01X1296236D01*
G03X1296106Y412480I0J-200D01*
G01X1296105Y412479D01*
G02X1294131I-987J1131D01*
G01X1294130D01*
Y412480D01*
G03X1294000Y412528I-130J-152D01*
G01X1293736D01*
G03X1293606Y412480I0J-200D01*
G01X1293605Y412479D01*
G02X1292618Y412109I-987J1131D01*
G02Y415113I0J1502D01*
G02X1293605Y414743I0J-1501D01*
G01X1293606D01*
Y414742D01*
G03X1293736Y414694I130J152D01*
G01X1294000D01*
G03X1294130Y414742I0J200D01*
G01X1294131Y414743D01*
G02X1296105I987J-1131D01*
G01X1296106D01*
Y414742D01*
G03X1296236Y414694I130J152D01*
G01X1296500D01*
G03X1296630Y414742I0J200D01*
G01X1296631Y414743D01*
G02X1298605I987J-1131D01*
G37*
G36*
G01X1755692D02*
X1755693Y414742D01*
G03X1755823Y414694I130J152D01*
G01X1756087D01*
G03X1756217Y414742I0J200D01*
G01X1756218Y414743D01*
G02X1757205Y415113I987J-1131D01*
G02Y412109I0J-1502D01*
G02X1756218Y412479I0J1501D01*
G01X1756217D01*
Y412480D01*
G03X1756087Y412528I-130J-152D01*
G01X1755823D01*
G03X1755693Y412480I0J-200D01*
G01X1755692Y412479D01*
G02X1753718I-987J1131D01*
G01X1753717D01*
Y412480D01*
G03X1753587Y412528I-130J-152D01*
G01X1753323D01*
G03X1753193Y412480I0J-200D01*
G01X1753192Y412479D01*
G02X1751218I-987J1131D01*
G01X1751217D01*
Y412480D01*
G03X1751087Y412528I-130J-152D01*
G01X1750823D01*
G03X1750693Y412480I0J-200D01*
G01X1750692Y412479D01*
G02X1749705Y412109I-987J1131D01*
G02Y415113I0J1502D01*
G02X1750692Y414743I0J-1501D01*
G01X1750693D01*
Y414742D01*
G03X1750823Y414694I130J152D01*
G01X1751087D01*
G03X1751217Y414742I0J200D01*
G01X1751218Y414743D01*
G02X1753192I987J-1131D01*
G01X1753193D01*
Y414742D01*
G03X1753323Y414694I130J152D01*
G01X1753587D01*
G03X1753717Y414742I0J200D01*
G01X1753718Y414743D01*
G02X1755692I987J-1131D01*
G37*
G36*
G01X429607Y421327D02*
X429901D01*
G03X430048Y421392I-1J200D01*
G02X432260I1106J-1017D01*
G03X432407Y421327I148J135D01*
G01X432701D01*
G03X432848Y421392I-1J200D01*
G02X433954Y421877I1106J-1019D01*
G02Y418873I0J-1502D01*
G02X432848Y419358I0J1504D01*
G03X432701Y419423I-148J-135D01*
G01X432407D01*
G03X432260Y419358I1J-200D01*
G02X430048I-1106J1017D01*
G03X429901Y419423I-148J-135D01*
G01X429607D01*
G03X429460Y419358I1J-200D01*
G02X428354Y418873I-1106J1019D01*
G02Y421877I0J1502D01*
G02X429460Y421392I0J-1504D01*
G03X429607Y421327I148J135D01*
G37*
G36*
G01X1343780D02*
X1344074D01*
G03X1344221Y421392I-1J200D01*
G02X1346433I1106J-1017D01*
G03X1346580Y421327I148J135D01*
G01X1346874D01*
G03X1347021Y421392I-1J200D01*
G02X1348127Y421877I1106J-1019D01*
G02Y418873I0J-1502D01*
G02X1347021Y419358I0J1504D01*
G03X1346874Y419423I-148J-135D01*
G01X1346580D01*
G03X1346433Y419358I1J-200D01*
G02X1344221I-1106J1017D01*
G03X1344074Y419423I-148J-135D01*
G01X1343780D01*
G03X1343633Y419358I1J-200D01*
G02X1342527Y418873I-1106J1019D01*
G02Y421877I0J1502D01*
G02X1343633Y421392I0J-1504D01*
G03X1343780Y421327I148J135D01*
G37*
G36*
G01X1800867D02*
X1801161D01*
G03X1801308Y421392I-1J200D01*
G02X1803520I1106J-1017D01*
G03X1803667Y421327I148J135D01*
G01X1803961D01*
G03X1804108Y421392I-1J200D01*
G02X1805214Y421877I1106J-1019D01*
G02Y418873I0J-1502D01*
G02X1804108Y419358I0J1504D01*
G03X1803961Y419423I-148J-135D01*
G01X1803667D01*
G03X1803520Y419358I1J-200D01*
G02X1801308I-1106J1017D01*
G03X1801161Y419423I-148J-135D01*
G01X1800867D01*
G03X1800720Y419358I1J-200D01*
G02X1799614Y418873I-1106J1019D01*
G02Y421877I0J1502D01*
G02X1800720Y421392I0J-1504D01*
G03X1800867Y421327I148J135D01*
G37*
G36*
G01X352653Y421489D02*
G02X355657I1502J0D01*
G02X355251Y420462I-1502J0D01*
G01X355225Y420435D01*
X355197Y420364D01*
Y420014D01*
X355225Y419943D01*
X355251Y419916D01*
G02Y417862I-1096J-1027D01*
G01X355225Y417835D01*
X355197Y417764D01*
Y417414D01*
X355225Y417343D01*
X355251Y417316D01*
G02X355657Y416289I-1096J-1027D01*
G02X352653I-1502J0D01*
G02X353059Y417316I1502J0D01*
G01X353085Y417343D01*
X353113Y417414D01*
Y417764D01*
X353085Y417835D01*
X353059Y417862D01*
G02Y419916I1096J1027D01*
G01X353085Y419943D01*
X353113Y420014D01*
Y420364D01*
X353085Y420435D01*
X353059Y420462D01*
G02X352653Y421489I1096J1027D01*
G37*
G36*
G01X1266826D02*
G02X1269830I1502J0D01*
G02X1269424Y420462I-1502J0D01*
G01X1269398Y420435D01*
X1269370Y420364D01*
Y420014D01*
X1269398Y419943D01*
X1269424Y419916D01*
G02Y417862I-1096J-1027D01*
G01X1269398Y417835D01*
X1269370Y417764D01*
Y417414D01*
X1269398Y417343D01*
X1269424Y417316D01*
G02X1269830Y416289I-1096J-1027D01*
G02X1266826I-1502J0D01*
G02X1267232Y417316I1502J0D01*
G01X1267258Y417343D01*
X1267286Y417414D01*
Y417764D01*
X1267258Y417835D01*
X1267232Y417862D01*
G02Y419916I1096J1027D01*
G01X1267258Y419943D01*
X1267286Y420014D01*
Y420364D01*
X1267258Y420435D01*
X1267232Y420462D01*
G02X1266826Y421489I1096J1027D01*
G37*
G36*
G01X1723913D02*
G02X1726917I1502J0D01*
G02X1726511Y420462I-1502J0D01*
G01X1726485Y420435D01*
X1726457Y420364D01*
Y420014D01*
X1726485Y419943D01*
X1726511Y419916D01*
G02Y417862I-1096J-1027D01*
G01X1726485Y417835D01*
X1726457Y417764D01*
Y417414D01*
X1726485Y417343D01*
X1726511Y417316D01*
G02X1726917Y416289I-1096J-1027D01*
G02X1723913I-1502J0D01*
G02X1724319Y417316I1502J0D01*
G01X1724345Y417343D01*
X1724373Y417414D01*
Y417764D01*
X1724345Y417835D01*
X1724319Y417862D01*
G02Y419916I1096J1027D01*
G01X1724345Y419943D01*
X1724373Y420014D01*
Y420364D01*
X1724345Y420435D01*
X1724319Y420462D01*
G02X1723913Y421489I1096J1027D01*
G37*
G36*
G01X337570Y422088D02*
G02X340574I1502J0D01*
G02X340168Y421061I-1502J0D01*
G01X340142Y421034D01*
X340114Y420963D01*
Y420613D01*
X340142Y420542D01*
X340168Y420515D01*
G02Y418461I-1096J-1027D01*
G01X340142Y418434D01*
X340114Y418363D01*
Y418013D01*
X340142Y417942D01*
X340168Y417915D01*
G02X340574Y416888I-1096J-1027D01*
G02X337570I-1502J0D01*
G02X337976Y417915I1502J0D01*
G01X338002Y417942D01*
X338030Y418013D01*
Y418363D01*
X338002Y418434D01*
X337976Y418461D01*
G02Y420515I1096J1027D01*
G01X338002Y420542D01*
X338030Y420613D01*
Y420963D01*
X338002Y421034D01*
X337976Y421061D01*
G02X337570Y422088I1096J1027D01*
G37*
G36*
G01X384197Y425199D02*
X384198Y425198D01*
G03X384328Y425150I130J152D01*
G01X384592D01*
G03X384722Y425198I0J200D01*
G01X384723Y425199D01*
G02X385710Y425569I987J-1131D01*
G02Y422565I0J-1502D01*
G02X384723Y422935I0J1501D01*
G01X384722D01*
Y422936D01*
G03X384592Y422984I-130J-152D01*
G01X384328D01*
G03X384198Y422936I0J-200D01*
G01X384197Y422935D01*
G02X382223I-987J1131D01*
G01X382222D01*
Y422936D01*
G03X382092Y422984I-130J-152D01*
G01X381828D01*
G03X381698Y422936I0J-200D01*
G01X381697Y422935D01*
G02X379723I-987J1131D01*
G01X379722D01*
Y422936D01*
G03X379592Y422984I-130J-152D01*
G01X379328D01*
G03X379198Y422936I0J-200D01*
G01X379197Y422935D01*
G02X378210Y422565I-987J1131D01*
G02Y425569I0J1502D01*
G02X379197Y425199I0J-1501D01*
G01X379198D01*
Y425198D01*
G03X379328Y425150I130J152D01*
G01X379592D01*
G03X379722Y425198I0J200D01*
G01X379723Y425199D01*
G02X381697I987J-1131D01*
G01X381698D01*
Y425198D01*
G03X381828Y425150I130J152D01*
G01X382092D01*
G03X382222Y425198I0J200D01*
G01X382223Y425199D01*
G02X384197I987J-1131D01*
G37*
G36*
G01X1298370D02*
X1298371Y425198D01*
G03X1298501Y425150I130J152D01*
G01X1298765D01*
G03X1298895Y425198I0J200D01*
G01X1298896Y425199D01*
G02X1299883Y425569I987J-1131D01*
G02Y422565I0J-1502D01*
G02X1298896Y422935I0J1501D01*
G01X1298895D01*
Y422936D01*
G03X1298765Y422984I-130J-152D01*
G01X1298501D01*
G03X1298371Y422936I0J-200D01*
G01X1298370Y422935D01*
G02X1296396I-987J1131D01*
G01X1296395D01*
Y422936D01*
G03X1296265Y422984I-130J-152D01*
G01X1296001D01*
G03X1295871Y422936I0J-200D01*
G01X1295870Y422935D01*
G02X1293896I-987J1131D01*
G01X1293895D01*
Y422936D01*
G03X1293765Y422984I-130J-152D01*
G01X1293501D01*
G03X1293371Y422936I0J-200D01*
G01X1293370Y422935D01*
G02X1292383Y422565I-987J1131D01*
G02Y425569I0J1502D01*
G02X1293370Y425199I0J-1501D01*
G01X1293371D01*
Y425198D01*
G03X1293501Y425150I130J152D01*
G01X1293765D01*
G03X1293895Y425198I0J200D01*
G01X1293896Y425199D01*
G02X1295870I987J-1131D01*
G01X1295871D01*
Y425198D01*
G03X1296001Y425150I130J152D01*
G01X1296265D01*
G03X1296395Y425198I0J200D01*
G01X1296396Y425199D01*
G02X1298370I987J-1131D01*
G37*
G36*
G01X1755457D02*
X1755458Y425198D01*
G03X1755588Y425150I130J152D01*
G01X1755852D01*
G03X1755982Y425198I0J200D01*
G01X1755983Y425199D01*
G02X1756970Y425569I987J-1131D01*
G02Y422565I0J-1502D01*
G02X1755983Y422935I0J1501D01*
G01X1755982D01*
Y422936D01*
G03X1755852Y422984I-130J-152D01*
G01X1755588D01*
G03X1755458Y422936I0J-200D01*
G01X1755457Y422935D01*
G02X1753483I-987J1131D01*
G01X1753482D01*
Y422936D01*
G03X1753352Y422984I-130J-152D01*
G01X1753088D01*
G03X1752958Y422936I0J-200D01*
G01X1752957Y422935D01*
G02X1750983I-987J1131D01*
G01X1750982D01*
Y422936D01*
G03X1750852Y422984I-130J-152D01*
G01X1750588D01*
G03X1750458Y422936I0J-200D01*
G01X1750457Y422935D01*
G02X1749470Y422565I-987J1131D01*
G02Y425569I0J1502D01*
G02X1750457Y425199I0J-1501D01*
G01X1750458D01*
Y425198D01*
G03X1750588Y425150I130J152D01*
G01X1750852D01*
G03X1750982Y425198I0J200D01*
G01X1750983Y425199D01*
G02X1752957I987J-1131D01*
G01X1752958D01*
Y425198D01*
G03X1753088Y425150I130J152D01*
G01X1753352D01*
G03X1753482Y425198I0J200D01*
G01X1753483Y425199D01*
G02X1755457I987J-1131D01*
G37*
G36*
G01X1366538Y377987D02*
G02X1366156Y377065I-1306J1D01*
G01X1356386Y367295D01*
G02X1355462Y366912I-924J923D01*
G01X1313865D01*
G02X1312941Y367295I0J1306D01*
G01X1312328Y367908D01*
G03X1312126Y367958I-142J-141D01*
G01X1311788Y367851D01*
G03X1311651Y367695I60J-191D01*
G02X1310172Y366454I-1479J261D01*
G02X1308670Y367956I0J1502D01*
G02X1309777Y369405I1502J0D01*
G01X1309778D01*
G03X1309910Y369525I-54J192D01*
G01X1310045Y369869D01*
X1310036Y369963D01*
X1310010Y370003D01*
G02X1309781Y370799I1273J797D01*
G01Y370801D01*
G02X1311283Y372303I1502J0D01*
G02X1312717Y371248I0J-1502D01*
G01Y371246D01*
G03X1312766Y371166I190J62D01*
G01X1314347Y369585D01*
G03X1314489Y369526I142J141D01*
G01X1323405D01*
G03X1323581Y369630I1J200D01*
G01X1323749Y369937D01*
G03X1323742Y370141I-175J96D01*
G02X1323505Y370951I1266J810D01*
G02X1326509I1502J0D01*
G02X1326272Y370141I-1503J0D01*
G03X1326265Y369937I168J-108D01*
G01X1326433Y369630D01*
G03X1326609Y369526I175J96D01*
G01X1354838D01*
G03X1354980Y369585I0J200D01*
G01X1363867Y378471D01*
G03X1363926Y378613I-141J142D01*
G01Y419464D01*
G03X1363867Y419606I-200J0D01*
G01X1360354Y423118D01*
G03X1360274Y423167I-142J-141D01*
G01X1360273D01*
G02X1359217Y424601I446J1434D01*
G02X1360719Y426103I1502J0D01*
G02X1362153Y425048I0J-1502D01*
G01Y425046D01*
G03X1362202Y424966I190J62D01*
G01X1366156Y421012D01*
G02X1366538Y420090I-924J-923D01*
G01Y377987D01*
G37*
G36*
G01X356153Y426689D02*
G02X359157I1502J0D01*
G02X358751Y425662I-1502J0D01*
G01X358725Y425635D01*
X358697Y425564D01*
Y425214D01*
X358725Y425143D01*
X358751Y425116D01*
G02Y423062I-1096J-1027D01*
G01X358725Y423035D01*
X358697Y422964D01*
Y422614D01*
X358725Y422543D01*
X358751Y422516D01*
G02Y420462I-1096J-1027D01*
G01X358725Y420435D01*
X358697Y420364D01*
Y420014D01*
X358725Y419943D01*
X358751Y419916D01*
G02Y417862I-1096J-1027D01*
G01X358725Y417835D01*
X358697Y417764D01*
Y417414D01*
X358725Y417343D01*
X358751Y417316D01*
G02Y415262I-1096J-1027D01*
G01X358725Y415235D01*
X358697Y415164D01*
Y414814D01*
X358725Y414743D01*
X358751Y414716D01*
G02Y412662I-1096J-1027D01*
G01X358725Y412635D01*
X358697Y412564D01*
Y412214D01*
X358725Y412143D01*
X358751Y412116D01*
G02Y410062I-1096J-1027D01*
G01X358725Y410035D01*
X358697Y409964D01*
Y409614D01*
X358725Y409543D01*
X358751Y409516D01*
G02Y407462I-1096J-1027D01*
G01X358725Y407435D01*
X358697Y407364D01*
Y407014D01*
X358725Y406943D01*
X358751Y406916D01*
G02X359157Y405889I-1096J-1027D01*
G02X358937Y405108I-1502J2D01*
G01Y405106D01*
X358936D01*
G03X358913Y404958I172J-103D01*
G01X358985Y404647D01*
X359029Y404583D01*
X359062Y404562D01*
G02X359750Y403300I-813J-1262D01*
G02X356746I-1502J0D01*
G02X356966Y404081I1502J-2D01*
G01Y404083D01*
X356967D01*
G03X356990Y404231I-172J103D01*
G01X356918Y404542D01*
X356874Y404606D01*
X356841Y404627D01*
G02X356153Y405889I813J1262D01*
G02X356559Y406916I1502J0D01*
G01X356585Y406943D01*
X356613Y407014D01*
Y407364D01*
X356585Y407435D01*
X356559Y407462D01*
G02Y409516I1096J1027D01*
G01X356585Y409543D01*
X356613Y409614D01*
Y409964D01*
X356585Y410035D01*
X356559Y410062D01*
G02Y412116I1096J1027D01*
G01X356585Y412143D01*
X356613Y412214D01*
Y412564D01*
X356585Y412635D01*
X356559Y412662D01*
G02Y414716I1096J1027D01*
G01X356585Y414743D01*
X356613Y414814D01*
Y415164D01*
X356585Y415235D01*
X356559Y415262D01*
G02Y417316I1096J1027D01*
G01X356585Y417343D01*
X356613Y417414D01*
Y417764D01*
X356585Y417835D01*
X356559Y417862D01*
G02Y419916I1096J1027D01*
G01X356585Y419943D01*
X356613Y420014D01*
Y420364D01*
X356585Y420435D01*
X356559Y420462D01*
G02Y422516I1096J1027D01*
G01X356585Y422543D01*
X356613Y422614D01*
Y422964D01*
X356585Y423035D01*
X356559Y423062D01*
G02Y425116I1096J1027D01*
G01X356585Y425143D01*
X356613Y425214D01*
Y425564D01*
X356585Y425635D01*
X356559Y425662D01*
G02X356153Y426689I1096J1027D01*
G37*
G36*
G01X1270326D02*
G02X1273330I1502J0D01*
G02X1272924Y425662I-1502J0D01*
G01X1272898Y425635D01*
X1272870Y425564D01*
Y425214D01*
X1272898Y425143D01*
X1272924Y425116D01*
G02Y423062I-1096J-1027D01*
G01X1272898Y423035D01*
X1272870Y422964D01*
Y422614D01*
X1272898Y422543D01*
X1272924Y422516D01*
G02Y420462I-1096J-1027D01*
G01X1272898Y420435D01*
X1272870Y420364D01*
Y420014D01*
X1272898Y419943D01*
X1272924Y419916D01*
G02Y417862I-1096J-1027D01*
G01X1272898Y417835D01*
X1272870Y417764D01*
Y417414D01*
X1272898Y417343D01*
X1272924Y417316D01*
G02Y415262I-1096J-1027D01*
G01X1272898Y415235D01*
X1272870Y415164D01*
Y414814D01*
X1272898Y414743D01*
X1272924Y414716D01*
G02Y412662I-1096J-1027D01*
G01X1272898Y412635D01*
X1272870Y412564D01*
Y412214D01*
X1272898Y412143D01*
X1272924Y412116D01*
G02Y410062I-1096J-1027D01*
G01X1272898Y410035D01*
X1272870Y409964D01*
Y409614D01*
X1272898Y409543D01*
X1272924Y409516D01*
G02Y407462I-1096J-1027D01*
G01X1272898Y407435D01*
X1272870Y407364D01*
Y407014D01*
X1272898Y406943D01*
X1272924Y406916D01*
G02X1273330Y405889I-1096J-1027D01*
G02X1273110Y405108I-1502J2D01*
G01Y405106D01*
X1273109D01*
G03X1273086Y404958I172J-103D01*
G01X1273158Y404647D01*
X1273202Y404583D01*
X1273235Y404562D01*
G02X1273923Y403300I-813J-1262D01*
G02X1270919I-1502J0D01*
G02X1271139Y404081I1502J-2D01*
G01Y404083D01*
X1271140D01*
G03X1271163Y404231I-172J103D01*
G01X1271091Y404542D01*
X1271047Y404606D01*
X1271014Y404627D01*
G02X1270326Y405889I813J1262D01*
G02X1270732Y406916I1502J0D01*
G01X1270758Y406943D01*
X1270786Y407014D01*
Y407364D01*
X1270758Y407435D01*
X1270732Y407462D01*
G02Y409516I1096J1027D01*
G01X1270758Y409543D01*
X1270786Y409614D01*
Y409964D01*
X1270758Y410035D01*
X1270732Y410062D01*
G02Y412116I1096J1027D01*
G01X1270758Y412143D01*
X1270786Y412214D01*
Y412564D01*
X1270758Y412635D01*
X1270732Y412662D01*
G02Y414716I1096J1027D01*
G01X1270758Y414743D01*
X1270786Y414814D01*
Y415164D01*
X1270758Y415235D01*
X1270732Y415262D01*
G02Y417316I1096J1027D01*
G01X1270758Y417343D01*
X1270786Y417414D01*
Y417764D01*
X1270758Y417835D01*
X1270732Y417862D01*
G02Y419916I1096J1027D01*
G01X1270758Y419943D01*
X1270786Y420014D01*
Y420364D01*
X1270758Y420435D01*
X1270732Y420462D01*
G02Y422516I1096J1027D01*
G01X1270758Y422543D01*
X1270786Y422614D01*
Y422964D01*
X1270758Y423035D01*
X1270732Y423062D01*
G02Y425116I1096J1027D01*
G01X1270758Y425143D01*
X1270786Y425214D01*
Y425564D01*
X1270758Y425635D01*
X1270732Y425662D01*
G02X1270326Y426689I1096J1027D01*
G37*
G36*
G01X1727413D02*
G02X1730417I1502J0D01*
G02X1730011Y425662I-1502J0D01*
G01X1729985Y425635D01*
X1729957Y425564D01*
Y425214D01*
X1729985Y425143D01*
X1730011Y425116D01*
G02Y423062I-1096J-1027D01*
G01X1729985Y423035D01*
X1729957Y422964D01*
Y422614D01*
X1729985Y422543D01*
X1730011Y422516D01*
G02Y420462I-1096J-1027D01*
G01X1729985Y420435D01*
X1729957Y420364D01*
Y420014D01*
X1729985Y419943D01*
X1730011Y419916D01*
G02Y417862I-1096J-1027D01*
G01X1729985Y417835D01*
X1729957Y417764D01*
Y417414D01*
X1729985Y417343D01*
X1730011Y417316D01*
G02Y415262I-1096J-1027D01*
G01X1729985Y415235D01*
X1729957Y415164D01*
Y414814D01*
X1729985Y414743D01*
X1730011Y414716D01*
G02Y412662I-1096J-1027D01*
G01X1729985Y412635D01*
X1729957Y412564D01*
Y412214D01*
X1729985Y412143D01*
X1730011Y412116D01*
G02Y410062I-1096J-1027D01*
G01X1729985Y410035D01*
X1729957Y409964D01*
Y409614D01*
X1729985Y409543D01*
X1730011Y409516D01*
G02Y407462I-1096J-1027D01*
G01X1729985Y407435D01*
X1729957Y407364D01*
Y407014D01*
X1729985Y406943D01*
X1730011Y406916D01*
G02X1730417Y405889I-1096J-1027D01*
G02X1730197Y405108I-1502J2D01*
G01Y405106D01*
X1730196D01*
G03X1730173Y404958I172J-103D01*
G01X1730245Y404647D01*
X1730289Y404583D01*
X1730322Y404562D01*
G02X1731010Y403300I-813J-1262D01*
G02X1728006I-1502J0D01*
G02X1728226Y404081I1502J-2D01*
G01Y404083D01*
X1728227D01*
G03X1728250Y404231I-172J103D01*
G01X1728178Y404542D01*
X1728134Y404606D01*
X1728101Y404627D01*
G02X1727413Y405889I813J1262D01*
G02X1727819Y406916I1502J0D01*
G01X1727845Y406943D01*
X1727873Y407014D01*
Y407364D01*
X1727845Y407435D01*
X1727819Y407462D01*
G02Y409516I1096J1027D01*
G01X1727845Y409543D01*
X1727873Y409614D01*
Y409964D01*
X1727845Y410035D01*
X1727819Y410062D01*
G02Y412116I1096J1027D01*
G01X1727845Y412143D01*
X1727873Y412214D01*
Y412564D01*
X1727845Y412635D01*
X1727819Y412662D01*
G02Y414716I1096J1027D01*
G01X1727845Y414743D01*
X1727873Y414814D01*
Y415164D01*
X1727845Y415235D01*
X1727819Y415262D01*
G02Y417316I1096J1027D01*
G01X1727845Y417343D01*
X1727873Y417414D01*
Y417764D01*
X1727845Y417835D01*
X1727819Y417862D01*
G02Y419916I1096J1027D01*
G01X1727845Y419943D01*
X1727873Y420014D01*
Y420364D01*
X1727845Y420435D01*
X1727819Y420462D01*
G02Y422516I1096J1027D01*
G01X1727845Y422543D01*
X1727873Y422614D01*
Y422964D01*
X1727845Y423035D01*
X1727819Y423062D01*
G02Y425116I1096J1027D01*
G01X1727845Y425143D01*
X1727873Y425214D01*
Y425564D01*
X1727845Y425635D01*
X1727819Y425662D01*
G02X1727413Y426689I1096J1027D01*
G37*
G36*
G01X420713Y427439D02*
G02X423717I1502J0D01*
G02X423347Y426452I-1501J0D01*
G01Y426451D01*
X423346D01*
G03X423298Y426321I152J-130D01*
G01Y426057D01*
G03X423346Y425927I200J0D01*
G01X423347Y425926D01*
G02X423717Y424939I-1131J-987D01*
G02X420713I-1502J0D01*
G02X421083Y425926I1501J0D01*
G01Y425927D01*
X421084D01*
G03X421132Y426057I-152J130D01*
G01Y426321D01*
G03X421084Y426451I-200J0D01*
G01X421083Y426452D01*
G02X420713Y427439I1131J987D01*
G37*
G36*
G01X1334886D02*
G02X1337890I1502J0D01*
G02X1337520Y426452I-1501J0D01*
G01Y426451D01*
X1337519D01*
G03X1337471Y426321I152J-130D01*
G01Y426057D01*
G03X1337519Y425927I200J0D01*
G01X1337520Y425926D01*
G02X1337890Y424939I-1131J-987D01*
G02X1334886I-1502J0D01*
G02X1335256Y425926I1501J0D01*
G01Y425927D01*
X1335257D01*
G03X1335305Y426057I-152J130D01*
G01Y426321D01*
G03X1335257Y426451I-200J0D01*
G01X1335256Y426452D01*
G02X1334886Y427439I1131J987D01*
G37*
G36*
G01X1791973D02*
G02X1794977I1502J0D01*
G02X1794607Y426452I-1501J0D01*
G01Y426451D01*
X1794606D01*
G03X1794558Y426321I152J-130D01*
G01Y426057D01*
G03X1794606Y425927I200J0D01*
G01X1794607Y425926D01*
G02X1794977Y424939I-1131J-987D01*
G02X1791973I-1502J0D01*
G02X1792343Y425926I1501J0D01*
G01Y425927D01*
X1792344D01*
G03X1792392Y426057I-152J130D01*
G01Y426321D01*
G03X1792344Y426451I-200J0D01*
G01X1792343Y426452D01*
G02X1791973Y427439I1131J987D01*
G37*
G36*
G01X966592Y429098D02*
G03X966963Y429470I-28J399D01*
G02X968462Y430870I1499J-103D01*
G02X969964Y429368I0J-1502D01*
G02X968564Y427869I-1503J0D01*
G03X968193Y427497I28J-399D01*
G02X966694Y426097I-1499J103D01*
G02X965192Y427599I0J1502D01*
G02X966592Y429098I1503J0D01*
G37*
G36*
G01X357090Y433971D02*
Y434265D01*
G03X357025Y434412I-200J-1D01*
G02X356540Y435518I1019J1106D01*
G02X359544I1502J0D01*
G02X359059Y434412I-1504J0D01*
G03X358994Y434265I135J-148D01*
G01Y433971D01*
G03X359059Y433824I200J1D01*
G02X359544Y432718I-1019J-1106D01*
G02X356540I-1502J0D01*
G02X357025Y433824I1504J0D01*
G03X357090Y433971I-135J148D01*
G37*
G36*
G01X1271263D02*
Y434265D01*
G03X1271198Y434412I-200J-1D01*
G02X1270713Y435518I1019J1106D01*
G02X1273717I1502J0D01*
G02X1273232Y434412I-1504J0D01*
G03X1273167Y434265I135J-148D01*
G01Y433971D01*
G03X1273232Y433824I200J1D01*
G02X1273717Y432718I-1019J-1106D01*
G02X1270713I-1502J0D01*
G02X1271198Y433824I1504J0D01*
G03X1271263Y433971I-135J148D01*
G37*
G36*
G01X1728350D02*
Y434265D01*
G03X1728285Y434412I-200J-1D01*
G02X1727800Y435518I1019J1106D01*
G02X1730804I1502J0D01*
G02X1730319Y434412I-1504J0D01*
G03X1730254Y434265I135J-148D01*
G01Y433971D01*
G03X1730319Y433824I200J1D01*
G02X1730804Y432718I-1019J-1106D01*
G02X1727800I-1502J0D01*
G02X1728285Y433824I1504J0D01*
G03X1728350Y433971I-135J148D01*
G37*
G36*
G01X290951Y440869D02*
G02X292453Y442371I1502J0D01*
G02X293559Y441886I0J-1504D01*
G03X293706Y441821I148J135D01*
G01X294000D01*
G03X294147Y441886I-1J200D01*
G02X295253Y442371I1106J-1019D01*
G02X296755Y440869I0J-1502D01*
G02X296349Y439842I-1502J0D01*
G01X296323Y439815D01*
X296295Y439744D01*
Y439394D01*
X296323Y439323D01*
X296349Y439296D01*
G02Y437242I-1096J-1027D01*
G01X296323Y437215D01*
X296295Y437144D01*
Y436794D01*
X296323Y436723D01*
X296349Y436696D01*
G02Y434642I-1096J-1027D01*
G01X296323Y434615D01*
X296295Y434544D01*
Y434194D01*
X296323Y434123D01*
X296349Y434096D01*
G02Y432042I-1096J-1027D01*
G01X296323Y432015D01*
X296295Y431944D01*
Y431594D01*
X296323Y431523D01*
X296349Y431496D01*
G02X296755Y430469I-1096J-1027D01*
G02X295253Y428967I-1502J0D01*
G02X294147Y429452I0J1504D01*
G03X294000Y429517I-148J-135D01*
G01X293706D01*
G03X293559Y429452I1J-200D01*
G02X292453Y428967I-1106J1019D01*
G02X290951Y430469I0J1502D01*
G02X291357Y431496I1502J0D01*
G01X291383Y431523D01*
X291411Y431594D01*
Y431944D01*
X291383Y432015D01*
X291357Y432042D01*
G02Y434096I1096J1027D01*
G01X291383Y434123D01*
X291411Y434194D01*
Y434544D01*
X291383Y434615D01*
X291357Y434642D01*
G02Y436696I1096J1027D01*
G01X291383Y436723D01*
X291411Y436794D01*
Y437144D01*
X291383Y437215D01*
X291357Y437242D01*
G02Y439296I1096J1027D01*
G01X291383Y439323D01*
X291411Y439394D01*
Y439744D01*
X291383Y439815D01*
X291357Y439842D01*
G02X290951Y440869I1096J1027D01*
G37*
G36*
G01X748037D02*
G02X749539Y442371I1502J0D01*
G02X750645Y441886I0J-1504D01*
G03X750792Y441821I148J135D01*
G01X751086D01*
G03X751233Y441886I-1J200D01*
G02X752339Y442371I1106J-1019D01*
G02X753841Y440869I0J-1502D01*
G02X753435Y439842I-1502J0D01*
G01X753409Y439815D01*
X753381Y439744D01*
Y439394D01*
X753409Y439323D01*
X753435Y439296D01*
G02Y437242I-1096J-1027D01*
G01X753409Y437215D01*
X753381Y437144D01*
Y436794D01*
X753409Y436723D01*
X753435Y436696D01*
G02Y434642I-1096J-1027D01*
G01X753409Y434615D01*
X753381Y434544D01*
Y434194D01*
X753409Y434123D01*
X753435Y434096D01*
G02Y432042I-1096J-1027D01*
G01X753409Y432015D01*
X753381Y431944D01*
Y431594D01*
X753409Y431523D01*
X753435Y431496D01*
G02X753841Y430469I-1096J-1027D01*
G02X752339Y428967I-1502J0D01*
G02X751233Y429452I0J1504D01*
G03X751086Y429517I-148J-135D01*
G01X750792D01*
G03X750645Y429452I1J-200D01*
G02X749539Y428967I-1106J1019D01*
G02X748037Y430469I0J1502D01*
G02X748443Y431496I1502J0D01*
G01X748469Y431523D01*
X748497Y431594D01*
Y431944D01*
X748469Y432015D01*
X748443Y432042D01*
G02Y434096I1096J1027D01*
G01X748469Y434123D01*
X748497Y434194D01*
Y434544D01*
X748469Y434615D01*
X748443Y434642D01*
G02Y436696I1096J1027D01*
G01X748469Y436723D01*
X748497Y436794D01*
Y437144D01*
X748469Y437215D01*
X748443Y437242D01*
G02Y439296I1096J1027D01*
G01X748469Y439323D01*
X748497Y439394D01*
Y439744D01*
X748469Y439815D01*
X748443Y439842D01*
G02X748037Y440869I1096J1027D01*
G37*
G36*
G01X1205124D02*
G02X1206626Y442371I1502J0D01*
G02X1207732Y441886I0J-1504D01*
G03X1207879Y441821I148J135D01*
G01X1208173D01*
G03X1208320Y441886I-1J200D01*
G02X1209426Y442371I1106J-1019D01*
G02X1210928Y440869I0J-1502D01*
G02X1210522Y439842I-1502J0D01*
G01X1210496Y439815D01*
X1210468Y439744D01*
Y439394D01*
X1210496Y439323D01*
X1210522Y439296D01*
G02Y437242I-1096J-1027D01*
G01X1210496Y437215D01*
X1210468Y437144D01*
Y436794D01*
X1210496Y436723D01*
X1210522Y436696D01*
G02Y434642I-1096J-1027D01*
G01X1210496Y434615D01*
X1210468Y434544D01*
Y434194D01*
X1210496Y434123D01*
X1210522Y434096D01*
G02Y432042I-1096J-1027D01*
G01X1210496Y432015D01*
X1210468Y431944D01*
Y431594D01*
X1210496Y431523D01*
X1210522Y431496D01*
G02X1210928Y430469I-1096J-1027D01*
G02X1209426Y428967I-1502J0D01*
G02X1208320Y429452I0J1504D01*
G03X1208173Y429517I-148J-135D01*
G01X1207879D01*
G03X1207732Y429452I1J-200D01*
G02X1206626Y428967I-1106J1019D01*
G02X1205124Y430469I0J1502D01*
G02X1205530Y431496I1502J0D01*
G01X1205556Y431523D01*
X1205584Y431594D01*
Y431944D01*
X1205556Y432015D01*
X1205530Y432042D01*
G02Y434096I1096J1027D01*
G01X1205556Y434123D01*
X1205584Y434194D01*
Y434544D01*
X1205556Y434615D01*
X1205530Y434642D01*
G02Y436696I1096J1027D01*
G01X1205556Y436723D01*
X1205584Y436794D01*
Y437144D01*
X1205556Y437215D01*
X1205530Y437242D01*
G02Y439296I1096J1027D01*
G01X1205556Y439323D01*
X1205584Y439394D01*
Y439744D01*
X1205556Y439815D01*
X1205530Y439842D01*
G02X1205124Y440869I1096J1027D01*
G37*
G36*
G01X1662211D02*
G02X1663713Y442371I1502J0D01*
G02X1664819Y441886I0J-1504D01*
G03X1664966Y441821I148J135D01*
G01X1665260D01*
G03X1665407Y441886I-1J200D01*
G02X1666513Y442371I1106J-1019D01*
G02X1668015Y440869I0J-1502D01*
G02X1667609Y439842I-1502J0D01*
G01X1667583Y439815D01*
X1667555Y439744D01*
Y439394D01*
X1667583Y439323D01*
X1667609Y439296D01*
G02Y437242I-1096J-1027D01*
G01X1667583Y437215D01*
X1667555Y437144D01*
Y436794D01*
X1667583Y436723D01*
X1667609Y436696D01*
G02Y434642I-1096J-1027D01*
G01X1667583Y434615D01*
X1667555Y434544D01*
Y434194D01*
X1667583Y434123D01*
X1667609Y434096D01*
G02Y432042I-1096J-1027D01*
G01X1667583Y432015D01*
X1667555Y431944D01*
Y431594D01*
X1667583Y431523D01*
X1667609Y431496D01*
G02X1668015Y430469I-1096J-1027D01*
G02X1666513Y428967I-1502J0D01*
G02X1665407Y429452I0J1504D01*
G03X1665260Y429517I-148J-135D01*
G01X1664966D01*
G03X1664819Y429452I1J-200D01*
G02X1663713Y428967I-1106J1019D01*
G02X1662211Y430469I0J1502D01*
G02X1662617Y431496I1502J0D01*
G01X1662643Y431523D01*
X1662671Y431594D01*
Y431944D01*
X1662643Y432015D01*
X1662617Y432042D01*
G02Y434096I1096J1027D01*
G01X1662643Y434123D01*
X1662671Y434194D01*
Y434544D01*
X1662643Y434615D01*
X1662617Y434642D01*
G02Y436696I1096J1027D01*
G01X1662643Y436723D01*
X1662671Y436794D01*
Y437144D01*
X1662643Y437215D01*
X1662617Y437242D01*
G02Y439296I1096J1027D01*
G01X1662643Y439323D01*
X1662671Y439394D01*
Y439744D01*
X1662643Y439815D01*
X1662617Y439842D01*
G02X1662211Y440869I1096J1027D01*
G37*
G36*
G01X366967Y440571D02*
Y440865D01*
G03X366902Y441012I-200J-1D01*
G02X366417Y442118I1019J1106D01*
G02X369421I1502J0D01*
G02X368936Y441012I-1504J0D01*
G03X368871Y440865I135J-148D01*
G01Y440571D01*
G03X368936Y440424I200J1D01*
G02X369421Y439318I-1019J-1106D01*
G02X366417I-1502J0D01*
G02X366902Y440424I1504J0D01*
G03X366967Y440571I-135J148D01*
G37*
G36*
G01X374967D02*
Y440865D01*
G03X374902Y441012I-200J-1D01*
G02X374417Y442118I1019J1106D01*
G02X377421I1502J0D01*
G02X376936Y441012I-1504J0D01*
G03X376871Y440865I135J-148D01*
G01Y440571D01*
G03X376936Y440424I200J1D01*
G02X377421Y439318I-1019J-1106D01*
G02X374417I-1502J0D01*
G02X374902Y440424I1504J0D01*
G03X374967Y440571I-135J148D01*
G37*
G36*
G01X1281140D02*
Y440865D01*
G03X1281075Y441012I-200J-1D01*
G02X1280590Y442118I1019J1106D01*
G02X1283594I1502J0D01*
G02X1283109Y441012I-1504J0D01*
G03X1283044Y440865I135J-148D01*
G01Y440571D01*
G03X1283109Y440424I200J1D01*
G02X1283594Y439318I-1019J-1106D01*
G02X1280590I-1502J0D01*
G02X1281075Y440424I1504J0D01*
G03X1281140Y440571I-135J148D01*
G37*
G36*
G01X1289140D02*
Y440865D01*
G03X1289075Y441012I-200J-1D01*
G02X1288590Y442118I1019J1106D01*
G02X1291594I1502J0D01*
G02X1291109Y441012I-1504J0D01*
G03X1291044Y440865I135J-148D01*
G01Y440571D01*
G03X1291109Y440424I200J1D01*
G02X1291594Y439318I-1019J-1106D01*
G02X1288590I-1502J0D01*
G02X1289075Y440424I1504J0D01*
G03X1289140Y440571I-135J148D01*
G37*
G36*
G01X1738227D02*
Y440865D01*
G03X1738162Y441012I-200J-1D01*
G02X1737677Y442118I1019J1106D01*
G02X1740681I1502J0D01*
G02X1740196Y441012I-1504J0D01*
G03X1740131Y440865I135J-148D01*
G01Y440571D01*
G03X1740196Y440424I200J1D01*
G02X1740681Y439318I-1019J-1106D01*
G02X1737677I-1502J0D01*
G02X1738162Y440424I1504J0D01*
G03X1738227Y440571I-135J148D01*
G37*
G36*
G01X1746227D02*
Y440865D01*
G03X1746162Y441012I-200J-1D01*
G02X1745677Y442118I1019J1106D01*
G02X1748681I1502J0D01*
G02X1748196Y441012I-1504J0D01*
G03X1748131Y440865I135J-148D01*
G01Y440571D01*
G03X1748196Y440424I200J1D01*
G02X1748681Y439318I-1019J-1106D01*
G02X1745677I-1502J0D01*
G02X1746162Y440424I1504J0D01*
G03X1746227Y440571I-135J148D01*
G37*
G36*
G01X411172Y442174D02*
Y442468D01*
G03X411107Y442615I-200J-1D01*
G02X410622Y443721I1019J1106D01*
G02X412124Y445223I1502J0D01*
G02X413230Y444738I0J-1504D01*
G03X413377Y444673I148J135D01*
G01X413671D01*
G03X413818Y444738I-1J200D01*
G02X414924Y445223I1106J-1019D01*
G02X416426Y443721I0J-1502D01*
G02X415941Y442615I-1504J0D01*
G03X415876Y442468I135J-148D01*
G01Y442174D01*
G03X415941Y442027I200J1D01*
G02Y439815I-1017J-1106D01*
G03X415876Y439668I135J-148D01*
G01Y439374D01*
G03X415941Y439227I200J1D01*
G02Y437015I-1017J-1106D01*
G03X415876Y436868I135J-148D01*
G01Y436574D01*
G03X415941Y436427I200J1D01*
G02X416426Y435321I-1019J-1106D01*
G02X414924Y433819I-1502J0D01*
G02X413818Y434304I0J1504D01*
G03X413671Y434369I-148J-135D01*
G01X413377D01*
G03X413230Y434304I1J-200D01*
G02X412124Y433819I-1106J1019D01*
G02X410622Y435321I0J1502D01*
G02X411107Y436427I1504J0D01*
G03X411172Y436574I-135J148D01*
G01Y436868D01*
G03X411107Y437015I-200J-1D01*
G02Y439227I1017J1106D01*
G03X411172Y439374I-135J148D01*
G01Y439668D01*
G03X411107Y439815I-200J-1D01*
G02Y442027I1017J1106D01*
G03X411172Y442174I-135J148D01*
G37*
G36*
G01X1325345D02*
Y442468D01*
G03X1325280Y442615I-200J-1D01*
G02X1324795Y443721I1019J1106D01*
G02X1326297Y445223I1502J0D01*
G02X1327403Y444738I0J-1504D01*
G03X1327550Y444673I148J135D01*
G01X1327844D01*
G03X1327991Y444738I-1J200D01*
G02X1329097Y445223I1106J-1019D01*
G02X1330599Y443721I0J-1502D01*
G02X1330114Y442615I-1504J0D01*
G03X1330049Y442468I135J-148D01*
G01Y442174D01*
G03X1330114Y442027I200J1D01*
G02Y439815I-1017J-1106D01*
G03X1330049Y439668I135J-148D01*
G01Y439374D01*
G03X1330114Y439227I200J1D01*
G02Y437015I-1017J-1106D01*
G03X1330049Y436868I135J-148D01*
G01Y436574D01*
G03X1330114Y436427I200J1D01*
G02X1330599Y435321I-1019J-1106D01*
G02X1329097Y433819I-1502J0D01*
G02X1327991Y434304I0J1504D01*
G03X1327844Y434369I-148J-135D01*
G01X1327550D01*
G03X1327403Y434304I1J-200D01*
G02X1326297Y433819I-1106J1019D01*
G02X1324795Y435321I0J1502D01*
G02X1325280Y436427I1504J0D01*
G03X1325345Y436574I-135J148D01*
G01Y436868D01*
G03X1325280Y437015I-200J-1D01*
G02Y439227I1017J1106D01*
G03X1325345Y439374I-135J148D01*
G01Y439668D01*
G03X1325280Y439815I-200J-1D01*
G02Y442027I1017J1106D01*
G03X1325345Y442174I-135J148D01*
G37*
G36*
G01X1782432D02*
Y442468D01*
G03X1782367Y442615I-200J-1D01*
G02X1781882Y443721I1019J1106D01*
G02X1783384Y445223I1502J0D01*
G02X1784490Y444738I0J-1504D01*
G03X1784637Y444673I148J135D01*
G01X1784931D01*
G03X1785078Y444738I-1J200D01*
G02X1786184Y445223I1106J-1019D01*
G02X1787686Y443721I0J-1502D01*
G02X1787201Y442615I-1504J0D01*
G03X1787136Y442468I135J-148D01*
G01Y442174D01*
G03X1787201Y442027I200J1D01*
G02Y439815I-1017J-1106D01*
G03X1787136Y439668I135J-148D01*
G01Y439374D01*
G03X1787201Y439227I200J1D01*
G02Y437015I-1017J-1106D01*
G03X1787136Y436868I135J-148D01*
G01Y436574D01*
G03X1787201Y436427I200J1D01*
G02X1787686Y435321I-1019J-1106D01*
G02X1786184Y433819I-1502J0D01*
G02X1785078Y434304I0J1504D01*
G03X1784931Y434369I-148J-135D01*
G01X1784637D01*
G03X1784490Y434304I1J-200D01*
G02X1783384Y433819I-1106J1019D01*
G02X1781882Y435321I0J1502D01*
G02X1782367Y436427I1504J0D01*
G03X1782432Y436574I-135J148D01*
G01Y436868D01*
G03X1782367Y437015I-200J-1D01*
G02Y439227I1017J1106D01*
G03X1782432Y439374I-135J148D01*
G01Y439668D01*
G03X1782367Y439815I-200J-1D01*
G02Y442027I1017J1106D01*
G03X1782432Y442174I-135J148D01*
G37*
G36*
G01X384632Y442346D02*
Y442640D01*
G03X384567Y442787I-200J-1D01*
G02X384082Y443893I1019J1106D01*
G02X387086I1502J0D01*
G02X386601Y442787I-1504J0D01*
G03X386536Y442640I135J-148D01*
G01Y442346D01*
G03X386601Y442199I200J1D01*
G02Y439987I-1017J-1106D01*
G03X386536Y439840I135J-148D01*
G01Y439546D01*
G03X386601Y439399I200J1D01*
G02X387086Y438293I-1019J-1106D01*
G02X384082I-1502J0D01*
G02X384567Y439399I1504J0D01*
G03X384632Y439546I-135J148D01*
G01Y439840D01*
G03X384567Y439987I-200J-1D01*
G02Y442199I1017J1106D01*
G03X384632Y442346I-135J148D01*
G37*
G36*
G01X394625D02*
Y442640D01*
G03X394560Y442787I-200J-1D01*
G02X394075Y443893I1019J1106D01*
G02X397079I1502J0D01*
G02X396594Y442787I-1504J0D01*
G03X396529Y442640I135J-148D01*
G01Y442346D01*
G03X396594Y442199I200J1D01*
G02Y439987I-1017J-1106D01*
G03X396529Y439840I135J-148D01*
G01Y439546D01*
G03X396594Y439399I200J1D01*
G02X397079Y438293I-1019J-1106D01*
G02X394075I-1502J0D01*
G02X394560Y439399I1504J0D01*
G03X394625Y439546I-135J148D01*
G01Y439840D01*
G03X394560Y439987I-200J-1D01*
G02Y442199I1017J1106D01*
G03X394625Y442346I-135J148D01*
G37*
G36*
G01X1298805D02*
Y442640D01*
G03X1298740Y442787I-200J-1D01*
G02X1298255Y443893I1019J1106D01*
G02X1301259I1502J0D01*
G02X1300774Y442787I-1504J0D01*
G03X1300709Y442640I135J-148D01*
G01Y442346D01*
G03X1300774Y442199I200J1D01*
G02Y439987I-1017J-1106D01*
G03X1300709Y439840I135J-148D01*
G01Y439546D01*
G03X1300774Y439399I200J1D01*
G02X1301259Y438293I-1019J-1106D01*
G02X1298255I-1502J0D01*
G02X1298740Y439399I1504J0D01*
G03X1298805Y439546I-135J148D01*
G01Y439840D01*
G03X1298740Y439987I-200J-1D01*
G02Y442199I1017J1106D01*
G03X1298805Y442346I-135J148D01*
G37*
G36*
G01X1308798D02*
Y442640D01*
G03X1308733Y442787I-200J-1D01*
G02X1308248Y443893I1019J1106D01*
G02X1311252I1502J0D01*
G02X1310767Y442787I-1504J0D01*
G03X1310702Y442640I135J-148D01*
G01Y442346D01*
G03X1310767Y442199I200J1D01*
G02Y439987I-1017J-1106D01*
G03X1310702Y439840I135J-148D01*
G01Y439546D01*
G03X1310767Y439399I200J1D01*
G02X1311252Y438293I-1019J-1106D01*
G02X1308248I-1502J0D01*
G02X1308733Y439399I1504J0D01*
G03X1308798Y439546I-135J148D01*
G01Y439840D01*
G03X1308733Y439987I-200J-1D01*
G02Y442199I1017J1106D01*
G03X1308798Y442346I-135J148D01*
G37*
G36*
G01X1755892D02*
Y442640D01*
G03X1755827Y442787I-200J-1D01*
G02X1755342Y443893I1019J1106D01*
G02X1758346I1502J0D01*
G02X1757861Y442787I-1504J0D01*
G03X1757796Y442640I135J-148D01*
G01Y442346D01*
G03X1757861Y442199I200J1D01*
G02Y439987I-1017J-1106D01*
G03X1757796Y439840I135J-148D01*
G01Y439546D01*
G03X1757861Y439399I200J1D01*
G02X1758346Y438293I-1019J-1106D01*
G02X1755342I-1502J0D01*
G02X1755827Y439399I1504J0D01*
G03X1755892Y439546I-135J148D01*
G01Y439840D01*
G03X1755827Y439987I-200J-1D01*
G02Y442199I1017J1106D01*
G03X1755892Y442346I-135J148D01*
G37*
G36*
G01X1765885D02*
Y442640D01*
G03X1765820Y442787I-200J-1D01*
G02X1765335Y443893I1019J1106D01*
G02X1768339I1502J0D01*
G02X1767854Y442787I-1504J0D01*
G03X1767789Y442640I135J-148D01*
G01Y442346D01*
G03X1767854Y442199I200J1D01*
G02Y439987I-1017J-1106D01*
G03X1767789Y439840I135J-148D01*
G01Y439546D01*
G03X1767854Y439399I200J1D01*
G02X1768339Y438293I-1019J-1106D01*
G02X1765335I-1502J0D01*
G02X1765820Y439399I1504J0D01*
G03X1765885Y439546I-135J148D01*
G01Y439840D01*
G03X1765820Y439987I-200J-1D01*
G02Y442199I1017J1106D01*
G03X1765885Y442346I-135J148D01*
G37*
G36*
G01X263195Y445730D02*
G03X263555Y446227I-28J399D01*
G02X263509Y446595I1456J369D01*
G02X266513I1502J0D01*
G02X265117Y445097I-1502J0D01*
G03X264757Y444600I28J-399D01*
G02X264803Y444232I-1456J-369D01*
G02X261799I-1502J0D01*
G02X263195Y445730I1502J0D01*
G37*
G36*
G01X291805Y454177D02*
G02X293307Y455679I1502J0D01*
G02X294294Y455309I0J-1501D01*
G01X294295D01*
Y455308D01*
G03X294425Y455260I130J152D01*
G01X294689D01*
G03X294819Y455308I0J200D01*
G01X294820Y455309D01*
G02X295807Y455679I987J-1131D01*
G02X297309Y454177I0J-1502D01*
G02X296939Y453190I-1501J0D01*
G01Y453189D01*
X296938D01*
G03X296890Y453059I152J-130D01*
G01Y452795D01*
G03X296938Y452665I200J0D01*
G01X296939Y452664D01*
G02X297309Y451677I-1131J-987D01*
G02X295807Y450175I-1502J0D01*
G02X294820Y450545I0J1501D01*
G01X294819D01*
Y450546D01*
G03X294689Y450594I-130J-152D01*
G01X294425D01*
G03X294295Y450546I0J-200D01*
G01X294294Y450545D01*
G02X293307Y450175I-987J1131D01*
G02X291805Y451677I0J1502D01*
G02X292175Y452664I1501J0D01*
G01Y452665D01*
X292176D01*
G03X292224Y452795I-152J130D01*
G01Y453059D01*
G03X292176Y453189I-200J0D01*
G01X292175Y453190D01*
G02X291805Y454177I1131J987D01*
G37*
G36*
G01X748891D02*
G02X750393Y455679I1502J0D01*
G02X751380Y455309I0J-1501D01*
G01X751381D01*
Y455308D01*
G03X751511Y455260I130J152D01*
G01X751775D01*
G03X751905Y455308I0J200D01*
G01X751906Y455309D01*
G02X752893Y455679I987J-1131D01*
G02X754395Y454177I0J-1502D01*
G02X754025Y453190I-1501J0D01*
G01Y453189D01*
X754024D01*
G03X753976Y453059I152J-130D01*
G01Y452795D01*
G03X754024Y452665I200J0D01*
G01X754025Y452664D01*
G02X754395Y451677I-1131J-987D01*
G02X752893Y450175I-1502J0D01*
G02X751906Y450545I0J1501D01*
G01X751905D01*
Y450546D01*
G03X751775Y450594I-130J-152D01*
G01X751511D01*
G03X751381Y450546I0J-200D01*
G01X751380Y450545D01*
G02X750393Y450175I-987J1131D01*
G02X748891Y451677I0J1502D01*
G02X749261Y452664I1501J0D01*
G01Y452665D01*
X749262D01*
G03X749310Y452795I-152J130D01*
G01Y453059D01*
G03X749262Y453189I-200J0D01*
G01X749261Y453190D01*
G02X748891Y454177I1131J987D01*
G37*
G36*
G01X1205978D02*
G02X1207480Y455679I1502J0D01*
G02X1208467Y455309I0J-1501D01*
G01X1208468D01*
Y455308D01*
G03X1208598Y455260I130J152D01*
G01X1208862D01*
G03X1208992Y455308I0J200D01*
G01X1208993Y455309D01*
G02X1209980Y455679I987J-1131D01*
G02X1211482Y454177I0J-1502D01*
G02X1211112Y453190I-1501J0D01*
G01Y453189D01*
X1211111D01*
G03X1211063Y453059I152J-130D01*
G01Y452795D01*
G03X1211111Y452665I200J0D01*
G01X1211112Y452664D01*
G02X1211482Y451677I-1131J-987D01*
G02X1209980Y450175I-1502J0D01*
G02X1208993Y450545I0J1501D01*
G01X1208992D01*
Y450546D01*
G03X1208862Y450594I-130J-152D01*
G01X1208598D01*
G03X1208468Y450546I0J-200D01*
G01X1208467Y450545D01*
G02X1207480Y450175I-987J1131D01*
G02X1205978Y451677I0J1502D01*
G02X1206348Y452664I1501J0D01*
G01Y452665D01*
X1206349D01*
G03X1206397Y452795I-152J130D01*
G01Y453059D01*
G03X1206349Y453189I-200J0D01*
G01X1206348Y453190D01*
G02X1205978Y454177I1131J987D01*
G37*
G36*
G01X1663065D02*
G02X1664567Y455679I1502J0D01*
G02X1665554Y455309I0J-1501D01*
G01X1665555D01*
Y455308D01*
G03X1665685Y455260I130J152D01*
G01X1665949D01*
G03X1666079Y455308I0J200D01*
G01X1666080Y455309D01*
G02X1667067Y455679I987J-1131D01*
G02X1668569Y454177I0J-1502D01*
G02X1668199Y453190I-1501J0D01*
G01Y453189D01*
X1668198D01*
G03X1668150Y453059I152J-130D01*
G01Y452795D01*
G03X1668198Y452665I200J0D01*
G01X1668199Y452664D01*
G02X1668569Y451677I-1131J-987D01*
G02X1667067Y450175I-1502J0D01*
G02X1666080Y450545I0J1501D01*
G01X1666079D01*
Y450546D01*
G03X1665949Y450594I-130J-152D01*
G01X1665685D01*
G03X1665555Y450546I0J-200D01*
G01X1665554Y450545D01*
G02X1664567Y450175I-987J1131D01*
G02X1663065Y451677I0J1502D01*
G02X1663435Y452664I1501J0D01*
G01Y452665D01*
X1663436D01*
G03X1663484Y452795I-152J130D01*
G01Y453059D01*
G03X1663436Y453189I-200J0D01*
G01X1663435Y453190D01*
G02X1663065Y454177I1131J987D01*
G37*
G36*
G01X146923Y457759D02*
X146629D01*
G03X146482Y457694I1J-200D01*
G02X145376Y457209I-1106J1019D01*
G02Y460213I0J1502D01*
G02X146482Y459728I0J-1504D01*
G03X146629Y459663I148J135D01*
G01X146923D01*
G03X147070Y459728I-1J200D01*
G02X148176Y460213I1106J-1019D01*
G02X149678Y458711I0J-1502D01*
G02X149418Y457867I-1502J1D01*
G01Y457866D01*
X149393Y457830D01*
X149379Y457746D01*
X149483Y457365D01*
X149539Y457299D01*
X149579Y457280D01*
G02X150442Y455921I-639J-1359D01*
G01Y455918D01*
G02X150418Y455652I-1502J1D01*
G01X150410Y455610D01*
X150431Y455527D01*
X150670Y455224D01*
X150746Y455184D01*
X150789Y455182D01*
G02X152205Y453682I-86J-1500D01*
G02X149201I-1502J0D01*
G01Y453685D01*
G02X149225Y453951I1502J-1D01*
G01X149233Y453993D01*
X149212Y454076D01*
X148973Y454379D01*
X148897Y454419D01*
X148854Y454421D01*
G02X147438Y455921I86J1500D01*
G02X147698Y456765I1502J-1D01*
G01Y456766D01*
X147723Y456802D01*
X147737Y456886D01*
X147633Y457267D01*
X147577Y457333D01*
X147537Y457352D01*
G02X147070Y457694I637J1360D01*
G03X146923Y457759I-148J-135D01*
G37*
G36*
G01X604009D02*
X603715D01*
G03X603568Y457694I1J-200D01*
G02X602462Y457209I-1106J1019D01*
G02Y460213I0J1502D01*
G02X603568Y459728I0J-1504D01*
G03X603715Y459663I148J135D01*
G01X604009D01*
G03X604156Y459728I-1J200D01*
G02X605262Y460213I1106J-1019D01*
G02X606764Y458711I0J-1502D01*
G02X606504Y457867I-1502J1D01*
G01Y457866D01*
X606479Y457830D01*
X606465Y457746D01*
X606569Y457365D01*
X606625Y457299D01*
X606665Y457280D01*
G02X607528Y455921I-639J-1359D01*
G01Y455918D01*
G02X607504Y455652I-1502J1D01*
G01X607496Y455610D01*
X607517Y455527D01*
X607756Y455224D01*
X607832Y455184D01*
X607875Y455182D01*
G02X609291Y453682I-86J-1500D01*
G02X606287I-1502J0D01*
G01Y453685D01*
G02X606311Y453951I1502J-1D01*
G01X606319Y453993D01*
X606298Y454076D01*
X606059Y454379D01*
X605983Y454419D01*
X605940Y454421D01*
G02X604524Y455921I86J1500D01*
G02X604784Y456765I1502J-1D01*
G01Y456766D01*
X604809Y456802D01*
X604823Y456886D01*
X604719Y457267D01*
X604663Y457333D01*
X604623Y457352D01*
G02X604156Y457694I637J1360D01*
G03X604009Y457759I-148J-135D01*
G37*
G36*
G01X1518183D02*
X1517889D01*
G03X1517742Y457694I1J-200D01*
G02X1516636Y457209I-1106J1019D01*
G02Y460213I0J1502D01*
G02X1517742Y459728I0J-1504D01*
G03X1517889Y459663I148J135D01*
G01X1518183D01*
G03X1518330Y459728I-1J200D01*
G02X1519436Y460213I1106J-1019D01*
G02X1520938Y458711I0J-1502D01*
G02X1520678Y457867I-1502J1D01*
G01Y457866D01*
X1520653Y457830D01*
X1520639Y457746D01*
X1520743Y457365D01*
X1520799Y457299D01*
X1520839Y457280D01*
G02X1521702Y455921I-639J-1359D01*
G01Y455918D01*
G02X1521678Y455652I-1502J1D01*
G01X1521670Y455610D01*
X1521691Y455527D01*
X1521930Y455224D01*
X1522006Y455184D01*
X1522049Y455182D01*
G02X1523465Y453682I-86J-1500D01*
G02X1520461I-1502J0D01*
G01Y453685D01*
G02X1520485Y453951I1502J-1D01*
G01X1520493Y453993D01*
X1520472Y454076D01*
X1520233Y454379D01*
X1520157Y454419D01*
X1520114Y454421D01*
G02X1518698Y455921I86J1500D01*
G02X1518958Y456765I1502J-1D01*
G01Y456766D01*
X1518983Y456802D01*
X1518997Y456886D01*
X1518893Y457267D01*
X1518837Y457333D01*
X1518797Y457352D01*
G02X1518330Y457694I637J1360D01*
G03X1518183Y457759I-148J-135D01*
G37*
G36*
G01X463783Y459589D02*
X463469D01*
G03X463311Y459512I0J-200D01*
G02X462126Y458933I-1185J923D01*
G02Y461937I0J1502D01*
G02X463311Y461358I0J-1502D01*
G03X463469Y461281I158J123D01*
G01X463783D01*
G03X463941Y461358I0J200D01*
G02X465126Y461937I1185J-923D01*
G02Y458933I0J-1502D01*
G02X463941Y459512I0J1502D01*
G03X463783Y459589I-158J-123D01*
G37*
G36*
G01X360411Y461214D02*
X360097D01*
G03X359939Y461137I0J-200D01*
G02X358754Y460558I-1185J923D01*
G02Y463562I0J1502D01*
G02X359939Y462983I0J-1502D01*
G03X360097Y462906I158J123D01*
G01X360411D01*
G03X360569Y462983I0J200D01*
G02X361754Y463562I1185J-923D01*
G02Y460558I0J-1502D01*
G02X360569Y461137I0J1502D01*
G03X360411Y461214I-158J-123D01*
G37*
G36*
G01X1274584D02*
X1274270D01*
G03X1274112Y461137I0J-200D01*
G02X1272927Y460558I-1185J923D01*
G02Y463562I0J1502D01*
G02X1274112Y462983I0J-1502D01*
G03X1274270Y462906I158J123D01*
G01X1274584D01*
G03X1274742Y462983I0J200D01*
G02X1275927Y463562I1185J-923D01*
G02Y460558I0J-1502D01*
G02X1274742Y461137I0J1502D01*
G03X1274584Y461214I-158J-123D01*
G37*
G36*
G01X1731671D02*
X1731357D01*
G03X1731199Y461137I0J-200D01*
G02X1730014Y460558I-1185J923D01*
G02Y463562I0J1502D01*
G02X1731199Y462983I0J-1502D01*
G03X1731357Y462906I158J123D01*
G01X1731671D01*
G03X1731829Y462983I0J200D01*
G02X1733014Y463562I1185J-923D01*
G02Y460558I0J-1502D01*
G02X1731829Y461137I0J1502D01*
G03X1731671Y461214I-158J-123D01*
G37*
G36*
G01X466505Y463720D02*
X466191D01*
G03X466033Y463643I0J-200D01*
G02X464848Y463064I-1185J923D01*
G02Y466068I0J1502D01*
G02X466033Y465489I0J-1502D01*
G03X466191Y465412I158J123D01*
G01X466505D01*
G03X466663Y465489I0J200D01*
G02X467848Y466068I1185J-923D01*
G02Y463064I0J-1502D01*
G02X466663Y463643I0J1502D01*
G03X466505Y463720I-158J-123D01*
G37*
G36*
G01X373546Y468499D02*
G02Y471503I0J1502D01*
G02X374533Y471133I0J-1501D01*
G01X374534D01*
Y471132D01*
G03X374664Y471084I130J152D01*
G01X374928D01*
G03X375058Y471132I0J200D01*
G01X375059Y471133D01*
G02X376046Y471503I987J-1131D01*
G02Y468499I0J-1502D01*
G02X375059Y468869I0J1501D01*
G01X375058D01*
Y468870D01*
G03X374928Y468918I-130J-152D01*
G01X374664D01*
G03X374534Y468870I0J-200D01*
G01X374533Y468869D01*
G02X373546Y468499I-987J1131D01*
G37*
G36*
G01X1287719D02*
G02Y471503I0J1502D01*
G02X1288706Y471133I0J-1501D01*
G01X1288707D01*
Y471132D01*
G03X1288837Y471084I130J152D01*
G01X1289101D01*
G03X1289231Y471132I0J200D01*
G01X1289232Y471133D01*
G02X1290219Y471503I987J-1131D01*
G02Y468499I0J-1502D01*
G02X1289232Y468869I0J1501D01*
G01X1289231D01*
Y468870D01*
G03X1289101Y468918I-130J-152D01*
G01X1288837D01*
G03X1288707Y468870I0J-200D01*
G01X1288706Y468869D01*
G02X1287719Y468499I-987J1131D01*
G37*
G36*
G01X1744806D02*
G02Y471503I0J1502D01*
G02X1745793Y471133I0J-1501D01*
G01X1745794D01*
Y471132D01*
G03X1745924Y471084I130J152D01*
G01X1746188D01*
G03X1746318Y471132I0J200D01*
G01X1746319Y471133D01*
G02X1747306Y471503I987J-1131D01*
G02Y468499I0J-1502D01*
G02X1746319Y468869I0J1501D01*
G01X1746318D01*
Y468870D01*
G03X1746188Y468918I-130J-152D01*
G01X1745924D01*
G03X1745794Y468870I0J-200D01*
G01X1745793Y468869D01*
G02X1744806Y468499I-987J1131D01*
G37*
G36*
G01X466505Y475689D02*
X466191D01*
G03X466033Y475612I0J-200D01*
G02X464848Y475033I-1185J923D01*
G02Y478037I0J1502D01*
G02X466033Y477458I0J-1502D01*
G03X466191Y477381I158J123D01*
G01X466505D01*
G03X466663Y477458I0J200D01*
G02X467848Y478037I1185J-923D01*
G02Y475033I0J-1502D01*
G02X466663Y475612I0J1502D01*
G03X466505Y475689I-158J-123D01*
G37*
G36*
G01X357742Y475551D02*
G02Y478555I0J1502D01*
G02X358729Y478185I0J-1501D01*
G01X358730D01*
Y478184D01*
G03X358860Y478136I130J152D01*
G01X359124D01*
G03X359254Y478184I0J200D01*
G01X359255Y478185D01*
G02X360242Y478555I987J-1131D01*
G02Y475551I0J-1502D01*
G02X359255Y475921I0J1501D01*
G01X359254D01*
Y475922D01*
G03X359124Y475970I-130J-152D01*
G01X358860D01*
G03X358730Y475922I0J-200D01*
G01X358729Y475921D01*
G02X357742Y475551I-987J1131D01*
G37*
G36*
G01X1271915D02*
G02Y478555I0J1502D01*
G02X1272902Y478185I0J-1501D01*
G01X1272903D01*
Y478184D01*
G03X1273033Y478136I130J152D01*
G01X1273297D01*
G03X1273427Y478184I0J200D01*
G01X1273428Y478185D01*
G02X1274415Y478555I987J-1131D01*
G02Y475551I0J-1502D01*
G02X1273428Y475921I0J1501D01*
G01X1273427D01*
Y475922D01*
G03X1273297Y475970I-130J-152D01*
G01X1273033D01*
G03X1272903Y475922I0J-200D01*
G01X1272902Y475921D01*
G02X1271915Y475551I-987J1131D01*
G37*
G36*
G01X1729002D02*
G02Y478555I0J1502D01*
G02X1729989Y478185I0J-1501D01*
G01X1729990D01*
Y478184D01*
G03X1730120Y478136I130J152D01*
G01X1730384D01*
G03X1730514Y478184I0J200D01*
G01X1730515Y478185D01*
G02X1731502Y478555I987J-1131D01*
G02Y475551I0J-1502D01*
G02X1730515Y475921I0J1501D01*
G01X1730514D01*
Y475922D01*
G03X1730384Y475970I-130J-152D01*
G01X1730120D01*
G03X1729990Y475922I0J-200D01*
G01X1729989Y475921D01*
G02X1729002Y475551I-987J1131D01*
G37*
G36*
G01X54172Y477078D02*
Y477372D01*
G03X54107Y477519I-200J-1D01*
G02X53622Y478625I1019J1106D01*
G02X56626I1502J0D01*
G02X56141Y477519I-1504J0D01*
G03X56076Y477372I135J-148D01*
G01Y477078D01*
G03X56141Y476931I200J1D01*
G02X56626Y475825I-1019J-1106D01*
G02X53622I-1502J0D01*
G02X54107Y476931I1504J0D01*
G03X54172Y477078I-135J148D01*
G37*
G36*
G01X511258D02*
Y477372D01*
G03X511193Y477519I-200J-1D01*
G02X510708Y478625I1019J1106D01*
G02X513712I1502J0D01*
G02X513227Y477519I-1504J0D01*
G03X513162Y477372I135J-148D01*
G01Y477078D01*
G03X513227Y476931I200J1D01*
G02X513712Y475825I-1019J-1106D01*
G02X510708I-1502J0D01*
G02X511193Y476931I1504J0D01*
G03X511258Y477078I-135J148D01*
G37*
G36*
G01X968345D02*
Y477372D01*
G03X968280Y477519I-200J-1D01*
G02X967795Y478625I1019J1106D01*
G02X970799I1502J0D01*
G02X970314Y477519I-1504J0D01*
G03X970249Y477372I135J-148D01*
G01Y477078D01*
G03X970314Y476931I200J1D01*
G02X970799Y475825I-1019J-1106D01*
G02X967795I-1502J0D01*
G02X968280Y476931I1504J0D01*
G03X968345Y477078I-135J148D01*
G37*
G36*
G01X1424882Y478625D02*
G02X1427886I1502J0D01*
G02X1427516Y477638I-1501J0D01*
G01Y477637D01*
X1427515D01*
G03X1427467Y477507I152J-130D01*
G01Y477243D01*
G03X1427515Y477113I200J0D01*
G01X1427516Y477112D01*
G02X1427886Y476125I-1131J-987D01*
G02X1424882I-1502J0D01*
G02X1425252Y477112I1501J0D01*
G01Y477113D01*
X1425253D01*
G03X1425301Y477243I-152J130D01*
G01Y477507D01*
G03X1425253Y477637I-200J0D01*
G01X1425252Y477638D01*
G02X1424882Y478625I1131J987D01*
G37*
G36*
G01X1733450Y479217D02*
G02X1734952Y480719I1502J0D01*
G02X1735827Y480438I0J-1503D01*
G01X1735860Y480414D01*
X1735939Y480396D01*
X1736263Y480456D01*
G03X1736394Y480542I-35J197D01*
G02X1737646Y481215I1252J-828D01*
G02X1739148Y479713I0J-1502D01*
G02X1738778Y478726I-1501J0D01*
G01Y478725D01*
X1738777D01*
G03X1738729Y478595I152J-130D01*
G01Y478331D01*
G03X1738777Y478201I200J0D01*
G01X1738778Y478200D01*
G02X1739148Y477213I-1131J-987D01*
G02X1737646Y475711I-1502J0D01*
G02X1736771Y475992I0J1503D01*
G01X1736738Y476016D01*
X1736659Y476034D01*
X1736335Y475974D01*
G03X1736204Y475888I35J-197D01*
G02X1734952Y475215I-1252J828D01*
G02X1733450Y476717I0J1502D01*
G02X1733820Y477704I1501J0D01*
G01Y477705D01*
X1733821D01*
G03X1733869Y477835I-152J130D01*
G01Y478099D01*
G03X1733821Y478229I-200J0D01*
G01X1733820Y478230D01*
G02X1733450Y479217I1131J987D01*
G37*
G36*
G01X366420Y481488D02*
G02X367922Y479986I0J-1502D01*
G02X367552Y478999I-1501J0D01*
G01Y478998D01*
X367551D01*
G03X367503Y478868I152J-130D01*
G01Y478604D01*
G03X367551Y478474I200J0D01*
G01X367552Y478473D01*
G02X367922Y477486I-1131J-987D01*
G02X366420Y475984I-1502J0D01*
G02X365735Y476150I1J1502D01*
G01X365733D01*
G03X365556Y476152I-91J-178D01*
G01X365225Y475993D01*
X365168Y475919D01*
X365159Y475873D01*
G02X363686Y474666I-1473J295D01*
G02X362184Y476168I0J1502D01*
G02X362554Y477155I1501J0D01*
G01Y477156D01*
X362555D01*
G03X362603Y477286I-152J130D01*
G01Y477550D01*
G03X362555Y477680I-200J0D01*
G01X362554Y477681D01*
G02X362184Y478668I1131J987D01*
G02X363686Y480170I1502J0D01*
G02X364371Y480004I-1J-1502D01*
G01X364373D01*
G03X364550Y480002I91J178D01*
G01X364881Y480161D01*
X364938Y480235D01*
X364947Y480281D01*
G02X366420Y481488I1473J-295D01*
G37*
G36*
G01X1280631Y481696D02*
G02X1282133Y480194I0J-1502D01*
G02X1281763Y479207I-1501J0D01*
G01Y479206D01*
X1281762D01*
G03X1281714Y479076I152J-130D01*
G01Y478812D01*
G03X1281762Y478682I200J0D01*
G01X1281763Y478681D01*
G02X1282133Y477694I-1131J-987D01*
G02X1280631Y476192I-1502J0D01*
G02X1279946Y476358I1J1502D01*
G01X1279944D01*
G03X1279767Y476360I-91J-178D01*
G01X1279436Y476201D01*
X1279379Y476127D01*
X1279370Y476081D01*
G02X1277897Y474874I-1473J295D01*
G02X1276395Y476376I0J1502D01*
G02X1276765Y477363I1501J0D01*
G01Y477364D01*
X1276766D01*
G03X1276814Y477494I-152J130D01*
G01Y477758D01*
G03X1276766Y477888I-200J0D01*
G01X1276765Y477889D01*
G02X1276395Y478876I1131J987D01*
G02X1277897Y480378I1502J0D01*
G02X1278582Y480212I-1J-1502D01*
G01X1278584D01*
G03X1278761Y480210I91J178D01*
G01X1279092Y480369D01*
X1279149Y480443D01*
X1279158Y480489D01*
G02X1280631Y481696I1473J-295D01*
G37*
G36*
G01X352168Y481071D02*
G02X355172I1502J0D01*
G02X354802Y480084I-1501J0D01*
G01Y480083D01*
X354801D01*
G03X354753Y479953I152J-130D01*
G01Y479689D01*
G03X354801Y479559I200J0D01*
G01X354802Y479558D01*
G02Y477584I-1131J-987D01*
G01Y477583D01*
X354801D01*
G03X354753Y477453I152J-130D01*
G01Y477189D01*
G03X354801Y477059I200J0D01*
G01X354802Y477058D01*
G02Y475084I-1131J-987D01*
G01Y475083D01*
X354801D01*
G03X354753Y474953I152J-130D01*
G01Y474689D01*
G03X354801Y474559I200J0D01*
G01X354802Y474558D01*
G02X355172Y473571I-1131J-987D01*
G02X352168I-1502J0D01*
G02X352538Y474558I1501J0D01*
G01Y474559D01*
X352539D01*
G03X352587Y474689I-152J130D01*
G01Y474953D01*
G03X352539Y475083I-200J0D01*
G01X352538Y475084D01*
G02Y477058I1131J987D01*
G01Y477059D01*
X352539D01*
G03X352587Y477189I-152J130D01*
G01Y477453D01*
G03X352539Y477583I-200J0D01*
G01X352538Y477584D01*
G02Y479558I1131J987D01*
G01Y479559D01*
X352539D01*
G03X352587Y479689I-152J130D01*
G01Y479953D01*
G03X352539Y480083I-200J0D01*
G01X352538Y480084D01*
G02X352168Y481071I1131J987D01*
G37*
G36*
G01X1266341D02*
G02X1269345I1502J0D01*
G02X1268975Y480084I-1501J0D01*
G01Y480083D01*
X1268974D01*
G03X1268926Y479953I152J-130D01*
G01Y479689D01*
G03X1268974Y479559I200J0D01*
G01X1268975Y479558D01*
G02Y477584I-1131J-987D01*
G01Y477583D01*
X1268974D01*
G03X1268926Y477453I152J-130D01*
G01Y477189D01*
G03X1268974Y477059I200J0D01*
G01X1268975Y477058D01*
G02Y475084I-1131J-987D01*
G01Y475083D01*
X1268974D01*
G03X1268926Y474953I152J-130D01*
G01Y474689D01*
G03X1268974Y474559I200J0D01*
G01X1268975Y474558D01*
G02X1269345Y473571I-1131J-987D01*
G02X1266341I-1502J0D01*
G02X1266711Y474558I1501J0D01*
G01Y474559D01*
X1266712D01*
G03X1266760Y474689I-152J130D01*
G01Y474953D01*
G03X1266712Y475083I-200J0D01*
G01X1266711Y475084D01*
G02Y477058I1131J987D01*
G01Y477059D01*
X1266712D01*
G03X1266760Y477189I-152J130D01*
G01Y477453D01*
G03X1266712Y477583I-200J0D01*
G01X1266711Y477584D01*
G02Y479558I1131J987D01*
G01Y479559D01*
X1266712D01*
G03X1266760Y479689I-152J130D01*
G01Y479953D01*
G03X1266712Y480083I-200J0D01*
G01X1266711Y480084D01*
G02X1266341Y481071I1131J987D01*
G37*
G36*
G01X1723428D02*
G02X1726432I1502J0D01*
G02X1726062Y480084I-1501J0D01*
G01Y480083D01*
X1726061D01*
G03X1726013Y479953I152J-130D01*
G01Y479689D01*
G03X1726061Y479559I200J0D01*
G01X1726062Y479558D01*
G02Y477584I-1131J-987D01*
G01Y477583D01*
X1726061D01*
G03X1726013Y477453I152J-130D01*
G01Y477189D01*
G03X1726061Y477059I200J0D01*
G01X1726062Y477058D01*
G02Y475084I-1131J-987D01*
G01Y475083D01*
X1726061D01*
G03X1726013Y474953I152J-130D01*
G01Y474689D01*
G03X1726061Y474559I200J0D01*
G01X1726062Y474558D01*
G02X1726432Y473571I-1131J-987D01*
G02X1723428I-1502J0D01*
G02X1723798Y474558I1501J0D01*
G01Y474559D01*
X1723799D01*
G03X1723847Y474689I-152J130D01*
G01Y474953D01*
G03X1723799Y475083I-200J0D01*
G01X1723798Y475084D01*
G02Y477058I1131J987D01*
G01Y477059D01*
X1723799D01*
G03X1723847Y477189I-152J130D01*
G01Y477453D01*
G03X1723799Y477583I-200J0D01*
G01X1723798Y477584D01*
G02Y479558I1131J987D01*
G01Y479559D01*
X1723799D01*
G03X1723847Y479689I-152J130D01*
G01Y479953D01*
G03X1723799Y480083I-200J0D01*
G01X1723798Y480084D01*
G02X1723428Y481071I1131J987D01*
G37*
G36*
G01X54726Y486270D02*
X54727Y486269D01*
G03X54857Y486221I130J152D01*
G01X55121D01*
G03X55251Y486269I0J200D01*
G01X55252Y486270D01*
G02X56239Y486640I987J-1131D01*
G02X57741Y485138I0J-1502D01*
G02X57474Y484283I-1502J0D01*
G01X57451Y484249D01*
X57434Y484168D01*
X57514Y483801D01*
X57562Y483734D01*
X57597Y483713D01*
G02X58326Y482425I-773J-1288D01*
G02X55322I-1502J0D01*
G02X55589Y483280I1502J0D01*
G01X55612Y483314D01*
X55629Y483395D01*
X55549Y483762D01*
X55501Y483829D01*
X55466Y483850D01*
G02X55253Y484006I777J1285D01*
G03X55251Y484007I-88J-173D01*
G03X55121Y484055I-130J-152D01*
G01X54857D01*
G03X54727Y484007I0J-200D01*
G01X54726Y484006D01*
G02X52752I-987J1131D01*
G01X52751D01*
Y484007D01*
G03X52621Y484055I-130J-152D01*
G01X52357D01*
G03X52227Y484007I0J-200D01*
G01X52226Y484006D01*
G02X51239Y483636I-987J1131D01*
G02X50118Y484139I0J1501D01*
G01X50089Y484172D01*
X50012Y484206D01*
X49667Y484204D01*
G03X49519Y484138I0J-200D01*
G01X49518Y484137D01*
G02X48390Y483626I-1129J991D01*
G02Y486630I0J1502D01*
G02X49511Y486127I0J-1501D01*
G01X49540Y486094D01*
X49617Y486060D01*
X49962Y486062D01*
G03X50110Y486128I0J200D01*
G01X50111Y486129D01*
G02X51239Y486640I1129J-991D01*
G02X52226Y486270I0J-1501D01*
G01X52227D01*
Y486269D01*
G03X52357Y486221I130J152D01*
G01X52621D01*
G03X52751Y486269I0J200D01*
G01X52752Y486270D01*
G02X54726I987J-1131D01*
G37*
G36*
G01X511812D02*
X511813Y486269D01*
G03X511943Y486221I130J152D01*
G01X512207D01*
G03X512337Y486269I0J200D01*
G01X512338Y486270D01*
G02X513325Y486640I987J-1131D01*
G02X514827Y485138I0J-1502D01*
G02X514560Y484283I-1502J0D01*
G01X514537Y484249D01*
X514520Y484168D01*
X514600Y483801D01*
X514648Y483734D01*
X514683Y483713D01*
G02X515412Y482425I-773J-1288D01*
G02X512408I-1502J0D01*
G02X512675Y483280I1502J0D01*
G01X512698Y483314D01*
X512715Y483395D01*
X512635Y483762D01*
X512587Y483829D01*
X512552Y483850D01*
G02X512339Y484006I777J1285D01*
G03X512337Y484007I-88J-173D01*
G03X512207Y484055I-130J-152D01*
G01X511943D01*
G03X511813Y484007I0J-200D01*
G01X511812Y484006D01*
G02X509838I-987J1131D01*
G01X509837D01*
Y484007D01*
G03X509707Y484055I-130J-152D01*
G01X509443D01*
G03X509313Y484007I0J-200D01*
G01X509312Y484006D01*
G02X508325Y483636I-987J1131D01*
G02X507204Y484139I0J1501D01*
G01X507175Y484172D01*
X507098Y484206D01*
X506753Y484204D01*
G03X506605Y484138I0J-200D01*
G01X506604Y484137D01*
G02X505476Y483626I-1129J991D01*
G02Y486630I0J1502D01*
G02X506597Y486127I0J-1501D01*
G01X506626Y486094D01*
X506703Y486060D01*
X507048Y486062D01*
G03X507196Y486128I0J200D01*
G01X507197Y486129D01*
G02X508325Y486640I1129J-991D01*
G02X509312Y486270I0J-1501D01*
G01X509313D01*
Y486269D01*
G03X509443Y486221I130J152D01*
G01X509707D01*
G03X509837Y486269I0J200D01*
G01X509838Y486270D01*
G02X511812I987J-1131D01*
G37*
G36*
G01X968899D02*
X968900Y486269D01*
G03X969030Y486221I130J152D01*
G01X969294D01*
G03X969424Y486269I0J200D01*
G01X969425Y486270D01*
G02X970412Y486640I987J-1131D01*
G02X971914Y485138I0J-1502D01*
G02X971647Y484283I-1502J0D01*
G01X971624Y484249D01*
X971607Y484168D01*
X971687Y483801D01*
X971735Y483734D01*
X971770Y483713D01*
G02X972499Y482425I-773J-1288D01*
G02X969495I-1502J0D01*
G02X969762Y483280I1502J0D01*
G01X969785Y483314D01*
X969802Y483395D01*
X969722Y483762D01*
X969674Y483829D01*
X969639Y483850D01*
G02X969426Y484006I777J1285D01*
G03X969424Y484007I-88J-173D01*
G03X969294Y484055I-130J-152D01*
G01X969030D01*
G03X968900Y484007I0J-200D01*
G01X968899Y484006D01*
G02X966925I-987J1131D01*
G01X966924D01*
Y484007D01*
G03X966794Y484055I-130J-152D01*
G01X966530D01*
G03X966400Y484007I0J-200D01*
G01X966399Y484006D01*
G02X965412Y483636I-987J1131D01*
G02X964291Y484139I0J1501D01*
G01X964262Y484172D01*
X964185Y484206D01*
X963840Y484204D01*
G03X963692Y484138I0J-200D01*
G01X963691Y484137D01*
G02X962563Y483626I-1129J991D01*
G02Y486630I0J1502D01*
G02X963684Y486127I0J-1501D01*
G01X963713Y486094D01*
X963790Y486060D01*
X964135Y486062D01*
G03X964283Y486128I0J200D01*
G01X964284Y486129D01*
G02X965412Y486640I1129J-991D01*
G02X966399Y486270I0J-1501D01*
G01X966400D01*
Y486269D01*
G03X966530Y486221I130J152D01*
G01X966794D01*
G03X966924Y486269I0J200D01*
G01X966925Y486270D01*
G02X968899I987J-1131D01*
G37*
G36*
G01X375319Y486712D02*
X375320Y486711D01*
G03X375450Y486663I130J152D01*
G01X375714D01*
G03X375844Y486711I0J200D01*
G01X375845Y486712D01*
G02X376832Y487082I987J-1131D01*
G02Y484078I0J-1502D01*
G02X375845Y484448I0J1501D01*
G01X375844D01*
Y484449D01*
G03X375714Y484497I-130J-152D01*
G01X375450D01*
G03X375320Y484449I0J-200D01*
G01X375319Y484448D01*
G02X373345I-987J1131D01*
G01X373344D01*
Y484449D01*
G03X373214Y484497I-130J-152D01*
G01X372950D01*
G03X372820Y484449I0J-200D01*
G01X372819Y484448D01*
G02X371832Y484078I-987J1131D01*
G02Y487082I0J1502D01*
G02X372819Y486712I0J-1501D01*
G01X372820D01*
Y486711D01*
G03X372950Y486663I130J152D01*
G01X373214D01*
G03X373344Y486711I0J200D01*
G01X373345Y486712D01*
G02X375319I987J-1131D01*
G37*
G36*
G01X1289492D02*
X1289493Y486711D01*
G03X1289623Y486663I130J152D01*
G01X1289887D01*
G03X1290017Y486711I0J200D01*
G01X1290018Y486712D01*
G02X1291005Y487082I987J-1131D01*
G02Y484078I0J-1502D01*
G02X1290018Y484448I0J1501D01*
G01X1290017D01*
Y484449D01*
G03X1289887Y484497I-130J-152D01*
G01X1289623D01*
G03X1289493Y484449I0J-200D01*
G01X1289492Y484448D01*
G02X1287518I-987J1131D01*
G01X1287517D01*
Y484449D01*
G03X1287387Y484497I-130J-152D01*
G01X1287123D01*
G03X1286993Y484449I0J-200D01*
G01X1286992Y484448D01*
G02X1286005Y484078I-987J1131D01*
G02Y487082I0J1502D01*
G02X1286992Y486712I0J-1501D01*
G01X1286993D01*
Y486711D01*
G03X1287123Y486663I130J152D01*
G01X1287387D01*
G03X1287517Y486711I0J200D01*
G01X1287518Y486712D01*
G02X1289492I987J-1131D01*
G37*
G36*
G01X1746579D02*
X1746580Y486711D01*
G03X1746710Y486663I130J152D01*
G01X1746974D01*
G03X1747104Y486711I0J200D01*
G01X1747105Y486712D01*
G02X1748092Y487082I987J-1131D01*
G02Y484078I0J-1502D01*
G02X1747105Y484448I0J1501D01*
G01X1747104D01*
Y484449D01*
G03X1746974Y484497I-130J-152D01*
G01X1746710D01*
G03X1746580Y484449I0J-200D01*
G01X1746579Y484448D01*
G02X1744605I-987J1131D01*
G01X1744604D01*
Y484449D01*
G03X1744474Y484497I-130J-152D01*
G01X1744210D01*
G03X1744080Y484449I0J-200D01*
G01X1744079Y484448D01*
G02X1743092Y484078I-987J1131D01*
G02Y487082I0J1502D01*
G02X1744079Y486712I0J-1501D01*
G01X1744080D01*
Y486711D01*
G03X1744210Y486663I130J152D01*
G01X1744474D01*
G03X1744604Y486711I0J200D01*
G01X1744605Y486712D01*
G02X1746579I987J-1131D01*
G37*
G36*
G01X61198Y493714D02*
G02X64202I1502J0D01*
G02X63832Y492727I-1501J0D01*
G01Y492726D01*
X63831D01*
G03X63783Y492596I152J-130D01*
G01Y492332D01*
G03X63831Y492202I200J0D01*
G01X63832Y492201D01*
G02X64202Y491214I-1131J-987D01*
G02X61198I-1502J0D01*
G02X61568Y492201I1501J0D01*
G01Y492202D01*
X61569D01*
G03X61617Y492332I-152J130D01*
G01Y492596D01*
G03X61569Y492726I-200J0D01*
G01X61568Y492727D01*
G02X61198Y493714I1131J987D01*
G37*
G36*
G01X518284D02*
G02X521288I1502J0D01*
G02X520918Y492727I-1501J0D01*
G01Y492726D01*
X520917D01*
G03X520869Y492596I152J-130D01*
G01Y492332D01*
G03X520917Y492202I200J0D01*
G01X520918Y492201D01*
G02X521288Y491214I-1131J-987D01*
G02X518284I-1502J0D01*
G02X518654Y492201I1501J0D01*
G01Y492202D01*
X518655D01*
G03X518703Y492332I-152J130D01*
G01Y492596D01*
G03X518655Y492726I-200J0D01*
G01X518654Y492727D01*
G02X518284Y493714I1131J987D01*
G37*
G36*
G01X975371D02*
G02X978375I1502J0D01*
G02X978005Y492727I-1501J0D01*
G01Y492726D01*
X978004D01*
G03X977956Y492596I152J-130D01*
G01Y492332D01*
G03X978004Y492202I200J0D01*
G01X978005Y492201D01*
G02X978375Y491214I-1131J-987D01*
G02X975371I-1502J0D01*
G02X975741Y492201I1501J0D01*
G01Y492202D01*
X975742D01*
G03X975790Y492332I-152J130D01*
G01Y492596D01*
G03X975742Y492726I-200J0D01*
G01X975741Y492727D01*
G02X975371Y493714I1131J987D01*
G37*
G36*
G01X1432458D02*
G02X1435462I1502J0D01*
G02X1435092Y492727I-1501J0D01*
G01Y492726D01*
X1435091D01*
G03X1435043Y492596I152J-130D01*
G01Y492332D01*
G03X1435091Y492202I200J0D01*
G01X1435092Y492201D01*
G02X1435462Y491214I-1131J-987D01*
G02X1432458I-1502J0D01*
G02X1432828Y492201I1501J0D01*
G01Y492202D01*
X1432829D01*
G03X1432877Y492332I-152J130D01*
G01Y492596D01*
G03X1432829Y492726I-200J0D01*
G01X1432828Y492727D01*
G02X1432458Y493714I1131J987D01*
G37*
G36*
G01X64901Y495487D02*
G02X67905I1502J0D01*
G02X67535Y494500I-1501J0D01*
G01Y494499D01*
X67534D01*
G03X67486Y494369I152J-130D01*
G01Y494105D01*
G03X67534Y493975I200J0D01*
G01X67535Y493974D01*
G02X67905Y492987I-1131J-987D01*
G02X64901I-1502J0D01*
G02X65271Y493974I1501J0D01*
G01Y493975D01*
X65272D01*
G03X65320Y494105I-152J130D01*
G01Y494369D01*
G03X65272Y494499I-200J0D01*
G01X65271Y494500D01*
G02X64901Y495487I1131J987D01*
G37*
G36*
G01X521987D02*
G02X524991I1502J0D01*
G02X524621Y494500I-1501J0D01*
G01Y494499D01*
X524620D01*
G03X524572Y494369I152J-130D01*
G01Y494105D01*
G03X524620Y493975I200J0D01*
G01X524621Y493974D01*
G02X524991Y492987I-1131J-987D01*
G02X521987I-1502J0D01*
G02X522357Y493974I1501J0D01*
G01Y493975D01*
X522358D01*
G03X522406Y494105I-152J130D01*
G01Y494369D01*
G03X522358Y494499I-200J0D01*
G01X522357Y494500D01*
G02X521987Y495487I1131J987D01*
G37*
G36*
G01X979074D02*
G02X982078I1502J0D01*
G02X981708Y494500I-1501J0D01*
G01Y494499D01*
X981707D01*
G03X981659Y494369I152J-130D01*
G01Y494105D01*
G03X981707Y493975I200J0D01*
G01X981708Y493974D01*
G02X982078Y492987I-1131J-987D01*
G02X979074I-1502J0D01*
G02X979444Y493974I1501J0D01*
G01Y493975D01*
X979445D01*
G03X979493Y494105I-152J130D01*
G01Y494369D01*
G03X979445Y494499I-200J0D01*
G01X979444Y494500D01*
G02X979074Y495487I1131J987D01*
G37*
G36*
G01X1436161D02*
G02X1439165I1502J0D01*
G02X1438795Y494500I-1501J0D01*
G01Y494499D01*
X1438794D01*
G03X1438746Y494369I152J-130D01*
G01Y494105D01*
G03X1438794Y493975I200J0D01*
G01X1438795Y493974D01*
G02X1439165Y492987I-1131J-987D01*
G02X1436161I-1502J0D01*
G02X1436531Y493974I1501J0D01*
G01Y493975D01*
X1436532D01*
G03X1436580Y494105I-152J130D01*
G01Y494369D01*
G03X1436532Y494499I-200J0D01*
G01X1436531Y494500D01*
G02X1436161Y495487I1131J987D01*
G37*
G36*
G01X375255Y494089D02*
Y494383D01*
G03X375190Y494530I-200J-1D01*
G02X374705Y495636I1019J1106D01*
G02X377709I1502J0D01*
G02X377224Y494530I-1504J0D01*
G03X377159Y494383I135J-148D01*
G01Y494089D01*
G03X377224Y493942I200J1D01*
G02X377709Y492836I-1019J-1106D01*
G02X374705I-1502J0D01*
G02X375190Y493942I1504J0D01*
G03X375255Y494089I-135J148D01*
G37*
G36*
G01X1289428D02*
Y494383D01*
G03X1289363Y494530I-200J-1D01*
G02X1288878Y495636I1019J1106D01*
G02X1291882I1502J0D01*
G02X1291397Y494530I-1504J0D01*
G03X1291332Y494383I135J-148D01*
G01Y494089D01*
G03X1291397Y493942I200J1D01*
G02X1291882Y492836I-1019J-1106D01*
G02X1288878I-1502J0D01*
G02X1289363Y493942I1504J0D01*
G03X1289428Y494089I-135J148D01*
G37*
G36*
G01X1746515D02*
Y494383D01*
G03X1746450Y494530I-200J-1D01*
G02X1745965Y495636I1019J1106D01*
G02X1748969I1502J0D01*
G02X1748484Y494530I-1504J0D01*
G03X1748419Y494383I135J-148D01*
G01Y494089D01*
G03X1748484Y493942I200J1D01*
G02X1748969Y492836I-1019J-1106D01*
G02X1745965I-1502J0D01*
G02X1746450Y493942I1504J0D01*
G03X1746515Y494089I-135J148D01*
G37*
G36*
G01X70615Y496494D02*
Y496808D01*
G03X70538Y496966I-200J0D01*
G02X69959Y498151I923J1185D01*
G02X71461Y499653I1502J0D01*
G02X72448Y499283I0J-1501D01*
G01X72449D01*
Y499282D01*
G03X72579Y499234I130J152D01*
G01X72843D01*
G03X72973Y499282I0J200D01*
G01X72974Y499283D01*
G02X73961Y499653I987J-1131D01*
G02X75463Y498151I0J-1502D01*
G02X74884Y496966I-1502J0D01*
G03X74807Y496808I123J-158D01*
G01Y496494D01*
G03X74884Y496336I200J0D01*
G02X75463Y495151I-923J-1185D01*
G02X73961Y493649I-1502J0D01*
G02X72974Y494019I0J1501D01*
G01X72973D01*
Y494020D01*
G03X72843Y494068I-130J-152D01*
G01X72579D01*
G03X72449Y494020I0J-200D01*
G01X72448Y494019D01*
G02X71461Y493649I-987J1131D01*
G02X69959Y495151I0J1502D01*
G02X70538Y496336I1502J0D01*
G03X70615Y496494I-123J158D01*
G37*
G36*
G01X412773Y499969D02*
G02X415777I1502J0D01*
G02X415407Y498982I-1501J0D01*
G01Y498981D01*
X415406D01*
G03X415358Y498851I152J-130D01*
G01Y498587D01*
G03X415406Y498457I200J0D01*
G01X415407Y498456D01*
G02Y496482I-1131J-987D01*
G01Y496481D01*
X415406D01*
G03X415358Y496351I152J-130D01*
G01Y496087D01*
G03X415406Y495957I200J0D01*
G01X415407Y495956D01*
G02Y493982I-1131J-987D01*
G01Y493981D01*
X415406D01*
G03X415358Y493851I152J-130D01*
G01Y493587D01*
G03X415406Y493457I200J0D01*
G01X415407Y493456D01*
G02X415777Y492469I-1131J-987D01*
G02X412773I-1502J0D01*
G02X413143Y493456I1501J0D01*
G01Y493457D01*
X413144D01*
G03X413192Y493587I-152J130D01*
G01Y493851D01*
G03X413144Y493981I-200J0D01*
G01X413143Y493982D01*
G02Y495956I1131J987D01*
G01Y495957D01*
X413144D01*
G03X413192Y496087I-152J130D01*
G01Y496351D01*
G03X413144Y496481I-200J0D01*
G01X413143Y496482D01*
G02Y498456I1131J987D01*
G01Y498457D01*
X413144D01*
G03X413192Y498587I-152J130D01*
G01Y498851D01*
G03X413144Y498981I-200J0D01*
G01X413143Y498982D01*
G02X412773Y499969I1131J987D01*
G37*
G36*
G01X43288Y505957D02*
X43289Y505956D01*
G03X43419Y505908I130J152D01*
G01X43683D01*
G03X43813Y505956I0J200D01*
G01X43814Y505957D01*
G02X44801Y506327I987J-1131D01*
G02Y503323I0J-1502D01*
G02X43814Y503693I0J1501D01*
G01X43813D01*
Y503694D01*
G03X43683Y503742I-130J-152D01*
G01X43419D01*
G03X43289Y503694I0J-200D01*
G01X43288Y503693D01*
G02X41314I-987J1131D01*
G01X41313D01*
Y503694D01*
G03X41183Y503742I-130J-152D01*
G01X40919D01*
G03X40789Y503694I0J-200D01*
G01X40788Y503693D01*
G02X39801Y503323I-987J1131D01*
G02Y506327I0J1502D01*
G02X40788Y505957I0J-1501D01*
G01X40789D01*
Y505956D01*
G03X40919Y505908I130J152D01*
G01X41183D01*
G03X41313Y505956I0J200D01*
G01X41314Y505957D01*
G02X43288I987J-1131D01*
G37*
G36*
G01X500374D02*
X500375Y505956D01*
G03X500505Y505908I130J152D01*
G01X500769D01*
G03X500899Y505956I0J200D01*
G01X500900Y505957D01*
G02X501887Y506327I987J-1131D01*
G02Y503323I0J-1502D01*
G02X500900Y503693I0J1501D01*
G01X500899D01*
Y503694D01*
G03X500769Y503742I-130J-152D01*
G01X500505D01*
G03X500375Y503694I0J-200D01*
G01X500374Y503693D01*
G02X498400I-987J1131D01*
G01X498399D01*
Y503694D01*
G03X498269Y503742I-130J-152D01*
G01X498005D01*
G03X497875Y503694I0J-200D01*
G01X497874Y503693D01*
G02X496887Y503323I-987J1131D01*
G02Y506327I0J1502D01*
G02X497874Y505957I0J-1501D01*
G01X497875D01*
Y505956D01*
G03X498005Y505908I130J152D01*
G01X498269D01*
G03X498399Y505956I0J200D01*
G01X498400Y505957D01*
G02X500374I987J-1131D01*
G37*
G36*
G01X957461D02*
X957462Y505956D01*
G03X957592Y505908I130J152D01*
G01X957856D01*
G03X957986Y505956I0J200D01*
G01X957987Y505957D01*
G02X958974Y506327I987J-1131D01*
G02Y503323I0J-1502D01*
G02X957987Y503693I0J1501D01*
G01X957986D01*
Y503694D01*
G03X957856Y503742I-130J-152D01*
G01X957592D01*
G03X957462Y503694I0J-200D01*
G01X957461Y503693D01*
G02X955487I-987J1131D01*
G01X955486D01*
Y503694D01*
G03X955356Y503742I-130J-152D01*
G01X955092D01*
G03X954962Y503694I0J-200D01*
G01X954961Y503693D01*
G02X953974Y503323I-987J1131D01*
G02Y506327I0J1502D01*
G02X954961Y505957I0J-1501D01*
G01X954962D01*
Y505956D01*
G03X955092Y505908I130J152D01*
G01X955356D01*
G03X955486Y505956I0J200D01*
G01X955487Y505957D01*
G02X957461I987J-1131D01*
G37*
G36*
G01X449429Y507581D02*
X449430Y507580D01*
G03X449560Y507532I130J152D01*
G01X449824D01*
G03X449954Y507580I0J200D01*
G01X449955Y507581D01*
G02X450942Y507951I987J-1131D01*
G02Y504947I0J-1502D01*
G02X449955Y505317I0J1501D01*
G01X449954D01*
Y505318D01*
G03X449824Y505366I-130J-152D01*
G01X449560D01*
G03X449430Y505318I0J-200D01*
G01X449429Y505317D01*
G02X447455I-987J1131D01*
G01X447454D01*
Y505318D01*
G03X447324Y505366I-130J-152D01*
G01X447060D01*
G03X446930Y505318I0J-200D01*
G01X446929Y505317D01*
G02X445942Y504947I-987J1131D01*
G02Y507951I0J1502D01*
G02X446929Y507581I0J-1501D01*
G01X446930D01*
Y507580D01*
G03X447060Y507532I130J152D01*
G01X447324D01*
G03X447454Y507580I0J200D01*
G01X447455Y507581D01*
G02X449429I987J-1131D01*
G37*
G36*
G01X446025Y510010D02*
G02Y513014I0J1502D01*
G02X447012Y512644I0J-1501D01*
G01X447013D01*
Y512643D01*
G03X447143Y512595I130J152D01*
G01X447407D01*
G03X447537Y512643I0J200D01*
G01X447538Y512644D01*
G02X448525Y513014I987J-1131D01*
G02Y510010I0J-1502D01*
G02X447538Y510380I0J1501D01*
G01X447537D01*
Y510381D01*
G03X447407Y510429I-130J-152D01*
G01X447143D01*
G03X447013Y510381I0J-200D01*
G01X447012Y510380D01*
G02X446025Y510010I-987J1131D01*
G37*
G36*
G01X43229Y518533D02*
X43230Y518532D01*
G03X43360Y518484I130J152D01*
G01X43624D01*
G03X43754Y518532I0J200D01*
G01X43755Y518533D01*
G02X44742Y518903I987J-1131D01*
G02Y515899I0J-1502D01*
G02X43755Y516269I0J1501D01*
G01X43754D01*
Y516270D01*
G03X43624Y516318I-130J-152D01*
G01X43360D01*
G03X43230Y516270I0J-200D01*
G01X43229Y516269D01*
G02X41255I-987J1131D01*
G01X41254D01*
Y516270D01*
G03X41124Y516318I-130J-152D01*
G01X40860D01*
G03X40730Y516270I0J-200D01*
G01X40729Y516269D01*
G02X39742Y515899I-987J1131D01*
G02Y518903I0J1502D01*
G02X40729Y518533I0J-1501D01*
G01X40730D01*
Y518532D01*
G03X40860Y518484I130J152D01*
G01X41124D01*
G03X41254Y518532I0J200D01*
G01X41255Y518533D01*
G02X43229I987J-1131D01*
G37*
G36*
G01X500315D02*
X500316Y518532D01*
G03X500446Y518484I130J152D01*
G01X500710D01*
G03X500840Y518532I0J200D01*
G01X500841Y518533D01*
G02X501828Y518903I987J-1131D01*
G02Y515899I0J-1502D01*
G02X500841Y516269I0J1501D01*
G01X500840D01*
Y516270D01*
G03X500710Y516318I-130J-152D01*
G01X500446D01*
G03X500316Y516270I0J-200D01*
G01X500315Y516269D01*
G02X498341I-987J1131D01*
G01X498340D01*
Y516270D01*
G03X498210Y516318I-130J-152D01*
G01X497946D01*
G03X497816Y516270I0J-200D01*
G01X497815Y516269D01*
G02X496828Y515899I-987J1131D01*
G02Y518903I0J1502D01*
G02X497815Y518533I0J-1501D01*
G01X497816D01*
Y518532D01*
G03X497946Y518484I130J152D01*
G01X498210D01*
G03X498340Y518532I0J200D01*
G01X498341Y518533D01*
G02X500315I987J-1131D01*
G37*
G36*
G01X957402D02*
X957403Y518532D01*
G03X957533Y518484I130J152D01*
G01X957797D01*
G03X957927Y518532I0J200D01*
G01X957928Y518533D01*
G02X958915Y518903I987J-1131D01*
G02Y515899I0J-1502D01*
G02X957928Y516269I0J1501D01*
G01X957927D01*
Y516270D01*
G03X957797Y516318I-130J-152D01*
G01X957533D01*
G03X957403Y516270I0J-200D01*
G01X957402Y516269D01*
G02X955428I-987J1131D01*
G01X955427D01*
Y516270D01*
G03X955297Y516318I-130J-152D01*
G01X955033D01*
G03X954903Y516270I0J-200D01*
G01X954902Y516269D01*
G02X953915Y515899I-987J1131D01*
G02Y518903I0J1502D01*
G02X954902Y518533I0J-1501D01*
G01X954903D01*
Y518532D01*
G03X955033Y518484I130J152D01*
G01X955297D01*
G03X955427Y518532I0J200D01*
G01X955428Y518533D01*
G02X957402I987J-1131D01*
G37*
G36*
G01X1414489D02*
X1414490Y518532D01*
G03X1414620Y518484I130J152D01*
G01X1414884D01*
G03X1415014Y518532I0J200D01*
G01X1415015Y518533D01*
G02X1416002Y518903I987J-1131D01*
G02Y515899I0J-1502D01*
G02X1415015Y516269I0J1501D01*
G01X1415014D01*
Y516270D01*
G03X1414884Y516318I-130J-152D01*
G01X1414620D01*
G03X1414490Y516270I0J-200D01*
G01X1414489Y516269D01*
G02X1412515I-987J1131D01*
G01X1412514D01*
Y516270D01*
G03X1412384Y516318I-130J-152D01*
G01X1412120D01*
G03X1411990Y516270I0J-200D01*
G01X1411989Y516269D01*
G02X1411002Y515899I-987J1131D01*
G02Y518903I0J1502D01*
G02X1411989Y518533I0J-1501D01*
G01X1411990D01*
Y518532D01*
G03X1412120Y518484I130J152D01*
G01X1412384D01*
G03X1412514Y518532I0J200D01*
G01X1412515Y518533D01*
G02X1414489I987J-1131D01*
G37*
G36*
G01X446025Y518197D02*
G02Y521201I0J1502D01*
G02X447012Y520831I0J-1501D01*
G01X447013D01*
Y520830D01*
G03X447143Y520782I130J152D01*
G01X447407D01*
G03X447537Y520830I0J200D01*
G01X447538Y520831D01*
G02X448525Y521201I987J-1131D01*
G02Y518197I0J-1502D01*
G02X447538Y518567I0J1501D01*
G01X447537D01*
Y518568D01*
G03X447407Y518616I-130J-152D01*
G01X447143D01*
G03X447013Y518568I0J-200D01*
G01X447012Y518567D01*
G02X446025Y518197I-987J1131D01*
G37*
G36*
G01X44341Y523822D02*
Y524116D01*
G03X44276Y524263I-200J-1D01*
G02X43791Y525369I1019J1106D01*
G02X46795I1502J0D01*
G02X46310Y524263I-1504J0D01*
G03X46245Y524116I135J-148D01*
G01Y523822D01*
G03X46310Y523675I200J1D01*
G02X46795Y522569I-1019J-1106D01*
G02X43791I-1502J0D01*
G02X44276Y523675I1504J0D01*
G03X44341Y523822I-135J148D01*
G37*
G36*
G01X501427D02*
Y524116D01*
G03X501362Y524263I-200J-1D01*
G02X500877Y525369I1019J1106D01*
G02X503881I1502J0D01*
G02X503396Y524263I-1504J0D01*
G03X503331Y524116I135J-148D01*
G01Y523822D01*
G03X503396Y523675I200J1D01*
G02X503881Y522569I-1019J-1106D01*
G02X500877I-1502J0D01*
G02X501362Y523675I1504J0D01*
G03X501427Y523822I-135J148D01*
G37*
G36*
G01X958514D02*
Y524116D01*
G03X958449Y524263I-200J-1D01*
G02X957964Y525369I1019J1106D01*
G02X960968I1502J0D01*
G02X960483Y524263I-1504J0D01*
G03X960418Y524116I135J-148D01*
G01Y523822D01*
G03X960483Y523675I200J1D01*
G02X960968Y522569I-1019J-1106D01*
G02X957964I-1502J0D01*
G02X958449Y523675I1504J0D01*
G03X958514Y523822I-135J148D01*
G37*
G36*
G01X1415601D02*
Y524116D01*
G03X1415536Y524263I-200J-1D01*
G02X1415051Y525369I1019J1106D01*
G02X1418055I1502J0D01*
G02X1417570Y524263I-1504J0D01*
G03X1417505Y524116I135J-148D01*
G01Y523822D01*
G03X1417570Y523675I200J1D01*
G02X1418055Y522569I-1019J-1106D01*
G02X1415051I-1502J0D01*
G02X1415536Y523675I1504J0D01*
G03X1415601Y523822I-135J148D01*
G37*
G36*
G01X51367Y540458D02*
G02X54371I1502J0D01*
G02X54001Y539471I-1501J0D01*
G01Y539470D01*
X54000D01*
G03X53952Y539340I152J-130D01*
G01Y539076D01*
G03X54000Y538946I200J0D01*
G01X54001Y538945D01*
G02X54371Y537958I-1131J-987D01*
G02X51367I-1502J0D01*
G02X51737Y538945I1501J0D01*
G01Y538946D01*
X51738D01*
G03X51786Y539076I-152J130D01*
G01Y539340D01*
G03X51738Y539470I-200J0D01*
G01X51737Y539471D01*
G02X51367Y540458I1131J987D01*
G37*
G36*
G01X508453D02*
G02X511457I1502J0D01*
G02X511087Y539471I-1501J0D01*
G01Y539470D01*
X511086D01*
G03X511038Y539340I152J-130D01*
G01Y539076D01*
G03X511086Y538946I200J0D01*
G01X511087Y538945D01*
G02X511457Y537958I-1131J-987D01*
G02X508453I-1502J0D01*
G02X508823Y538945I1501J0D01*
G01Y538946D01*
X508824D01*
G03X508872Y539076I-152J130D01*
G01Y539340D01*
G03X508824Y539470I-200J0D01*
G01X508823Y539471D01*
G02X508453Y540458I1131J987D01*
G37*
G36*
G01X966090Y538911D02*
Y539205D01*
G03X966025Y539352I-200J-1D01*
G02X965540Y540458I1019J1106D01*
G02X968544I1502J0D01*
G02X968059Y539352I-1504J0D01*
G03X967994Y539205I135J-148D01*
G01Y538911D01*
G03X968059Y538764I200J1D01*
G02X968544Y537658I-1019J-1106D01*
G02X965540I-1502J0D01*
G02X966025Y538764I1504J0D01*
G03X966090Y538911I-135J148D01*
G37*
G36*
G01X1423177D02*
Y539205D01*
G03X1423112Y539352I-200J-1D01*
G02X1422627Y540458I1019J1106D01*
G02X1425631I1502J0D01*
G02X1425146Y539352I-1504J0D01*
G03X1425081Y539205I135J-148D01*
G01Y538911D01*
G03X1425146Y538764I200J1D01*
G02X1425631Y537658I-1019J-1106D01*
G02X1422627I-1502J0D01*
G02X1423112Y538764I1504J0D01*
G03X1423177Y538911I-135J148D01*
G37*
G36*
G01X55070Y542231D02*
G02X58074I1502J0D01*
G02X57704Y541244I-1501J0D01*
G01Y541243D01*
X57703D01*
G03X57655Y541113I152J-130D01*
G01Y540849D01*
G03X57703Y540719I200J0D01*
G01X57704Y540718D01*
G02X58074Y539731I-1131J-987D01*
G02X55070I-1502J0D01*
G02X55440Y540718I1501J0D01*
G01Y540719D01*
X55441D01*
G03X55489Y540849I-152J130D01*
G01Y541113D01*
G03X55441Y541243I-200J0D01*
G01X55440Y541244D01*
G02X55070Y542231I1131J987D01*
G37*
G36*
G01X512156D02*
G02X515160I1502J0D01*
G02X514790Y541244I-1501J0D01*
G01Y541243D01*
X514789D01*
G03X514741Y541113I152J-130D01*
G01Y540849D01*
G03X514789Y540719I200J0D01*
G01X514790Y540718D01*
G02X515160Y539731I-1131J-987D01*
G02X512156I-1502J0D01*
G02X512526Y540718I1501J0D01*
G01Y540719D01*
X512527D01*
G03X512575Y540849I-152J130D01*
G01Y541113D01*
G03X512527Y541243I-200J0D01*
G01X512526Y541244D01*
G02X512156Y542231I1131J987D01*
G37*
G36*
G01X969243D02*
G02X972247I1502J0D01*
G02X971877Y541244I-1501J0D01*
G01Y541243D01*
X971876D01*
G03X971828Y541113I152J-130D01*
G01Y540849D01*
G03X971876Y540719I200J0D01*
G01X971877Y540718D01*
G02X972247Y539731I-1131J-987D01*
G02X969243I-1502J0D01*
G02X969613Y540718I1501J0D01*
G01Y540719D01*
X969614D01*
G03X969662Y540849I-152J130D01*
G01Y541113D01*
G03X969614Y541243I-200J0D01*
G01X969613Y541244D01*
G02X969243Y542231I1131J987D01*
G37*
G36*
G01X1426330D02*
G02X1429334I1502J0D01*
G02X1428964Y541244I-1501J0D01*
G01Y541243D01*
X1428963D01*
G03X1428915Y541113I152J-130D01*
G01Y540849D01*
G03X1428963Y540719I200J0D01*
G01X1428964Y540718D01*
G02X1429334Y539731I-1131J-987D01*
G02X1426330I-1502J0D01*
G02X1426700Y540718I1501J0D01*
G01Y540719D01*
X1426701D01*
G03X1426749Y540849I-152J130D01*
G01Y541113D01*
G03X1426701Y541243I-200J0D01*
G01X1426700Y541244D01*
G02X1426330Y542231I1131J987D01*
G37*
G36*
G01X1756089Y541450D02*
G02Y544454I0J1502D01*
G02X1757193Y543971I0J-1503D01*
G01X1757222Y543939D01*
X1757302Y543905D01*
X1757647Y543915D01*
G03X1757796Y543989I-6J200D01*
G02X1758957Y544538I1161J-953D01*
G02Y541534I0J-1502D01*
G02X1757853Y542017I0J1503D01*
G01X1757824Y542049D01*
X1757744Y542083D01*
X1757399Y542073D01*
G03X1757250Y541999I6J-200D01*
G02X1756089Y541450I-1161J953D01*
G37*
G36*
G01X74175Y549490D02*
X74176Y549489D01*
G03X74306Y549441I130J152D01*
G01X74570D01*
G03X74700Y549489I0J200D01*
G01X74701Y549490D01*
G02X75688Y549860I987J-1131D01*
G02Y546856I0J-1502D01*
G02X74701Y547226I0J1501D01*
G01X74700D01*
Y547227D01*
G03X74570Y547275I-130J-152D01*
G01X74306D01*
G03X74176Y547227I0J-200D01*
G01X74175Y547226D01*
G02X72201I-987J1131D01*
G01X72200D01*
Y547227D01*
G03X72070Y547275I-130J-152D01*
G01X71806D01*
G03X71676Y547227I0J-200D01*
G01X71675Y547226D01*
G02X69701I-987J1131D01*
G01X69700D01*
Y547227D01*
G03X69570Y547275I-130J-152D01*
G01X69306D01*
G03X69176Y547227I0J-200D01*
G01X69175Y547226D01*
G02X69127Y547185I-999J1121D01*
G01X69091Y547157D01*
X69051Y547074D01*
X69053Y546714D01*
G03X69129Y546558I200J1D01*
G02X69704Y545377I-927J-1182D01*
G02X69334Y544390I-1501J0D01*
G01Y544389D01*
X69333D01*
G03X69285Y544259I152J-130D01*
G01Y543995D01*
G03X69333Y543865I200J0D01*
G01X69334Y543864D01*
G02Y541890I-1131J-987D01*
G01Y541889D01*
X69333D01*
G03X69285Y541759I152J-130D01*
G01Y541495D01*
G03X69333Y541365I200J0D01*
G01X69334Y541364D01*
G02Y539390I-1131J-987D01*
G01Y539389D01*
X69333D01*
G03X69285Y539259I152J-130D01*
G01Y538995D01*
G03X69333Y538865I200J0D01*
G01X69334Y538864D01*
G02X69704Y537877I-1131J-987D01*
G02X66700I-1502J0D01*
G02X67070Y538864I1501J0D01*
G01Y538865D01*
X67071D01*
G03X67119Y538995I-152J130D01*
G01Y539259D01*
G03X67071Y539389I-200J0D01*
G01X67070Y539390D01*
G02Y541364I1131J987D01*
G01Y541365D01*
X67071D01*
G03X67119Y541495I-152J130D01*
G01Y541759D01*
G03X67071Y541889I-200J0D01*
G01X67070Y541890D01*
G02Y543864I1131J987D01*
G01Y543865D01*
X67071D01*
G03X67119Y543995I-152J130D01*
G01Y544259D01*
G03X67071Y544389I-200J0D01*
G01X67070Y544390D01*
G02X66700Y545377I1131J987D01*
G01Y545378D01*
G02X67263Y546550I1502J0D01*
G01X67299Y546578D01*
X67339Y546661D01*
X67337Y547021D01*
G03X67261Y547177I-200J-1D01*
G02X66686Y548358I927J1182D01*
G02X68188Y549860I1502J0D01*
G02X69175Y549490I0J-1501D01*
G01X69176D01*
Y549489D01*
G03X69306Y549441I130J152D01*
G01X69570D01*
G03X69700Y549489I0J200D01*
G01X69701Y549490D01*
G02X71675I987J-1131D01*
G01X71676D01*
Y549489D01*
G03X71806Y549441I130J152D01*
G01X72070D01*
G03X72200Y549489I0J200D01*
G01X72201Y549490D01*
G02X74175I987J-1131D01*
G37*
G36*
G01X988375Y549498D02*
X988376Y549497D01*
G03X988506Y549449I130J152D01*
G01X988770D01*
G03X988900Y549497I0J200D01*
G01X988901Y549498D01*
G02X989888Y549868I987J-1131D01*
G02Y546864I0J-1502D01*
G02X988901Y547234I0J1501D01*
G01X988900D01*
Y547235D01*
G03X988770Y547283I-130J-152D01*
G01X988506D01*
G03X988376Y547235I0J-200D01*
G01X988375Y547234D01*
G02X986401I-987J1131D01*
G01X986400D01*
Y547235D01*
G03X986270Y547283I-130J-152D01*
G01X986006D01*
G03X985876Y547235I0J-200D01*
G01X985875Y547234D01*
G02X983901I-987J1131D01*
G01X983900D01*
Y547235D01*
G03X983770Y547283I-130J-152D01*
G01X983506D01*
G03X983376Y547235I0J-200D01*
G01X983375Y547234D01*
G02X983312Y547182I-987J1132D01*
G03X983235Y547025I123J-158D01*
G01X983233Y546710D01*
G03X983308Y546554I200J0D01*
G01X983309Y546553D01*
G02X983877Y545377I-933J-1176D01*
G02X983507Y544390I-1501J0D01*
G01Y544389D01*
X983506D01*
G03X983458Y544259I152J-130D01*
G01Y543995D01*
G03X983506Y543865I200J0D01*
G01X983507Y543864D01*
G02Y541890I-1131J-987D01*
G01Y541889D01*
X983506D01*
G03X983458Y541759I152J-130D01*
G01Y541495D01*
G03X983506Y541365I200J0D01*
G01X983507Y541364D01*
G02Y539390I-1131J-987D01*
G01Y539389D01*
X983506D01*
G03X983458Y539259I152J-130D01*
G01Y538995D01*
G03X983506Y538865I200J0D01*
G01X983507Y538864D01*
G02X983877Y537877I-1131J-987D01*
G02X980873I-1502J0D01*
G02X981243Y538864I1501J0D01*
G01Y538865D01*
X981244D01*
G03X981292Y538995I-152J130D01*
G01Y539259D01*
G03X981244Y539389I-200J0D01*
G01X981243Y539390D01*
G02Y541364I1131J987D01*
G01Y541365D01*
X981244D01*
G03X981292Y541495I-152J130D01*
G01Y541759D01*
G03X981244Y541889I-200J0D01*
G01X981243Y541890D01*
G02Y543864I1131J987D01*
G01Y543865D01*
X981244D01*
G03X981292Y543995I-152J130D01*
G01Y544259D01*
G03X981244Y544389I-200J0D01*
G01X981243Y544390D01*
G02X980873Y545377I1131J987D01*
G02X981451Y546561I1502J0D01*
G03X981528Y546718I-123J158D01*
G01X981530Y547033D01*
G03X981455Y547189I-200J0D01*
G01X981454Y547190D01*
G02X980886Y548366I933J1176D01*
G02X982388Y549868I1502J0D01*
G02X983375Y549498I0J-1501D01*
G01X983376D01*
Y549497D01*
G03X983506Y549449I130J152D01*
G01X983770D01*
G03X983900Y549497I0J200D01*
G01X983901Y549498D01*
G02X985875I987J-1131D01*
G01X985876D01*
Y549497D01*
G03X986006Y549449I130J152D01*
G01X986270D01*
G03X986400Y549497I0J200D01*
G01X986401Y549498D01*
G02X988375I987J-1131D01*
G37*
G36*
G01X343912Y533486D02*
X363267D01*
G02X364189Y533104I-1J-1306D01*
G01X377246Y520047D01*
G03X377326Y519998I142J141D01*
G01X377327D01*
G02X378383Y518564I-446J-1434D01*
G02X376881Y517062I-1502J0D01*
G02X375447Y518117I0J1502D01*
G01Y518119D01*
G03X375398Y518199I-190J-62D01*
G01X362783Y530815D01*
G03X362641Y530874I-142J-141D01*
G01X343286D01*
G02X342364Y531256I1J1306D01*
G01X328829Y544791D01*
G02X328446Y545715I923J924D01*
G01Y547144D01*
G03X328387Y547286I-200J0D01*
G01X327091Y548582D01*
G03X327011Y548631I-142J-141D01*
G01X327010D01*
G02X325954Y550065I446J1434D01*
G02X327456Y551567I1502J0D01*
G02X328890Y550512I0J-1502D01*
G01Y550510D01*
G03X328939Y550430I190J62D01*
G01X330677Y548692D01*
G02X331060Y547768I-923J-924D01*
G01Y546339D01*
G03X331119Y546197I200J0D01*
G01X343770Y533545D01*
G03X343912Y533486I142J141D01*
G37*
G36*
G01X1165400Y551798D02*
G02Y554802I0J1502D01*
G02X1166387Y554432I0J-1501D01*
G01X1166388D01*
Y554431D01*
G03X1166518Y554383I130J152D01*
G01X1166782D01*
G03X1166912Y554431I0J200D01*
G01X1166913Y554432D01*
G02X1167900Y554802I987J-1131D01*
G02Y551798I0J-1502D01*
G02X1166913Y552168I0J1501D01*
G01X1166912D01*
Y552169D01*
G03X1166782Y552217I-130J-152D01*
G01X1166518D01*
G03X1166388Y552169I0J-200D01*
G01X1166387Y552168D01*
G02X1165400Y551798I-987J1131D01*
G37*
G36*
G01X450902Y554990D02*
G02X452404Y556492I1502J0D01*
G02X453465Y556053I0J-1502D01*
G01X453492Y556026D01*
X453562Y555996D01*
X453914Y555985D01*
X453984Y556010D01*
X454013Y556036D01*
G02X455009Y556414I996J-1123D01*
G02X456511Y554912I0J-1502D01*
G02X456105Y553885I-1502J0D01*
G01X456079Y553858D01*
X456051Y553787D01*
Y553437D01*
X456079Y553366D01*
X456105Y553339D01*
G02Y551285I-1096J-1027D01*
G01X456079Y551258D01*
X456051Y551187D01*
Y550837D01*
X456079Y550766D01*
X456105Y550739D01*
G02X456511Y549712I-1096J-1027D01*
G02X456026Y548606I-1504J0D01*
G03X455961Y548459I135J-148D01*
G01Y548165D01*
G03X456026Y548018I200J1D01*
G02X456511Y546912I-1019J-1106D01*
G02X456105Y545885I-1502J0D01*
G01X456079Y545858D01*
X456051Y545787D01*
Y545437D01*
X456079Y545366D01*
X456105Y545339D01*
G02X456511Y544312I-1096J-1027D01*
G02X455009Y542810I-1502J0D01*
G02X453948Y543249I0J1502D01*
G01X453921Y543276D01*
X453851Y543306D01*
X453499Y543317D01*
X453429Y543292D01*
X453400Y543266D01*
G02X452404Y542888I-996J1123D01*
G02X450902Y544390I0J1502D01*
G02X451308Y545417I1502J0D01*
G01X451334Y545444D01*
X451362Y545515D01*
Y545865D01*
X451334Y545936D01*
X451308Y545963D01*
G02X450902Y546990I1096J1027D01*
G02X451387Y548096I1504J0D01*
G03X451452Y548243I-135J148D01*
G01Y548537D01*
G03X451387Y548684I-200J-1D01*
G02X450902Y549790I1019J1106D01*
G02X451308Y550817I1502J0D01*
G01X451334Y550844D01*
X451362Y550915D01*
Y551265D01*
X451334Y551336D01*
X451308Y551363D01*
G02Y553417I1096J1027D01*
G01X451334Y553444D01*
X451362Y553515D01*
Y553865D01*
X451334Y553936D01*
X451308Y553963D01*
G02X450902Y554990I1096J1027D01*
G37*
G36*
G01X441502Y555090D02*
G02X444506I1502J0D01*
G02X444100Y554063I-1502J0D01*
G01X444074Y554036D01*
X444046Y553965D01*
Y553615D01*
X444074Y553544D01*
X444100Y553517D01*
G02Y551463I-1096J-1027D01*
G01X444074Y551436D01*
X444046Y551365D01*
Y551015D01*
X444074Y550944D01*
X444100Y550917D01*
G02X444506Y549890I-1096J-1027D01*
G02X443892Y548678I-1503J0D01*
G03X443811Y548530I118J-161D01*
G01X443789Y548225D01*
G03X443849Y548068I200J-14D01*
G02X444306Y546990I-1045J-1079D01*
G02X443900Y545963I-1502J0D01*
G01X443874Y545936D01*
X443846Y545865D01*
Y545515D01*
X443874Y545444D01*
X443900Y545417D01*
G02X444306Y544390I-1096J-1027D01*
G02X441302I-1502J0D01*
G02X441708Y545417I1502J0D01*
G01X441734Y545444D01*
X441762Y545515D01*
Y545865D01*
X441734Y545936D01*
X441708Y545963D01*
G02X441302Y546990I1096J1027D01*
G02X441916Y548202I1503J0D01*
G03X441997Y548350I-118J161D01*
G01X442019Y548655D01*
G03X441959Y548812I-200J14D01*
G02X441502Y549890I1045J1079D01*
G02X441908Y550917I1502J0D01*
G01X441934Y550944D01*
X441962Y551015D01*
Y551365D01*
X441934Y551436D01*
X441908Y551463D01*
G02Y553517I1096J1027D01*
G01X441934Y553544D01*
X441962Y553615D01*
Y553965D01*
X441934Y554036D01*
X441908Y554063D01*
G02X441502Y555090I1096J1027D01*
G37*
G36*
G01X417838Y555190D02*
G02X420842I1502J0D01*
G02X420436Y554163I-1502J0D01*
G01X420410Y554136D01*
X420382Y554065D01*
Y553715D01*
X420410Y553644D01*
X420436Y553617D01*
G02Y551563I-1096J-1027D01*
G01X420410Y551536D01*
X420382Y551465D01*
Y551115D01*
X420410Y551044D01*
X420436Y551017D01*
G02X420842Y549990I-1096J-1027D01*
G02X420352Y548881I-1502J1D01*
G03X420350Y548879I140J-142D01*
G03X420287Y548748I136J-146D01*
G01X420265Y548474D01*
G03X420309Y548333I200J-15D01*
G02X420642Y547390I-1169J-943D01*
G02X420236Y546363I-1502J0D01*
G01X420210Y546336D01*
X420182Y546265D01*
Y545915D01*
X420210Y545844D01*
X420236Y545817D01*
G02X420642Y544790I-1096J-1027D01*
G02X417638I-1502J0D01*
G02X418044Y545817I1502J0D01*
G01X418070Y545844D01*
X418098Y545915D01*
Y546265D01*
X418070Y546336D01*
X418044Y546363D01*
G02X417638Y547390I1096J1027D01*
G02X418128Y548499I1502J-1D01*
G03X418130Y548501I-140J142D01*
G03X418193Y548632I-136J146D01*
G01X418215Y548906D01*
G03X418171Y549047I-200J15D01*
G02X417838Y549990I1169J943D01*
G02X418244Y551017I1502J0D01*
G01X418270Y551044D01*
X418298Y551115D01*
Y551465D01*
X418270Y551536D01*
X418244Y551563D01*
G02Y553617I1096J1027D01*
G01X418270Y553644D01*
X418298Y553715D01*
Y554065D01*
X418270Y554136D01*
X418244Y554163D01*
G02X417838Y555190I1096J1027D01*
G37*
G36*
G01X427238D02*
G02X428740Y556692I1502J0D01*
G02X429784Y556270I0J-1502D01*
G01X429813Y556242D01*
X429883Y556214D01*
X430241D01*
X430311Y556242D01*
X430340Y556270D01*
G02X431384Y556692I1044J-1080D01*
G02X432886Y555190I0J-1502D01*
G02X432480Y554163I-1502J0D01*
G01X432454Y554136D01*
X432426Y554065D01*
Y553715D01*
X432454Y553644D01*
X432480Y553617D01*
G02Y551563I-1096J-1027D01*
G01X432454Y551536D01*
X432426Y551465D01*
Y551115D01*
X432454Y551044D01*
X432480Y551017D01*
G02X432886Y549990I-1096J-1027D01*
G02X432307Y548805I-1502J0D01*
G03X432230Y548647I123J-158D01*
G01Y548333D01*
G03X432307Y548175I200J0D01*
G02X432886Y546990I-923J-1185D01*
G02X432480Y545963I-1502J0D01*
G01X432454Y545936D01*
X432426Y545865D01*
Y545515D01*
X432454Y545444D01*
X432480Y545417D01*
G02X432886Y544390I-1096J-1027D01*
G02X431384Y542888I-1502J0D01*
G02X430340Y543310I0J1502D01*
G01X430311Y543338D01*
X430241Y543366D01*
X429883D01*
X429813Y543338D01*
X429784Y543310D01*
G02X428740Y542888I-1044J1080D01*
G02X427238Y544390I0J1502D01*
G02X427644Y545417I1502J0D01*
G01X427670Y545444D01*
X427698Y545515D01*
Y545865D01*
X427670Y545936D01*
X427644Y545963D01*
G02X427238Y546990I1096J1027D01*
G02X427817Y548175I1502J0D01*
G03X427894Y548333I-123J158D01*
G01Y548647D01*
G03X427817Y548805I-200J0D01*
G02X427238Y549990I923J1185D01*
G02X427644Y551017I1502J0D01*
G01X427670Y551044D01*
X427698Y551115D01*
Y551465D01*
X427670Y551536D01*
X427644Y551563D01*
G02Y553617I1096J1027D01*
G01X427670Y553644D01*
X427698Y553715D01*
Y554065D01*
X427670Y554136D01*
X427644Y554163D01*
G02X427238Y555190I1096J1027D01*
G37*
G36*
G01X45390Y554242D02*
X45096D01*
G03X44949Y554177I1J-200D01*
G02X43843Y553692I-1106J1019D01*
G02Y556696I0J1502D01*
G02X44949Y556211I0J-1504D01*
G03X45096Y556146I148J135D01*
G01X45390D01*
G03X45537Y556211I-1J200D01*
G02X46643Y556696I1106J-1019D01*
G02Y553692I0J-1502D01*
G02X45537Y554177I0J1504D01*
G03X45390Y554242I-148J-135D01*
G37*
G36*
G01X502476D02*
X502182D01*
G03X502035Y554177I1J-200D01*
G02X500929Y553692I-1106J1019D01*
G02Y556696I0J1502D01*
G02X502035Y556211I0J-1504D01*
G03X502182Y556146I148J135D01*
G01X502476D01*
G03X502623Y556211I-1J200D01*
G02X503729Y556696I1106J-1019D01*
G02Y553692I0J-1502D01*
G02X502623Y554177I0J1504D01*
G03X502476Y554242I-148J-135D01*
G37*
G36*
G01X959563D02*
X959269D01*
G03X959122Y554177I1J-200D01*
G02X958016Y553692I-1106J1019D01*
G02Y556696I0J1502D01*
G02X959122Y556211I0J-1504D01*
G03X959269Y556146I148J135D01*
G01X959563D01*
G03X959710Y556211I-1J200D01*
G02X960816Y556696I1106J-1019D01*
G02Y553692I0J-1502D01*
G02X959710Y554177I0J1504D01*
G03X959563Y554242I-148J-135D01*
G37*
G36*
G01X1416650D02*
X1416356D01*
G03X1416209Y554177I1J-200D01*
G02X1415103Y553692I-1106J1019D01*
G02Y556696I0J1502D01*
G02X1416209Y556211I0J-1504D01*
G03X1416356Y556146I148J135D01*
G01X1416650D01*
G03X1416797Y556211I-1J200D01*
G02X1417903Y556696I1106J-1019D01*
G02Y553692I0J-1502D01*
G02X1416797Y554177I0J1504D01*
G03X1416650Y554242I-148J-135D01*
G37*
G36*
G01X203172Y561420D02*
G02X206176I1502J0D01*
G02X205806Y560433I-1501J0D01*
G03X205804Y560431I140J-142D01*
G03X205756Y560301I152J-130D01*
G01Y560036D01*
G03X205804Y559906I200J0D01*
G01X205805Y559905D01*
G02X206176Y558917I-1130J-988D01*
G02X203172I-1502J0D01*
G02X203542Y559904I1501J0D01*
G03X203544Y559906I-140J142D01*
G03X203592Y560036I-152J130D01*
G01Y560301D01*
G03X203544Y560431I-200J0D01*
G01X203543Y560432D01*
G02X203172Y561420I1130J988D01*
G37*
G36*
G01X660258D02*
G02X663262I1502J0D01*
G02X662892Y560433I-1501J0D01*
G03X662890Y560431I140J-142D01*
G03X662842Y560301I152J-130D01*
G01Y560036D01*
G03X662890Y559906I200J0D01*
G01X662891Y559905D01*
G02X663262Y558917I-1130J-988D01*
G02X660258I-1502J0D01*
G02X660628Y559904I1501J0D01*
G03X660630Y559906I-140J142D01*
G03X660678Y560036I-152J130D01*
G01Y560301D01*
G03X660630Y560431I-200J0D01*
G01X660629Y560432D01*
G02X660258Y561420I1130J988D01*
G37*
G36*
G01X1117345D02*
G02X1120349I1502J0D01*
G02X1119979Y560433I-1501J0D01*
G03X1119977Y560431I140J-142D01*
G03X1119929Y560301I152J-130D01*
G01Y560036D01*
G03X1119977Y559906I200J0D01*
G01X1119978Y559905D01*
G02X1120349Y558917I-1130J-988D01*
G02X1117345I-1502J0D01*
G02X1117715Y559904I1501J0D01*
G03X1117717Y559906I-140J142D01*
G03X1117765Y560036I-152J130D01*
G01Y560301D01*
G03X1117717Y560431I-200J0D01*
G01X1117716Y560432D01*
G02X1117345Y561420I1130J988D01*
G37*
G36*
G01X1574432D02*
G02X1577436I1502J0D01*
G02X1577066Y560433I-1501J0D01*
G03X1577064Y560431I140J-142D01*
G03X1577016Y560301I152J-130D01*
G01Y560036D01*
G03X1577064Y559906I200J0D01*
G01X1577065Y559905D01*
G02X1577436Y558917I-1130J-988D01*
G02X1574432I-1502J0D01*
G02X1574802Y559904I1501J0D01*
G03X1574804Y559906I-140J142D01*
G03X1574852Y560036I-152J130D01*
G01Y560301D01*
G03X1574804Y560431I-200J0D01*
G01X1574803Y560432D01*
G02X1574432Y561420I1130J988D01*
G37*
G36*
G01X45390Y562242D02*
X45096D01*
G03X44949Y562177I1J-200D01*
G02X43843Y561692I-1106J1019D01*
G02Y564696I0J1502D01*
G02X44949Y564211I0J-1504D01*
G03X45096Y564146I148J135D01*
G01X45390D01*
G03X45537Y564211I-1J200D01*
G02X46643Y564696I1106J-1019D01*
G02Y561692I0J-1502D01*
G02X45537Y562177I0J1504D01*
G03X45390Y562242I-148J-135D01*
G37*
G36*
G01X502476D02*
X502182D01*
G03X502035Y562177I1J-200D01*
G02X500929Y561692I-1106J1019D01*
G02Y564696I0J1502D01*
G02X502035Y564211I0J-1504D01*
G03X502182Y564146I148J135D01*
G01X502476D01*
G03X502623Y564211I-1J200D01*
G02X503729Y564696I1106J-1019D01*
G02Y561692I0J-1502D01*
G02X502623Y562177I0J1504D01*
G03X502476Y562242I-148J-135D01*
G37*
G36*
G01X959563D02*
X959269D01*
G03X959122Y562177I1J-200D01*
G02X958016Y561692I-1106J1019D01*
G02Y564696I0J1502D01*
G02X959122Y564211I0J-1504D01*
G03X959269Y564146I148J135D01*
G01X959563D01*
G03X959710Y564211I-1J200D01*
G02X960816Y564696I1106J-1019D01*
G02Y561692I0J-1502D01*
G02X959710Y562177I0J1504D01*
G03X959563Y562242I-148J-135D01*
G37*
G36*
G01X1416650D02*
X1416356D01*
G03X1416209Y562177I1J-200D01*
G02X1415103Y561692I-1106J1019D01*
G02Y564696I0J1502D01*
G02X1416209Y564211I0J-1504D01*
G03X1416356Y564146I148J135D01*
G01X1416650D01*
G03X1416797Y564211I-1J200D01*
G02X1417903Y564696I1106J-1019D01*
G02Y561692I0J-1502D01*
G02X1416797Y562177I0J1504D01*
G03X1416650Y562242I-148J-135D01*
G37*
G36*
G01X77232Y564994D02*
Y565300D01*
G03X77161Y565452I-200J-1D01*
G02X76631Y566597I972J1145D01*
G02X79635I1502J0D01*
G02X79105Y565452I-1502J0D01*
G03X79034Y565300I129J-153D01*
G01Y564994D01*
G03X79105Y564842I200J1D01*
G02X79635Y563697I-972J-1145D01*
G02X79229Y562670I-1502J0D01*
G01X79203Y562643D01*
X79175Y562572D01*
Y562222D01*
X79203Y562151D01*
X79229Y562124D01*
G02Y560070I-1096J-1027D01*
G01X79203Y560043D01*
X79175Y559972D01*
Y559622D01*
X79203Y559551D01*
X79229Y559524D01*
G02Y557470I-1096J-1027D01*
G01X79203Y557443D01*
X79175Y557372D01*
Y557022D01*
X79203Y556951D01*
X79229Y556924D01*
G02Y554870I-1096J-1027D01*
G01X79203Y554843D01*
X79175Y554772D01*
Y554422D01*
X79203Y554351D01*
X79229Y554324D01*
G02X79635Y553297I-1096J-1027D01*
G02X76631I-1502J0D01*
G02X77037Y554324I1502J0D01*
G01X77063Y554351D01*
X77091Y554422D01*
Y554772D01*
X77063Y554843D01*
X77037Y554870D01*
G02Y556924I1096J1027D01*
G01X77063Y556951D01*
X77091Y557022D01*
Y557372D01*
X77063Y557443D01*
X77037Y557470D01*
G02Y559524I1096J1027D01*
G01X77063Y559551D01*
X77091Y559622D01*
Y559972D01*
X77063Y560043D01*
X77037Y560070D01*
G02Y562124I1096J1027D01*
G01X77063Y562151D01*
X77091Y562222D01*
Y562572D01*
X77063Y562643D01*
X77037Y562670D01*
G02X76631Y563697I1096J1027D01*
G02X77161Y564842I1502J0D01*
G03X77232Y564994I-129J153D01*
G37*
G36*
G01X45390Y570242D02*
X45096D01*
G03X44949Y570177I1J-200D01*
G02X43843Y569692I-1106J1019D01*
G02Y572696I0J1502D01*
G02X44949Y572211I0J-1504D01*
G03X45096Y572146I148J135D01*
G01X45390D01*
G03X45537Y572211I-1J200D01*
G02X46643Y572696I1106J-1019D01*
G02Y569692I0J-1502D01*
G02X45537Y570177I0J1504D01*
G03X45390Y570242I-148J-135D01*
G37*
G36*
G01X502476D02*
X502182D01*
G03X502035Y570177I1J-200D01*
G02X500929Y569692I-1106J1019D01*
G02Y572696I0J1502D01*
G02X502035Y572211I0J-1504D01*
G03X502182Y572146I148J135D01*
G01X502476D01*
G03X502623Y572211I-1J200D01*
G02X503729Y572696I1106J-1019D01*
G02Y569692I0J-1502D01*
G02X502623Y570177I0J1504D01*
G03X502476Y570242I-148J-135D01*
G37*
G36*
G01X959563D02*
X959269D01*
G03X959122Y570177I1J-200D01*
G02X958016Y569692I-1106J1019D01*
G02Y572696I0J1502D01*
G02X959122Y572211I0J-1504D01*
G03X959269Y572146I148J135D01*
G01X959563D01*
G03X959710Y572211I-1J200D01*
G02X960816Y572696I1106J-1019D01*
G02Y569692I0J-1502D01*
G02X959710Y570177I0J1504D01*
G03X959563Y570242I-148J-135D01*
G37*
G36*
G01X1416650D02*
X1416356D01*
G03X1416209Y570177I1J-200D01*
G02X1415103Y569692I-1106J1019D01*
G02Y572696I0J1502D01*
G02X1416209Y572211I0J-1504D01*
G03X1416356Y572146I148J135D01*
G01X1416650D01*
G03X1416797Y572211I-1J200D01*
G02X1417903Y572696I1106J-1019D01*
G02Y569692I0J-1502D01*
G02X1416797Y570177I0J1504D01*
G03X1416650Y570242I-148J-135D01*
G37*
G36*
G01X46653Y582174D02*
X46947D01*
G03X47094Y582239I-1J200D01*
G02X49306I1106J-1017D01*
G03X49453Y582174I148J135D01*
G01X49747D01*
G03X49894Y582239I-1J200D01*
G02X51000Y582724I1106J-1019D01*
G02Y579720I0J-1502D01*
G02X49894Y580205I0J1504D01*
G03X49747Y580270I-148J-135D01*
G01X49453D01*
G03X49306Y580205I1J-200D01*
G02X47094I-1106J1017D01*
G03X46947Y580270I-148J-135D01*
G01X46653D01*
G03X46506Y580205I1J-200D01*
G02X45400Y579720I-1106J1019D01*
G02Y582724I0J1502D01*
G02X46506Y582239I0J-1504D01*
G03X46653Y582174I148J135D01*
G37*
G36*
G01X503739D02*
X504033D01*
G03X504180Y582239I-1J200D01*
G02X506392I1106J-1017D01*
G03X506539Y582174I148J135D01*
G01X506833D01*
G03X506980Y582239I-1J200D01*
G02X508086Y582724I1106J-1019D01*
G02Y579720I0J-1502D01*
G02X506980Y580205I0J1504D01*
G03X506833Y580270I-148J-135D01*
G01X506539D01*
G03X506392Y580205I1J-200D01*
G02X504180I-1106J1017D01*
G03X504033Y580270I-148J-135D01*
G01X503739D01*
G03X503592Y580205I1J-200D01*
G02X502486Y579720I-1106J1019D01*
G02Y582724I0J1502D01*
G02X503592Y582239I0J-1504D01*
G03X503739Y582174I148J135D01*
G37*
G36*
G01X960826D02*
X961120D01*
G03X961267Y582239I-1J200D01*
G02X963479I1106J-1017D01*
G03X963626Y582174I148J135D01*
G01X963920D01*
G03X964067Y582239I-1J200D01*
G02X965173Y582724I1106J-1019D01*
G02Y579720I0J-1502D01*
G02X964067Y580205I0J1504D01*
G03X963920Y580270I-148J-135D01*
G01X963626D01*
G03X963479Y580205I1J-200D01*
G02X961267I-1106J1017D01*
G03X961120Y580270I-148J-135D01*
G01X960826D01*
G03X960679Y580205I1J-200D01*
G02X959573Y579720I-1106J1019D01*
G02Y582724I0J1502D01*
G02X960679Y582239I0J-1504D01*
G03X960826Y582174I148J135D01*
G37*
G36*
G01X1417913D02*
X1418207D01*
G03X1418354Y582239I-1J200D01*
G02X1420566I1106J-1017D01*
G03X1420713Y582174I148J135D01*
G01X1421007D01*
G03X1421154Y582239I-1J200D01*
G02X1422260Y582724I1106J-1019D01*
G02Y579720I0J-1502D01*
G02X1421154Y580205I0J1504D01*
G03X1421007Y580270I-148J-135D01*
G01X1420713D01*
G03X1420566Y580205I1J-200D01*
G02X1418354I-1106J1017D01*
G03X1418207Y580270I-148J-135D01*
G01X1417913D01*
G03X1417766Y580205I1J-200D01*
G02X1416660Y579720I-1106J1019D01*
G02Y582724I0J1502D01*
G02X1417766Y582239I0J-1504D01*
G03X1417913Y582174I148J135D01*
G37*
G36*
G01X46653Y592167D02*
X46947D01*
G03X47094Y592232I-1J200D01*
G02X49306I1106J-1017D01*
G03X49453Y592167I148J135D01*
G01X49747D01*
G03X49894Y592232I-1J200D01*
G02X51000Y592717I1106J-1019D01*
G02Y589713I0J-1502D01*
G02X49894Y590198I0J1504D01*
G03X49747Y590263I-148J-135D01*
G01X49453D01*
G03X49306Y590198I1J-200D01*
G02X47094I-1106J1017D01*
G03X46947Y590263I-148J-135D01*
G01X46653D01*
G03X46506Y590198I1J-200D01*
G02X45400Y589713I-1106J1019D01*
G02Y592717I0J1502D01*
G02X46506Y592232I0J-1504D01*
G03X46653Y592167I148J135D01*
G37*
G36*
G01X503739D02*
X504033D01*
G03X504180Y592232I-1J200D01*
G02X506392I1106J-1017D01*
G03X506539Y592167I148J135D01*
G01X506833D01*
G03X506980Y592232I-1J200D01*
G02X508086Y592717I1106J-1019D01*
G02Y589713I0J-1502D01*
G02X506980Y590198I0J1504D01*
G03X506833Y590263I-148J-135D01*
G01X506539D01*
G03X506392Y590198I1J-200D01*
G02X504180I-1106J1017D01*
G03X504033Y590263I-148J-135D01*
G01X503739D01*
G03X503592Y590198I1J-200D01*
G02X502486Y589713I-1106J1019D01*
G02Y592717I0J1502D01*
G02X503592Y592232I0J-1504D01*
G03X503739Y592167I148J135D01*
G37*
G36*
G01X960826D02*
X961120D01*
G03X961267Y592232I-1J200D01*
G02X963479I1106J-1017D01*
G03X963626Y592167I148J135D01*
G01X963920D01*
G03X964067Y592232I-1J200D01*
G02X965173Y592717I1106J-1019D01*
G02Y589713I0J-1502D01*
G02X964067Y590198I0J1504D01*
G03X963920Y590263I-148J-135D01*
G01X963626D01*
G03X963479Y590198I1J-200D01*
G02X961267I-1106J1017D01*
G03X961120Y590263I-148J-135D01*
G01X960826D01*
G03X960679Y590198I1J-200D01*
G02X959573Y589713I-1106J1019D01*
G02Y592717I0J1502D01*
G02X960679Y592232I0J-1504D01*
G03X960826Y592167I148J135D01*
G37*
G36*
G01X1417913D02*
X1418207D01*
G03X1418354Y592232I-1J200D01*
G02X1420566I1106J-1017D01*
G03X1420713Y592167I148J135D01*
G01X1421007D01*
G03X1421154Y592232I-1J200D01*
G02X1422260Y592717I1106J-1019D01*
G02Y589713I0J-1502D01*
G02X1421154Y590198I0J1504D01*
G03X1421007Y590263I-148J-135D01*
G01X1420713D01*
G03X1420566Y590198I1J-200D01*
G02X1418354I-1106J1017D01*
G03X1418207Y590263I-148J-135D01*
G01X1417913D01*
G03X1417766Y590198I1J-200D01*
G02X1416660Y589713I-1106J1019D01*
G02Y592717I0J1502D01*
G02X1417766Y592232I0J-1504D01*
G03X1417913Y592167I148J135D01*
G37*
G36*
G01X49625Y611514D02*
X49919D01*
G03X50066Y611579I-1J200D01*
G02X52278I1106J-1017D01*
G03X52425Y611514I148J135D01*
G01X52719D01*
G03X52866Y611579I-1J200D01*
G02X53972Y612064I1106J-1019D01*
G02X55474Y610562I0J-1502D01*
G02X54989Y609456I-1504J0D01*
G03X54924Y609309I135J-148D01*
G01Y609015D01*
G03X54989Y608868I200J1D01*
G02X55474Y607762I-1019J-1106D01*
G02X53972Y606260I-1502J0D01*
G02X52866Y606745I0J1504D01*
G03X52719Y606810I-148J-135D01*
G01X52425D01*
G03X52278Y606745I1J-200D01*
G02X50066I-1106J1017D01*
G03X49919Y606810I-148J-135D01*
G01X49625D01*
G03X49478Y606745I1J-200D01*
G02X47266I-1106J1017D01*
G03X47119Y606810I-148J-135D01*
G01X46825D01*
G03X46678Y606745I1J-200D01*
G02X45572Y606260I-1106J1019D01*
G02X44070Y607762I0J1502D01*
G02X44555Y608868I1504J0D01*
G03X44620Y609015I-135J148D01*
G01Y609309D01*
G03X44555Y609456I-200J-1D01*
G02X44070Y610562I1019J1106D01*
G02X45572Y612064I1502J0D01*
G02X46678Y611579I0J-1504D01*
G03X46825Y611514I148J135D01*
G01X47119D01*
G03X47266Y611579I-1J200D01*
G02X49478I1106J-1017D01*
G03X49625Y611514I148J135D01*
G37*
G36*
G01X963798D02*
X964092D01*
G03X964239Y611579I-1J200D01*
G02X966451I1106J-1017D01*
G03X966598Y611514I148J135D01*
G01X966892D01*
G03X967039Y611579I-1J200D01*
G02X968145Y612064I1106J-1019D01*
G02X969647Y610562I0J-1502D01*
G02X969162Y609456I-1504J0D01*
G03X969097Y609309I135J-148D01*
G01Y609015D01*
G03X969162Y608868I200J1D01*
G02X969647Y607762I-1019J-1106D01*
G02X968145Y606260I-1502J0D01*
G02X967039Y606745I0J1504D01*
G03X966892Y606810I-148J-135D01*
G01X966598D01*
G03X966451Y606745I1J-200D01*
G02X964239I-1106J1017D01*
G03X964092Y606810I-148J-135D01*
G01X963798D01*
G03X963651Y606745I1J-200D01*
G02X961439I-1106J1017D01*
G03X961292Y606810I-148J-135D01*
G01X960998D01*
G03X960851Y606745I1J-200D01*
G02X959745Y606260I-1106J1019D01*
G02X958243Y607762I0J1502D01*
G02X958728Y608868I1504J0D01*
G03X958793Y609015I-135J148D01*
G01Y609309D01*
G03X958728Y609456I-200J-1D01*
G02X958243Y610562I1019J1106D01*
G02X959745Y612064I1502J0D01*
G02X960851Y611579I0J-1504D01*
G03X960998Y611514I148J135D01*
G01X961292D01*
G03X961439Y611579I-1J200D01*
G02X963651I1106J-1017D01*
G03X963798Y611514I148J135D01*
G37*
G36*
G01X1420885D02*
X1421179D01*
G03X1421326Y611579I-1J200D01*
G02X1423538I1106J-1017D01*
G03X1423685Y611514I148J135D01*
G01X1423979D01*
G03X1424126Y611579I-1J200D01*
G02X1425232Y612064I1106J-1019D01*
G02X1426734Y610562I0J-1502D01*
G02X1426249Y609456I-1504J0D01*
G03X1426184Y609309I135J-148D01*
G01Y609015D01*
G03X1426249Y608868I200J1D01*
G02X1426734Y607762I-1019J-1106D01*
G02X1425232Y606260I-1502J0D01*
G02X1424126Y606745I0J1504D01*
G03X1423979Y606810I-148J-135D01*
G01X1423685D01*
G03X1423538Y606745I1J-200D01*
G02X1421326I-1106J1017D01*
G03X1421179Y606810I-148J-135D01*
G01X1420885D01*
G03X1420738Y606745I1J-200D01*
G02X1418526I-1106J1017D01*
G03X1418379Y606810I-148J-135D01*
G01X1418085D01*
G03X1417938Y606745I1J-200D01*
G02X1416832Y606260I-1106J1019D01*
G02X1415330Y607762I0J1502D01*
G02X1415815Y608868I1504J0D01*
G03X1415880Y609015I-135J148D01*
G01Y609309D01*
G03X1415815Y609456I-200J-1D01*
G02X1415330Y610562I1019J1106D01*
G02X1416832Y612064I1502J0D01*
G02X1417938Y611579I0J-1504D01*
G03X1418085Y611514I148J135D01*
G01X1418379D01*
G03X1418526Y611579I-1J200D01*
G02X1420738I1106J-1017D01*
G03X1420885Y611514I148J135D01*
G37*
G36*
G01X68718Y617966D02*
Y618260D01*
G03X68653Y618407I-200J-1D01*
G02X68168Y619513I1019J1106D01*
G02X71172I1502J0D01*
G02X70687Y618407I-1504J0D01*
G03X70622Y618260I135J-148D01*
G01Y617966D01*
G03X70687Y617819I200J1D01*
G02Y615607I-1017J-1106D01*
G03X70622Y615460I135J-148D01*
G01Y615166D01*
G03X70687Y615019I200J1D01*
G02X71172Y613913I-1019J-1106D01*
G02X68168I-1502J0D01*
G02X68653Y615019I1504J0D01*
G03X68718Y615166I-135J148D01*
G01Y615460D01*
G03X68653Y615607I-200J-1D01*
G02Y617819I1017J1106D01*
G03X68718Y617966I-135J148D01*
G37*
G36*
G01X525804D02*
Y618260D01*
G03X525739Y618407I-200J-1D01*
G02X525254Y619513I1019J1106D01*
G02X528258I1502J0D01*
G02X527773Y618407I-1504J0D01*
G03X527708Y618260I135J-148D01*
G01Y617966D01*
G03X527773Y617819I200J1D01*
G02Y615607I-1017J-1106D01*
G03X527708Y615460I135J-148D01*
G01Y615166D01*
G03X527773Y615019I200J1D01*
G02X528258Y613913I-1019J-1106D01*
G02X525254I-1502J0D01*
G02X525739Y615019I1504J0D01*
G03X525804Y615166I-135J148D01*
G01Y615460D01*
G03X525739Y615607I-200J-1D01*
G02Y617819I1017J1106D01*
G03X525804Y617966I-135J148D01*
G37*
G36*
G01X982891D02*
Y618260D01*
G03X982826Y618407I-200J-1D01*
G02X982341Y619513I1019J1106D01*
G02X985345I1502J0D01*
G02X984860Y618407I-1504J0D01*
G03X984795Y618260I135J-148D01*
G01Y617966D01*
G03X984860Y617819I200J1D01*
G02Y615607I-1017J-1106D01*
G03X984795Y615460I135J-148D01*
G01Y615166D01*
G03X984860Y615019I200J1D01*
G02X985345Y613913I-1019J-1106D01*
G02X982341I-1502J0D01*
G02X982826Y615019I1504J0D01*
G03X982891Y615166I-135J148D01*
G01Y615460D01*
G03X982826Y615607I-200J-1D01*
G02Y617819I1017J1106D01*
G03X982891Y617966I-135J148D01*
G37*
G36*
G01X1439978D02*
Y618260D01*
G03X1439913Y618407I-200J-1D01*
G02X1439428Y619513I1019J1106D01*
G02X1442432I1502J0D01*
G02X1441947Y618407I-1504J0D01*
G03X1441882Y618260I135J-148D01*
G01Y617966D01*
G03X1441947Y617819I200J1D01*
G02Y615607I-1017J-1106D01*
G03X1441882Y615460I135J-148D01*
G01Y615166D01*
G03X1441947Y615019I200J1D01*
G02X1442432Y613913I-1019J-1106D01*
G02X1439428I-1502J0D01*
G02X1439913Y615019I1504J0D01*
G03X1439978Y615166I-135J148D01*
G01Y615460D01*
G03X1439913Y615607I-200J-1D01*
G02Y617819I1017J1106D01*
G03X1439978Y617966I-135J148D01*
G37*
G36*
G01X80788Y618211D02*
Y618505D01*
G03X80723Y618652I-200J-1D01*
G02X80238Y619758I1019J1106D01*
G02X83242I1502J0D01*
G02X82757Y618652I-1504J0D01*
G03X82692Y618505I135J-148D01*
G01Y618211D01*
G03X82757Y618064I200J1D01*
G02Y615852I-1017J-1106D01*
G03X82692Y615705I135J-148D01*
G01Y615411D01*
G03X82757Y615264I200J1D01*
G02X83242Y614158I-1019J-1106D01*
G02X80238I-1502J0D01*
G02X80723Y615264I1504J0D01*
G03X80788Y615411I-135J148D01*
G01Y615705D01*
G03X80723Y615852I-200J-1D01*
G02Y618064I1017J1106D01*
G03X80788Y618211I-135J148D01*
G37*
G36*
G01X537874D02*
Y618505D01*
G03X537809Y618652I-200J-1D01*
G02X537324Y619758I1019J1106D01*
G02X540328I1502J0D01*
G02X539843Y618652I-1504J0D01*
G03X539778Y618505I135J-148D01*
G01Y618211D01*
G03X539843Y618064I200J1D01*
G02Y615852I-1017J-1106D01*
G03X539778Y615705I135J-148D01*
G01Y615411D01*
G03X539843Y615264I200J1D01*
G02X540328Y614158I-1019J-1106D01*
G02X537324I-1502J0D01*
G02X537809Y615264I1504J0D01*
G03X537874Y615411I-135J148D01*
G01Y615705D01*
G03X537809Y615852I-200J-1D01*
G02Y618064I1017J1106D01*
G03X537874Y618211I-135J148D01*
G37*
G36*
G01X994961D02*
Y618505D01*
G03X994896Y618652I-200J-1D01*
G02X994411Y619758I1019J1106D01*
G02X997415I1502J0D01*
G02X996930Y618652I-1504J0D01*
G03X996865Y618505I135J-148D01*
G01Y618211D01*
G03X996930Y618064I200J1D01*
G02Y615852I-1017J-1106D01*
G03X996865Y615705I135J-148D01*
G01Y615411D01*
G03X996930Y615264I200J1D01*
G02X997415Y614158I-1019J-1106D01*
G02X994411I-1502J0D01*
G02X994896Y615264I1504J0D01*
G03X994961Y615411I-135J148D01*
G01Y615705D01*
G03X994896Y615852I-200J-1D01*
G02Y618064I1017J1106D01*
G03X994961Y618211I-135J148D01*
G37*
G36*
G01X1452048D02*
Y618505D01*
G03X1451983Y618652I-200J-1D01*
G02X1451498Y619758I1019J1106D01*
G02X1454502I1502J0D01*
G02X1454017Y618652I-1504J0D01*
G03X1453952Y618505I135J-148D01*
G01Y618211D01*
G03X1454017Y618064I200J1D01*
G02Y615852I-1017J-1106D01*
G03X1453952Y615705I135J-148D01*
G01Y615411D01*
G03X1454017Y615264I200J1D01*
G02X1454502Y614158I-1019J-1106D01*
G02X1451498I-1502J0D01*
G02X1451983Y615264I1504J0D01*
G03X1452048Y615411I-135J148D01*
G01Y615705D01*
G03X1451983Y615852I-200J-1D01*
G02Y618064I1017J1106D01*
G03X1452048Y618211I-135J148D01*
G37*
G36*
G01X60902Y619106D02*
Y619400D01*
G03X60837Y619547I-200J-1D01*
G02X60352Y620653I1019J1106D01*
G02X63356I1502J0D01*
G02X62871Y619547I-1504J0D01*
G03X62806Y619400I135J-148D01*
G01Y619106D01*
G03X62871Y618959I200J1D01*
G02X63356Y617853I-1019J-1106D01*
G02X60352I-1502J0D01*
G02X60837Y618959I1504J0D01*
G03X60902Y619106I-135J148D01*
G37*
G36*
G01X517988D02*
Y619400D01*
G03X517923Y619547I-200J-1D01*
G02X517438Y620653I1019J1106D01*
G02X520442I1502J0D01*
G02X519957Y619547I-1504J0D01*
G03X519892Y619400I135J-148D01*
G01Y619106D01*
G03X519957Y618959I200J1D01*
G02X520442Y617853I-1019J-1106D01*
G02X517438I-1502J0D01*
G02X517923Y618959I1504J0D01*
G03X517988Y619106I-135J148D01*
G37*
G36*
G01X975075D02*
Y619400D01*
G03X975010Y619547I-200J-1D01*
G02X974525Y620653I1019J1106D01*
G02X977529I1502J0D01*
G02X977044Y619547I-1504J0D01*
G03X976979Y619400I135J-148D01*
G01Y619106D01*
G03X977044Y618959I200J1D01*
G02X977529Y617853I-1019J-1106D01*
G02X974525I-1502J0D01*
G02X975010Y618959I1504J0D01*
G03X975075Y619106I-135J148D01*
G37*
G36*
G01X1432162D02*
Y619400D01*
G03X1432097Y619547I-200J-1D01*
G02X1431612Y620653I1019J1106D01*
G02X1434616I1502J0D01*
G02X1434131Y619547I-1504J0D01*
G03X1434066Y619400I135J-148D01*
G01Y619106D01*
G03X1434131Y618959I200J1D01*
G02X1434616Y617853I-1019J-1106D01*
G02X1431612I-1502J0D01*
G02X1432097Y618959I1504J0D01*
G03X1432162Y619106I-135J148D01*
G37*
G36*
G01X1711503Y553800D02*
G02X1711676Y553101I-1329J-700D01*
G02X1708672I-1502J0D01*
G02X1708845Y553800I1502J-1D01*
G03X1708868Y553893I-177J93D01*
G01Y615101D01*
G03X1708809Y615243I-200J0D01*
G01X1698505Y625547D01*
G03X1698363Y625606I-142J-141D01*
G01X1693792D01*
G03X1693699Y625583I0J-200D01*
G02X1693000Y625410I-700J1329D01*
G02Y628414I0J1502D01*
G02X1693699Y628241I-1J-1502D01*
G03X1693792Y628218I93J177D01*
G01X1698989D01*
G02X1699911Y627836I-1J-1306D01*
G01X1711098Y616649D01*
G02X1711480Y615727I-924J-923D01*
G01Y553893D01*
G03X1711503Y553800I200J0D01*
G37*
G36*
G01X1001605Y626103D02*
G02Y629107I0J1502D01*
G01X1001608D01*
G02X1002030Y629046I-2J-1502D01*
G03X1002173Y629057I57J192D01*
G01X1002415Y629172D01*
G03X1002513Y629275I-87J181D01*
G01Y629276D01*
G02X1003900Y630202I1387J-576D01*
G02Y627198I0J-1502D01*
G01X1003897D01*
G02X1003475Y627259I2J1502D01*
G03X1003332Y627248I-57J-192D01*
G01X1003090Y627133D01*
G03X1002992Y627030I87J-181D01*
G01Y627029D01*
G02X1001605Y626103I-1387J576D01*
G37*
G36*
G01X35293Y661450D02*
G02Y664454I0J1502D01*
G02X36320Y664048I0J-1502D01*
G01X36347Y664023D01*
X36415Y663995D01*
X36723Y663990D01*
G03X36857Y664039I3J200D01*
G02X37847Y664412I991J-1129D01*
G02Y661408I0J-1502D01*
G02X36820Y661814I0J1502D01*
G01X36793Y661839D01*
X36725Y661867D01*
X36417Y661872D01*
G03X36283Y661823I-3J-200D01*
G02X35293Y661450I-991J1129D01*
G37*
G36*
G01X35250Y670006D02*
G02Y673010I0J1502D01*
G02X36258Y672621I-1J-1502D01*
G01X36259Y672620D01*
G03X36393Y672569I133J149D01*
G01X36661D01*
G03X36795Y672620I1J200D01*
G01X36796Y672621D01*
G02X37804Y673010I1009J-1113D01*
G02Y670006I0J-1502D01*
G02X36796Y670395I1J1502D01*
G01X36795Y670396D01*
G03X36661Y670447I-133J-149D01*
G01X36393D01*
G03X36259Y670396I-1J-200D01*
G01X36258Y670395D01*
G02X35250Y670006I-1009J1113D01*
G37*
G36*
G01X545725Y678299D02*
G02X548729I1502J0D01*
G02X548272Y677220I-1502J0D01*
G01X548242Y677191D01*
X548211Y677115D01*
X548217Y676739D01*
X548251Y676664D01*
X548282Y676636D01*
G02X548778Y675521I-1005J-1115D01*
G02X545774I-1502J0D01*
G02X546231Y676600I1502J0D01*
G01X546261Y676629D01*
X546292Y676705D01*
X546286Y677081D01*
X546252Y677156D01*
X546221Y677184D01*
G02X545725Y678299I1005J1115D01*
G37*
G36*
G01X36910Y680606D02*
G02Y683610I0J1502D01*
G02X37952Y683190I0J-1503D01*
G01X37981Y683162D01*
X38051Y683134D01*
X38408D01*
X38478Y683162D01*
X38507Y683190D01*
G02X39549Y683610I1042J-1083D01*
G02Y680606I0J-1502D01*
G02X38507Y681026I0J1503D01*
G01X38478Y681054D01*
X38408Y681082D01*
X38051D01*
X37981Y681054D01*
X37952Y681026D01*
G02X36910Y680606I-1042J1083D01*
G37*
G36*
G01X535738Y685987D02*
G02Y688991I0J1502D01*
G02X536812Y688539I0J-1502D01*
G03X536945Y688479I143J140D01*
G01X537254Y688463D01*
X537325Y688487D01*
X537354Y688511D01*
G02X538315Y688859I961J-1154D01*
G01X538316D01*
G02Y685855I0J-1502D01*
G02X537242Y686307I0J1502D01*
G03X537109Y686367I-143J-140D01*
G01X536800Y686383D01*
X536729Y686359D01*
X536700Y686335D01*
G02X535739Y685987I-961J1154D01*
G01X535738D01*
G37*
G36*
G01X201544Y693687D02*
G03X201138Y694079I-400J-8D01*
G01X201115D01*
G02Y697083I0J1502D01*
G02X202617Y695610I0J-1502D01*
G03X203023Y695218I400J8D01*
G01X203046D01*
G02Y692214I0J-1502D01*
G02X201544Y693687I0J1502D01*
G37*
G36*
G01X35818Y700034D02*
X36112D01*
G03X36259Y700099I-1J200D01*
G02X38471I1106J-1017D01*
G03X38618Y700034I148J135D01*
G01X38912D01*
G03X39059Y700099I-1J200D01*
G02X40165Y700584I1106J-1019D01*
G02Y697580I0J-1502D01*
G02X39059Y698065I0J1504D01*
G03X38912Y698130I-148J-135D01*
G01X38618D01*
G03X38471Y698065I1J-200D01*
G02X36259I-1106J1017D01*
G03X36112Y698130I-148J-135D01*
G01X35818D01*
G03X35671Y698065I1J-200D01*
G02X34565Y697580I-1106J1019D01*
G02Y700584I0J1502D01*
G02X35671Y700099I0J-1504D01*
G03X35818Y700034I148J135D01*
G37*
G36*
G01X1161133Y700623D02*
X1161134Y700622D01*
G03X1161264Y700574I130J152D01*
G01X1161528D01*
G03X1161658Y700622I0J200D01*
G01X1161659Y700623D01*
G02X1162646Y700993I987J-1131D01*
G02Y697989I0J-1502D01*
G02X1161659Y698359I0J1501D01*
G01X1161658D01*
Y698360D01*
G03X1161528Y698408I-130J-152D01*
G01X1161264D01*
G03X1161134Y698360I0J-200D01*
G01X1161133Y698359D01*
G02X1159159I-987J1131D01*
G01X1159158D01*
Y698360D01*
G03X1159028Y698408I-130J-152D01*
G01X1158764D01*
G03X1158634Y698360I0J-200D01*
G01X1158633Y698359D01*
G02X1156659I-987J1131D01*
G01X1156658D01*
Y698360D01*
G03X1156528Y698408I-130J-152D01*
G01X1156264D01*
G03X1156134Y698360I0J-200D01*
G01X1156133Y698359D01*
G02X1155146Y697989I-987J1131D01*
G02Y700993I0J1502D01*
G02X1156133Y700623I0J-1501D01*
G01X1156134D01*
Y700622D01*
G03X1156264Y700574I130J152D01*
G01X1156528D01*
G03X1156658Y700622I0J200D01*
G01X1156659Y700623D01*
G02X1158633I987J-1131D01*
G01X1158634D01*
Y700622D01*
G03X1158764Y700574I130J152D01*
G01X1159028D01*
G03X1159158Y700622I0J200D01*
G01X1159159Y700623D01*
G02X1161133I987J-1131D01*
G37*
G36*
G01X528099Y702622D02*
G02X530903I1402J0D01*
G02X530436Y701577I-1403J0D01*
G01X530404Y701549D01*
X530369Y701471D01*
X530368Y701131D01*
G03X530434Y700982I200J0D01*
G02X530895Y699943I-940J-1039D01*
G01Y699942D01*
G02X530503Y698970I-1402J0D01*
G01X530475Y698941D01*
X530447Y698871D01*
Y698515D01*
X530475Y698445D01*
X530503Y698416D01*
G02X530895Y697443I-1010J-972D01*
G02X530503Y696470I-1402J-1D01*
G01X530475Y696441D01*
X530447Y696371D01*
Y696015D01*
X530475Y695945D01*
X530503Y695916D01*
G02X530895Y694943I-1010J-972D01*
G02X530503Y693970I-1402J-1D01*
G01X530475Y693941D01*
X530447Y693871D01*
Y693515D01*
X530475Y693445D01*
X530503Y693416D01*
G02X530895Y692444I-1010J-972D01*
G01Y692443D01*
G02X529493Y691041I-1402J0D01*
G01X529492D01*
G02X528520Y691433I0J1402D01*
G01X528491Y691461D01*
X528421Y691489D01*
X528065D01*
X527995Y691461D01*
X527966Y691433D01*
G02X526993Y691041I-972J1010D01*
G02X526020Y691433I-1J1402D01*
G01X525991Y691461D01*
X525921Y691489D01*
X525565D01*
X525495Y691461D01*
X525466Y691433D01*
G02X524494Y691041I-972J1010D01*
G01X524493D01*
G02Y693845I0J1402D01*
G01X524494D01*
G02X525466Y693453I0J-1402D01*
G01X525495Y693425D01*
X525565Y693397D01*
X525921D01*
X525991Y693425D01*
X526020Y693453D01*
G02X526993Y693845I972J-1010D01*
G02X527966Y693453I1J-1402D01*
G01X527995Y693425D01*
X528065Y693397D01*
X528421D01*
X528491Y693425D01*
X528520Y693453D01*
G02X528550Y693481I972J-1011D01*
G03X528616Y693629I-134J148D01*
G01Y693757D01*
G03X528550Y693905I-200J0D01*
G02X528091Y694943I944J1038D01*
G01Y694944D01*
G02X528483Y695916I1402J0D01*
G01X528511Y695945D01*
X528539Y696015D01*
Y696371D01*
X528511Y696441D01*
X528483Y696470D01*
G02X528091Y697443I1010J972D01*
G02X528483Y698416I1402J1D01*
G01X528511Y698445D01*
X528539Y698515D01*
Y698871D01*
X528511Y698941D01*
X528483Y698970D01*
G02X528091Y699942I1010J972D01*
G01Y699943D01*
G02X528558Y700988I1403J0D01*
G01X528590Y701016D01*
X528625Y701094D01*
X528626Y701434D01*
G03X528560Y701583I-200J0D01*
G02X528099Y702622I940J1039D01*
G37*
G36*
G01X522395Y707306D02*
X522693D01*
G03X522841Y707372I0J200D01*
G02X525017I1088J-983D01*
G03X525165Y707306I148J134D01*
G01X525463D01*
G03X525611Y707372I0J200D01*
G02X527843Y707306I1088J-983D01*
G01X527870Y707273D01*
X527945Y707234D01*
X528285Y707215D01*
G03X528436Y707271I12J200D01*
G01X528437Y707272D01*
G02X529469Y707697I1033J-1042D01*
G02Y704763I0J-1467D01*
G02X528325Y705312I0J1466D01*
G01X528298Y705345D01*
X528223Y705384D01*
X527883Y705403D01*
G03X527732Y705347I-12J-200D01*
G01X527731Y705346D01*
G02X526699Y704921I-1033J1042D01*
G02X525611Y705404I0J1467D01*
G03X525463Y705470I-148J-134D01*
G01X525165D01*
G03X525017Y705404I0J-200D01*
G02X522841I-1088J983D01*
G03X522693Y705470I-148J-134D01*
G01X522395D01*
G03X522247Y705404I0J-200D01*
G02X520071I-1088J983D01*
G03X519923Y705470I-148J-134D01*
G01X519625D01*
G03X519477Y705404I0J-200D01*
G02X518389Y704921I-1088J984D01*
G02X517313Y705392I1J1467D01*
G03X517166Y705456I-147J-136D01*
G01X516872D01*
G03X516725Y705392I0J-200D01*
G02X515649Y704921I-1077J996D01*
G02Y707855I0J1467D01*
G02X516725Y707384I-1J-1467D01*
G03X516872Y707320I147J136D01*
G01X517166D01*
G03X517313Y707384I0J200D01*
G02X518389Y707855I1077J-996D01*
G02X519477Y707372I0J-1467D01*
G03X519625Y707306I148J134D01*
G01X519923D01*
G03X520071Y707372I0J200D01*
G02X522247I1088J-983D01*
G03X522395Y707306I148J134D01*
G37*
G36*
G01X363015Y708863D02*
G02Y711867I0J1502D01*
G02X364161Y711335I0J-1500D01*
G01X364189Y711302D01*
X364267Y711265D01*
X364657Y711261D01*
X364737Y711296D01*
X364765Y711328D01*
G02X365887Y711831I1122J-1000D01*
G02Y708827I0J-1502D01*
G02X364741Y709359I0J1500D01*
G01X364713Y709392D01*
X364635Y709429D01*
X364245Y709433D01*
X364165Y709398D01*
X364137Y709366D01*
G02X363015Y708863I-1122J1000D01*
G37*
G36*
G01X437777Y713531D02*
X437778Y713530D01*
G03X437908Y713482I130J152D01*
G01X438172D01*
G03X438302Y713530I0J200D01*
G01X438303Y713531D01*
G02X439290Y713901I987J-1131D01*
G02X440792Y712399I0J-1502D01*
G02X440386Y711372I-1502J0D01*
G01X440360Y711345D01*
X440332Y711274D01*
Y710924D01*
X440360Y710853D01*
X440386Y710826D01*
G02X440792Y709799I-1096J-1027D01*
G02X439290Y708297I-1502J0D01*
G02X438303Y708667I0J1501D01*
G01X438302D01*
Y708668D01*
G03X438172Y708716I-130J-152D01*
G01X437908D01*
G03X437778Y708668I0J-200D01*
G01X437777Y708667D01*
G02X435803I-987J1131D01*
G01X435802D01*
Y708668D01*
G03X435672Y708716I-130J-152D01*
G01X435408D01*
G03X435278Y708668I0J-200D01*
G01X435277Y708667D01*
G02X433303I-987J1131D01*
G01X433302D01*
Y708668D01*
G03X433172Y708716I-130J-152D01*
G01X432908D01*
G03X432778Y708668I0J-200D01*
G01X432777Y708667D01*
G02X430803I-987J1131D01*
G01X430802D01*
Y708668D01*
G03X430672Y708716I-130J-152D01*
G01X430408D01*
G03X430278Y708668I0J-200D01*
G01X430277Y708667D01*
G02X429290Y708297I-987J1131D01*
G02X428246Y708719I0J1502D01*
G01X428217Y708747D01*
X428145Y708775D01*
X427822Y708771D01*
G03X427682Y708711I3J-200D01*
G02X426607Y708258I-1075J1049D01*
G02X425105Y709760I0J1502D01*
G02X425511Y710787I1502J0D01*
G01X425537Y710814D01*
X425565Y710885D01*
Y711235D01*
X425537Y711306D01*
X425511Y711333D01*
G02X425105Y712360I1096J1027D01*
G02X426607Y713862I1502J0D01*
G02X427651Y713440I0J-1502D01*
G01X427680Y713412D01*
X427752Y713384D01*
X428075Y713388D01*
G03X428215Y713448I-3J200D01*
G02X429290Y713901I1075J-1049D01*
G02X430277Y713531I0J-1501D01*
G01X430278D01*
Y713530D01*
G03X430408Y713482I130J152D01*
G01X430672D01*
G03X430802Y713530I0J200D01*
G01X430803Y713531D01*
G02X432777I987J-1131D01*
G01X432778D01*
Y713530D01*
G03X432908Y713482I130J152D01*
G01X433172D01*
G03X433302Y713530I0J200D01*
G01X433303Y713531D01*
G02X435277I987J-1131D01*
G01X435278D01*
Y713530D01*
G03X435408Y713482I130J152D01*
G01X435672D01*
G03X435802Y713530I0J200D01*
G01X435803Y713531D01*
G02X437777I987J-1131D01*
G37*
G36*
G01X503656Y679532D02*
X503963Y679363D01*
G03X504166Y679369I96J175D01*
G02X504966Y679600I800J-1270D01*
G02Y676596I0J-1502D01*
G02X504166Y676827I0J1501D01*
G03X503963Y676833I-107J-169D01*
G01X503656Y676664D01*
G03X503552Y676489I96J-175D01*
G01Y674754D01*
G02X503200Y673905I-1201J1D01*
G01X502406Y673111D01*
G02X501556Y672758I-851J849D01*
G01X493353D01*
G02X492503Y673111I1J1202D01*
G01X489580Y676034D01*
G02X489228Y676883I849J850D01*
G01Y713686D01*
G02X489580Y714535I1201J-1D01*
G01X496459Y721414D01*
G02X497308Y721766I850J-849D01*
G01X500935D01*
G02X501578Y721580I1J-1202D01*
G03X501819Y721601I107J169D01*
G02X502832Y721993I1012J-1110D01*
G02X503845Y721601I1J-1502D01*
G03X504086Y721580I134J148D01*
G02X504729Y721766I642J-1016D01*
G01X517986D01*
G02X518835Y721414I-1J-1201D01*
G01X519781Y720468D01*
G02X520134Y719618I-849J-851D01*
G01Y715067D01*
G02X519781Y714217I-1202J1D01*
G01X504103Y698539D01*
G02X503183Y698190I-849J851D01*
G01X502669Y698220D01*
G02X502588Y698243I13J200D01*
G01X502209Y698442D01*
G02X502146Y698495I95J176D01*
G01X502012Y698663D01*
X502011Y698665D01*
G03X501618Y698856I-393J-309D01*
G03X501428Y698818I1J-501D01*
G01X501208Y698726D01*
G03X501088Y698511I78J-184D01*
G01X501124Y698276D01*
Y698275D01*
G03X501618Y697854I494J79D01*
G01X501619D01*
G03X501752Y697872I0J501D01*
G03X501757Y697874I-71J186D01*
G01X501980Y697942D01*
G02X502075Y697947I58J-192D01*
G01X502545Y697861D01*
G02X502629Y697824I-37J-197D01*
G01X503072Y697490D01*
G02X503552Y696530I-721J-961D01*
G01Y679707D01*
G03X503656Y679532I200J0D01*
G37*
G36*
G01X1009683Y724519D02*
G02X1012687I1502J0D01*
G01Y724518D01*
G02X1012663Y724252I-1502J1D01*
G03X1012703Y724092I197J-36D01*
G01X1012841Y723919D01*
X1012851D01*
X1012866D01*
G03X1013019Y723987I3J200D01*
G01X1013104Y724082D01*
G03X1013152Y724241I-150J132D01*
G02X1013139Y724436I1489J197D01*
G02X1016143I1502J0D01*
G02X1014726Y722936I-1502J0D01*
G01X1014686Y722934D01*
X1014615Y722900D01*
X1014400Y722657D01*
G03X1014350Y722512I150J-133D01*
G02X1014353Y722417I-1499J-95D01*
G02X1012851Y720915I-1502J0D01*
G02X1011548Y721671I0J1501D01*
G01Y721672D01*
X1011547D01*
G03X1011375Y721772I-173J-100D01*
G01X1010975Y721774D01*
X1010883Y721721D01*
X1010856Y721675D01*
G02X1009562Y720936I-1294J763D01*
G02X1008060Y722438I0J1502D01*
G02X1009350Y723925I1502J0D01*
G01X1009388Y723930D01*
X1009456Y723969D01*
X1009650Y724218D01*
G03X1009691Y724363I-158J123D01*
G02X1009683Y724517I1494J155D01*
G01Y724519D01*
G37*
G36*
G01X398770Y795840D02*
X398476D01*
G03X398329Y795775I1J-200D01*
G02X397223Y795290I-1106J1019D01*
G02Y798294I0J1502D01*
G02X398329Y797809I0J-1504D01*
G03X398476Y797744I148J135D01*
G01X398770D01*
G03X398917Y797809I-1J200D01*
G02X400023Y798294I1106J-1019D01*
G02Y795290I0J-1502D01*
G02X398917Y795775I0J1504D01*
G03X398770Y795840I-148J-135D01*
G37*
G36*
G01X427806Y797400D02*
Y794600D01*
G02X427365Y793535I-1506J0D01*
G01X422045Y788214D01*
G03X421987Y788057I141J-141D01*
G01X422010Y787755D01*
G03X422090Y787610I199J15D01*
G01X422091Y787609D01*
G02X422702Y786400I-891J-1209D01*
G02X421200Y784898I-1502J0D01*
G02X419991Y785509I0J1502D01*
G01X419990Y785510D01*
G03X419845Y785590I-160J-119D01*
G01X419543Y785613D01*
G03X419386Y785555I-16J-199D01*
G01X406715Y772885D01*
G02X405650Y772444I-1065J1065D01*
G01X365850D01*
G02Y775456I0J1506D01*
G01X404943D01*
G03X405085Y775515I0J200D01*
G01X423101Y793531D01*
G03X423158Y793703I-141J142D01*
G01X423109Y794022D01*
G03X423004Y794169I-198J-30D01*
G02X422198Y795500I696J1331D01*
G02X423700Y797002I1502J0D01*
G01X423703D01*
G02X424248Y796899I-2J-1502D01*
G01X424294Y796881D01*
X424392Y796892D01*
X424707Y797105D01*
G03X424794Y797271I-113J165D01*
G01Y797400D01*
G02X427806I1506J0D01*
G37*
G36*
G01X414754Y832825D02*
X414755Y832824D01*
G03X414885Y832776I130J152D01*
G01X415149D01*
G03X415279Y832824I0J200D01*
G01X415280Y832825D01*
G02X416267Y833195I987J-1131D01*
G02X417769Y831693I0J-1502D01*
G02X417399Y830706I-1501J0D01*
G01Y830705D01*
X417398D01*
G03X417350Y830575I152J-130D01*
G01Y830311D01*
G03X417398Y830181I200J0D01*
G01X417399Y830180D01*
G02X417769Y829193I-1131J-987D01*
G02X416267Y827691I-1502J0D01*
G02X415280Y828061I0J1501D01*
G01X415279D01*
Y828062D01*
G03X415149Y828110I-130J-152D01*
G01X414885D01*
G03X414755Y828062I0J-200D01*
G01X414754Y828061D01*
G02X412780I-987J1131D01*
G01X412779D01*
Y828062D01*
G03X412649Y828110I-130J-152D01*
G01X412385D01*
G03X412255Y828062I0J-200D01*
G01X412254Y828061D01*
G02X411267Y827691I-987J1131D01*
G02X409765Y829193I0J1502D01*
G02X410135Y830180I1501J0D01*
G01Y830181D01*
X410136D01*
G03X410184Y830311I-152J130D01*
G01Y830575D01*
G03X410136Y830705I-200J0D01*
G01X410135Y830706D01*
G02X409765Y831693I1131J987D01*
G02X411267Y833195I1502J0D01*
G02X412254Y832825I0J-1501D01*
G01X412255D01*
Y832824D01*
G03X412385Y832776I130J152D01*
G01X412649D01*
G03X412779Y832824I0J200D01*
G01X412780Y832825D01*
G02X414754I987J-1131D01*
G37*
G36*
G01X1746557Y899314D02*
X1746243D01*
G03X1746085Y899237I0J-200D01*
G02X1744900Y898658I-1185J923D01*
G02Y901662I0J1502D01*
G02X1746085Y901083I0J-1502D01*
G03X1746243Y901006I158J123D01*
G01X1746557D01*
G03X1746715Y901083I0J200D01*
G02X1747900Y901662I1185J-923D01*
G02Y898658I0J-1502D01*
G02X1746715Y899237I0J1502D01*
G03X1746557Y899314I-158J-123D01*
G37*
G36*
G01X1772943Y929006D02*
Y929320D01*
G03X1772866Y929478I-200J0D01*
G02X1772287Y930663I923J1185D01*
G02X1775291I1502J0D01*
G02X1774712Y929478I-1502J0D01*
G03X1774635Y929320I123J-158D01*
G01Y929006D01*
G03X1774712Y928848I200J0D01*
G02X1775291Y927663I-923J-1185D01*
G02X1772287I-1502J0D01*
G02X1772866Y928848I1502J0D01*
G03X1772943Y929006I-123J158D01*
G37*
G36*
G01X399619Y932186D02*
G02X402623I1502J0D01*
G02X402253Y931199I-1501J0D01*
G01Y931198D01*
X402252D01*
G03X402204Y931068I152J-130D01*
G01Y930804D01*
G03X402252Y930674I200J0D01*
G01X402253Y930673D01*
G02X402623Y929686I-1131J-987D01*
G02X399619I-1502J0D01*
G02X399989Y930673I1501J0D01*
G01Y930674D01*
X399990D01*
G03X400038Y930804I-152J130D01*
G01Y931068D01*
G03X399990Y931198I-200J0D01*
G01X399989Y931199D01*
G02X399619Y932186I1131J987D01*
G37*
G36*
G01X407619D02*
G02X410623I1502J0D01*
G02X410253Y931199I-1501J0D01*
G01Y931198D01*
X410252D01*
G03X410204Y931068I152J-130D01*
G01Y930804D01*
G03X410252Y930674I200J0D01*
G01X410253Y930673D01*
G02X410623Y929686I-1131J-987D01*
G02X407619I-1502J0D01*
G02X407989Y930673I1501J0D01*
G01Y930674D01*
X407990D01*
G03X408038Y930804I-152J130D01*
G01Y931068D01*
G03X407990Y931198I-200J0D01*
G01X407989Y931199D01*
G02X407619Y932186I1131J987D01*
G37*
G36*
G01X415619D02*
G02X418623I1502J0D01*
G02X418253Y931199I-1501J0D01*
G01Y931198D01*
X418252D01*
G03X418204Y931068I152J-130D01*
G01Y930804D01*
G03X418252Y930674I200J0D01*
G01X418253Y930673D01*
G02X418623Y929686I-1131J-987D01*
G02X415619I-1502J0D01*
G02X415989Y930673I1501J0D01*
G01Y930674D01*
X415990D01*
G03X416038Y930804I-152J130D01*
G01Y931068D01*
G03X415990Y931198I-200J0D01*
G01X415989Y931199D01*
G02X415619Y932186I1131J987D01*
G37*
G36*
G01X423619D02*
G02X426623I1502J0D01*
G02X426253Y931199I-1501J0D01*
G01Y931198D01*
X426252D01*
G03X426204Y931068I152J-130D01*
G01Y930804D01*
G03X426252Y930674I200J0D01*
G01X426253Y930673D01*
G02X426623Y929686I-1131J-987D01*
G02X423619I-1502J0D01*
G02X423989Y930673I1501J0D01*
G01Y930674D01*
X423990D01*
G03X424038Y930804I-152J130D01*
G01Y931068D01*
G03X423990Y931198I-200J0D01*
G01X423989Y931199D01*
G02X423619Y932186I1131J987D01*
G37*
G36*
G01X1781411Y957047D02*
X1781705D01*
G03X1781852Y957112I-1J200D01*
G02X1784064I1106J-1017D01*
G03X1784211Y957047I148J135D01*
G01X1784505D01*
G03X1784652Y957112I-1J200D01*
G02X1785758Y957597I1106J-1019D01*
G02X1787260Y956095I0J-1502D01*
G02X1786775Y954989I-1504J0D01*
G03X1786710Y954842I135J-148D01*
G01Y954548D01*
G03X1786775Y954401I200J1D01*
G02X1787260Y953295I-1019J-1106D01*
G02X1785758Y951793I-1502J0D01*
G02X1784652Y952278I0J1504D01*
G03X1784505Y952343I-148J-135D01*
G01X1784211D01*
G03X1784064Y952278I1J-200D01*
G02X1781852I-1106J1017D01*
G03X1781705Y952343I-148J-135D01*
G01X1781411D01*
G03X1781264Y952278I1J-200D01*
G02X1780158Y951793I-1106J1019D01*
G02X1778656Y953295I0J1502D01*
G02X1779141Y954401I1504J0D01*
G03X1779206Y954548I-135J148D01*
G01Y954842D01*
G03X1779141Y954989I-200J-1D01*
G02X1778656Y956095I1019J1106D01*
G02X1780158Y957597I1502J0D01*
G02X1781264Y957112I0J-1504D01*
G03X1781411Y957047I148J135D01*
G37*
G36*
G01X1771598Y860272D02*
G02X1771042Y858930I-1902J2D01*
G01X1747573Y835461D01*
G03X1747514Y835319I141J-142D01*
G01Y512061D01*
G03X1747573Y511919I200J0D01*
G01X1762588Y496904D01*
G02X1763144Y495562I-1346J-1344D01*
G01Y487721D01*
G02X1762588Y486379I-1902J2D01*
G01X1759746Y483537D01*
G02X1758401Y482980I-1345J1345D01*
G02X1756500Y484882I1J1902D01*
G02X1756567Y485386I1901J4D01*
G01X1756579Y485429D01*
X1756565Y485515D01*
X1756344Y485839D01*
X1756269Y485884D01*
X1756226Y485889D01*
G02X1754889Y487382I165J1493D01*
G02X1756391Y488884I1502J0D01*
G02X1757826Y487826I0J-1502D01*
G01X1757841Y487775D01*
X1757917Y487704D01*
X1758301Y487608D01*
G03X1758491Y487661I48J194D01*
G01X1759283Y488453D01*
G03X1759342Y488595I-141J142D01*
G01Y494688D01*
G03X1759283Y494830I-200J0D01*
G01X1744267Y509845D01*
G02X1743710Y511190I1345J1345D01*
G01Y836190D01*
G02X1744267Y837535I1902J0D01*
G01X1767737Y861004D01*
G03X1767796Y861146I-141J142D01*
G01Y910530D01*
G03X1767737Y910672I-200J0D01*
G01X1759423Y918985D01*
G02X1758866Y920330I1345J1345D01*
G01Y927154D01*
G02X1759423Y928499I1902J0D01*
G01X1767737Y936812D01*
G03X1767796Y936954I-141J142D01*
G01Y965405D01*
G02X1768352Y966747I1902J-2D01*
G01X1772110Y970505D01*
G02X1773455Y971062I1345J-1345D01*
G01X1789363D01*
G02Y967258I0J-1902D01*
G01X1774326D01*
G03X1774184Y967199I0J-200D01*
G01X1771657Y964673D01*
G03X1771598Y964531I141J-142D01*
G01Y936080D01*
G02X1771042Y934738I-1902J2D01*
G01X1762729Y926425D01*
G03X1762670Y926283I141J-142D01*
G01Y921201D01*
G03X1762729Y921059I200J0D01*
G01X1771042Y912746D01*
G02X1771598Y911404I-1346J-1344D01*
G01Y860272D01*
G37*
G36*
G01X450591Y1003264D02*
G02Y1006268I0J1502D01*
G02X451996Y1005297I0J-1502D01*
G03X452113Y1005180I187J70D01*
G01X452394Y1005075D01*
G03X452559Y1005086I70J187D01*
G02X453270Y1005265I711J-1323D01*
G02Y1002261I0J-1502D01*
G02X451865Y1003232I0J1502D01*
G03X451748Y1003349I-187J-70D01*
G01X451467Y1003454D01*
G03X451302Y1003443I-70J-187D01*
G02X450591Y1003264I-711J1323D01*
G37*
G36*
G01X473639Y1032454D02*
G02Y1029450I0J-1502D01*
G02X473461Y1029461I3J1502D01*
G01X473460D01*
G03X473321Y1029426I-24J-199D01*
G01X473102Y1029270D01*
G03X473023Y1029151I116J-163D01*
G02X471558Y1027980I-1465J331D01*
G02Y1030984I0J1502D01*
G02X471736Y1030973I-3J-1502D01*
G01X471737D01*
G03X471876Y1031008I24J199D01*
G01X472095Y1031164D01*
G03X472174Y1031283I-116J163D01*
G02X473639Y1032454I1465J-331D01*
G37*
G36*
G01X413534Y1061829D02*
X413535Y1061828D01*
G03X413665Y1061780I130J152D01*
G01X413929D01*
G03X414059Y1061828I0J200D01*
G01X414060Y1061829D01*
G02X415047Y1062199I987J-1131D01*
G02X416549Y1060697I0J-1502D01*
G02X416143Y1059670I-1502J0D01*
G01X416117Y1059643D01*
X416089Y1059572D01*
Y1059222D01*
X416117Y1059151D01*
X416143Y1059124D01*
G02X416549Y1058097I-1096J-1027D01*
G02X415047Y1056595I-1502J0D01*
G02X414060Y1056965I0J1501D01*
G01X414059D01*
Y1056966D01*
G03X413929Y1057014I-130J-152D01*
G01X413665D01*
G03X413535Y1056966I0J-200D01*
G01X413534Y1056965D01*
G02X411560I-987J1131D01*
G01X411559D01*
Y1056966D01*
G03X411429Y1057014I-130J-152D01*
G01X411165D01*
G03X411035Y1056966I0J-200D01*
G01X411034Y1056965D01*
G02X409060I-987J1131D01*
G01X409059D01*
Y1056966D01*
G03X408929Y1057014I-130J-152D01*
G01X408665D01*
G03X408535Y1056966I0J-200D01*
G01X408534Y1056965D01*
G02X406560I-987J1131D01*
G01X406559D01*
Y1056966D01*
G03X406429Y1057014I-130J-152D01*
G01X406165D01*
G03X406035Y1056966I0J-200D01*
G01X406034Y1056965D01*
G02X405047Y1056595I-987J1131D01*
G02X403545Y1058097I0J1502D01*
G02X403951Y1059124I1502J0D01*
G01X403977Y1059151D01*
X404005Y1059222D01*
Y1059572D01*
X403977Y1059643D01*
X403951Y1059670D01*
G02X403545Y1060697I1096J1027D01*
G02X405047Y1062199I1502J0D01*
G02X406034Y1061829I0J-1501D01*
G01X406035D01*
Y1061828D01*
G03X406165Y1061780I130J152D01*
G01X406429D01*
G03X406559Y1061828I0J200D01*
G01X406560Y1061829D01*
G02X408534I987J-1131D01*
G01X408535D01*
Y1061828D01*
G03X408665Y1061780I130J152D01*
G01X408929D01*
G03X409059Y1061828I0J200D01*
G01X409060Y1061829D01*
G02X411034I987J-1131D01*
G01X411035D01*
Y1061828D01*
G03X411165Y1061780I130J152D01*
G01X411429D01*
G03X411559Y1061828I0J200D01*
G01X411560Y1061829D01*
G02X413534I987J-1131D01*
G37*
G36*
G01X501664D02*
X501665Y1061828D01*
G03X501795Y1061780I130J152D01*
G01X502059D01*
G03X502189Y1061828I0J200D01*
G01X502190Y1061829D01*
G02X503177Y1062199I987J-1131D01*
G02X504679Y1060697I0J-1502D01*
G02X504273Y1059670I-1502J0D01*
G01X504247Y1059643D01*
X504219Y1059572D01*
Y1059222D01*
X504247Y1059151D01*
X504273Y1059124D01*
G02X504679Y1058097I-1096J-1027D01*
G02X503177Y1056595I-1502J0D01*
G02X502190Y1056965I0J1501D01*
G01X502189D01*
Y1056966D01*
G03X502059Y1057014I-130J-152D01*
G01X501795D01*
G03X501665Y1056966I0J-200D01*
G01X501664Y1056965D01*
G02X499690I-987J1131D01*
G01X499689D01*
Y1056966D01*
G03X499559Y1057014I-130J-152D01*
G01X499295D01*
G03X499165Y1056966I0J-200D01*
G01X499164Y1056965D01*
G02X497190I-987J1131D01*
G01X497189D01*
Y1056966D01*
G03X497059Y1057014I-130J-152D01*
G01X496795D01*
G03X496665Y1056966I0J-200D01*
G01X496664Y1056965D01*
G02X494690I-987J1131D01*
G01X494689D01*
Y1056966D01*
G03X494559Y1057014I-130J-152D01*
G01X494295D01*
G03X494165Y1056966I0J-200D01*
G01X494164Y1056965D01*
G02X493177Y1056595I-987J1131D01*
G02X491675Y1058097I0J1502D01*
G02X492081Y1059124I1502J0D01*
G01X492107Y1059151D01*
X492135Y1059222D01*
Y1059572D01*
X492107Y1059643D01*
X492081Y1059670D01*
G02X491675Y1060697I1096J1027D01*
G02X493177Y1062199I1502J0D01*
G02X494164Y1061829I0J-1501D01*
G01X494165D01*
Y1061828D01*
G03X494295Y1061780I130J152D01*
G01X494559D01*
G03X494689Y1061828I0J200D01*
G01X494690Y1061829D01*
G02X496664I987J-1131D01*
G01X496665D01*
Y1061828D01*
G03X496795Y1061780I130J152D01*
G01X497059D01*
G03X497189Y1061828I0J200D01*
G01X497190Y1061829D01*
G02X499164I987J-1131D01*
G01X499165D01*
Y1061828D01*
G03X499295Y1061780I130J152D01*
G01X499559D01*
G03X499689Y1061828I0J200D01*
G01X499690Y1061829D01*
G02X501664I987J-1131D01*
G37*
G36*
G01X499990Y1087928D02*
X499991Y1087927D01*
G03X500121Y1087879I130J152D01*
G01X500385D01*
G03X500515Y1087927I0J200D01*
G01X500516Y1087928D01*
G02X501503Y1088298I987J-1131D01*
G02X503005Y1086796I0J-1502D01*
G02X502635Y1085809I-1501J0D01*
G01Y1085808D01*
X502634D01*
G03X502586Y1085678I152J-130D01*
G01Y1085414D01*
G03X502634Y1085284I200J0D01*
G01X502635Y1085283D01*
G02X503005Y1084296I-1131J-987D01*
G02X501503Y1082794I-1502J0D01*
G02X500516Y1083164I0J1501D01*
G01X500515D01*
Y1083165D01*
G03X500385Y1083213I-130J-152D01*
G01X500121D01*
G03X499991Y1083165I0J-200D01*
G01X499990Y1083164D01*
G02X498016I-987J1131D01*
G01X498015D01*
Y1083165D01*
G03X497885Y1083213I-130J-152D01*
G01X497621D01*
G03X497491Y1083165I0J-200D01*
G01X497490Y1083164D01*
G02X495516I-987J1131D01*
G01X495515D01*
Y1083165D01*
G03X495385Y1083213I-130J-152D01*
G01X495121D01*
G03X494991Y1083165I0J-200D01*
G01X494990Y1083164D01*
G02X493016I-987J1131D01*
G01X493015D01*
Y1083165D01*
G03X492885Y1083213I-130J-152D01*
G01X492621D01*
G03X492491Y1083165I0J-200D01*
G01X492490Y1083164D01*
G02X491503Y1082794I-987J1131D01*
G02X490001Y1084296I0J1502D01*
G02X490371Y1085283I1501J0D01*
G01Y1085284D01*
X490372D01*
G03X490420Y1085414I-152J130D01*
G01Y1085678D01*
G03X490372Y1085808I-200J0D01*
G01X490371Y1085809D01*
G02X490001Y1086796I1131J987D01*
G02X491503Y1088298I1502J0D01*
G02X492490Y1087928I0J-1501D01*
G01X492491D01*
Y1087927D01*
G03X492621Y1087879I130J152D01*
G01X492885D01*
G03X493015Y1087927I0J200D01*
G01X493016Y1087928D01*
G02X494990I987J-1131D01*
G01X494991D01*
Y1087927D01*
G03X495121Y1087879I130J152D01*
G01X495385D01*
G03X495515Y1087927I0J200D01*
G01X495516Y1087928D01*
G02X497490I987J-1131D01*
G01X497491D01*
Y1087927D01*
G03X497621Y1087879I130J152D01*
G01X497885D01*
G03X498015Y1087927I0J200D01*
G01X498016Y1087928D01*
G02X499990I987J-1131D01*
G37*
G36*
G01X500879Y1091541D02*
Y1091835D01*
G03X500814Y1091982I-200J-1D01*
G02X500329Y1093088I1019J1106D01*
G02X503333I1502J0D01*
G02X502848Y1091982I-1504J0D01*
G03X502783Y1091835I135J-148D01*
G01Y1091541D01*
G03X502848Y1091394I200J1D01*
G02X503333Y1090288I-1019J-1106D01*
G02X500329I-1502J0D01*
G02X500814Y1091394I1504J0D01*
G03X500879Y1091541I-135J148D01*
G37*
G36*
G01X412080Y1112146D02*
G02Y1115150I0J1502D01*
G02X413067Y1114780I0J-1501D01*
G01X413068D01*
Y1114779D01*
G03X413198Y1114731I130J152D01*
G01X413462D01*
G03X413592Y1114779I0J200D01*
G01X413593Y1114780D01*
G02X414580Y1115150I987J-1131D01*
G02Y1112146I0J-1502D01*
G02X413593Y1112516I0J1501D01*
G01X413592D01*
Y1112517D01*
G03X413462Y1112565I-130J-152D01*
G01X413198D01*
G03X413068Y1112517I0J-200D01*
G01X413067Y1112516D01*
G02X412080Y1112146I-987J1131D01*
G37*
G36*
G01X509795D02*
G02Y1115150I0J1502D01*
G02X510782Y1114780I0J-1501D01*
G01X510783D01*
Y1114779D01*
G03X510913Y1114731I130J152D01*
G01X511177D01*
G03X511307Y1114779I0J200D01*
G01X511308Y1114780D01*
G02X512295Y1115150I987J-1131D01*
G02Y1112146I0J-1502D01*
G02X511308Y1112516I0J1501D01*
G01X511307D01*
Y1112517D01*
G03X511177Y1112565I-130J-152D01*
G01X510913D01*
G03X510783Y1112517I0J-200D01*
G01X510782Y1112516D01*
G02X509795Y1112146I-987J1131D01*
G37*
G36*
G01X502510Y1107895D02*
G02X502304Y1107909I-1J1502D01*
G01X502268Y1107914D01*
X502197Y1107898D01*
X501914Y1107710D01*
X501872Y1107650D01*
X501863Y1107615D01*
G02X500410Y1106495I-1453J383D01*
G02X498908Y1107997I0J1502D01*
G02X499438Y1109142I1502J0D01*
G03X499509Y1109294I-129J153D01*
G01Y1109600D01*
G03X499438Y1109752I-200J-1D01*
G02X498908Y1110897I972J1145D01*
G02X499438Y1112042I1502J0D01*
G03X499509Y1112194I-129J153D01*
G01Y1112500D01*
G03X499438Y1112652I-200J-1D01*
G02X498908Y1113797I972J1145D01*
G02X500410Y1115299I1502J0D01*
G02X501866Y1114167I0J-1502D01*
G01X501875Y1114130D01*
X501920Y1114068D01*
X502215Y1113879D01*
X502290Y1113865D01*
X502328Y1113872D01*
G02X502610Y1113899I284J-1475D01*
G02X503413Y1113666I0J-1502D01*
G01X503455Y1113639D01*
X503552Y1113632D01*
X503950Y1113804D01*
X504010Y1113880D01*
X504020Y1113929D01*
G02X505212Y1115123I1475J-281D01*
G01X505255Y1115131D01*
X505323Y1115180D01*
X505521Y1115513D01*
X505530Y1115598D01*
X505517Y1115639D01*
G02X505444Y1116101I1429J463D01*
G02X505888Y1117167I1502J0D01*
G03X505947Y1117309I-141J142D01*
G01Y1117593D01*
G03X505888Y1117735I-200J0D01*
G02X505444Y1118801I1058J1066D01*
G02X508448I1502J0D01*
G02X508004Y1117735I-1502J0D01*
G03X507945Y1117593I141J-142D01*
G01Y1117309D01*
G03X508004Y1117167I200J0D01*
G02X508448Y1116101I-1058J-1066D01*
G02X507229Y1114626I-1502J0D01*
G01X507186Y1114618D01*
X507118Y1114569D01*
X506920Y1114236D01*
X506911Y1114151D01*
X506924Y1114110D01*
G02X506997Y1113648I-1429J-463D01*
G02X506000Y1112234I-1501J0D01*
G03X505874Y1112095I68J-188D01*
G01X505779Y1111725D01*
X505802Y1111629D01*
X505835Y1111592D01*
G02X506212Y1110597I-1125J-995D01*
G02X505765Y1109528I-1502J0D01*
G01X505738Y1109502D01*
X505707Y1109432D01*
X505694Y1109081D01*
X505719Y1109011D01*
X505744Y1108982D01*
G02X506112Y1107997I-1134J-985D01*
G02X504610Y1106495I-1502J0D01*
G02X503157Y1107615I0J1503D01*
G01X503148Y1107650D01*
X503106Y1107710D01*
X502823Y1107898D01*
X502752Y1107914D01*
X502716Y1107909D01*
G02X502510Y1107895I-205J1488D01*
G37*
G36*
G01X404795D02*
G02X404589Y1107909I-1J1502D01*
G01X404553Y1107914D01*
X404482Y1107898D01*
X404199Y1107710D01*
X404157Y1107650D01*
X404148Y1107615D01*
G02X402695Y1106495I-1453J383D01*
G02X401193Y1107997I0J1502D01*
G02X401723Y1109142I1502J0D01*
G03X401794Y1109294I-129J153D01*
G01Y1109600D01*
G03X401723Y1109752I-200J-1D01*
G02X401193Y1110897I972J1145D01*
G02X401723Y1112042I1502J0D01*
G03X401794Y1112194I-129J153D01*
G01Y1112500D01*
G03X401723Y1112652I-200J-1D01*
G02X401193Y1113797I972J1145D01*
G02X402695Y1115299I1502J0D01*
G02X404151Y1114167I0J-1502D01*
G01X404160Y1114130D01*
X404205Y1114068D01*
X404500Y1113879D01*
X404575Y1113865D01*
X404613Y1113872D01*
G02X404895Y1113899I284J-1475D01*
G02X405698Y1113666I0J-1502D01*
G01X405740Y1113639D01*
X405837Y1113632D01*
X406235Y1113804D01*
X406295Y1113880D01*
X406305Y1113929D01*
G02X407780Y1115150I1475J-280D01*
G02X409282Y1113648I0J-1502D01*
G02X408285Y1112234I-1501J0D01*
G03X408159Y1112095I68J-188D01*
G01X408064Y1111725D01*
X408087Y1111629D01*
X408120Y1111592D01*
G02X408497Y1110597I-1125J-995D01*
G02X408050Y1109528I-1502J0D01*
G01X408023Y1109502D01*
X407992Y1109432D01*
X407979Y1109081D01*
X408004Y1109011D01*
X408029Y1108982D01*
G02X408397Y1107997I-1134J-985D01*
G02X406895Y1106495I-1502J0D01*
G02X405442Y1107615I0J1503D01*
G01X405433Y1107650D01*
X405391Y1107710D01*
X405108Y1107898D01*
X405037Y1107914D01*
X405001Y1107909D01*
G02X404795Y1107895I-205J1488D01*
G37*
G36*
G01X517086Y1099255D02*
Y1097813D01*
G02X516647Y1096753I-1501J1D01*
G01X514672Y1094778D01*
G02X513610Y1094338I-1062J1062D01*
G01X510954D01*
G02X509892Y1094778I0J1502D01*
G01X505690Y1098981D01*
G03X505548Y1099040I-142J-141D01*
G01X498100D01*
G03X497958Y1098981I0J-200D01*
G01X493756Y1094778D01*
G02X492694Y1094338I-1062J1062D01*
G01X489553D01*
G02X488491Y1094778I0J1502D01*
G01X487280Y1095989D01*
G02X486840Y1097051I1062J1062D01*
G01Y1100436D01*
G03X486782Y1100578I-200J1D01*
G01X486510Y1100849D01*
G03X486227I-142J-141D01*
G01X485352Y1099973D01*
G02X484292Y1099534I-1061J1062D01*
G01X469570D01*
G03X469428Y1099475I0J-200D01*
G01X465945Y1095992D01*
G03X465886Y1095850I141J-142D01*
G01Y1038534D01*
G02X462884I-1501J0D01*
G01Y1096557D01*
G02X463323Y1097617I1501J-1D01*
G01X467803Y1102097D01*
G02X468863Y1102536I1061J-1062D01*
G01X483585D01*
G03X483727Y1102595I0J200D01*
G01X484809Y1103677D01*
G03X484868Y1103819I-141J142D01*
G01Y1105005D01*
G03X484794Y1105160I-200J0D01*
G01X484553Y1105356D01*
G03X484388Y1105396I-125J-156D01*
G01X484384D01*
G03X484264Y1105318I42J-196D01*
G01X484083Y1105068D01*
X484064Y1104996D01*
X484068Y1104959D01*
G02X484077Y1104792I-1493J-164D01*
G02X481073I-1502J0D01*
G02X482272Y1106263I1502J0D01*
G01X482273D01*
G03X482393Y1106341I-42J196D01*
G01X482574Y1106591D01*
X482593Y1106663D01*
X482589Y1106700D01*
G02X482580Y1106867I1493J164D01*
G02X484082Y1108369I1502J0D01*
G02X485525Y1107285I0J-1502D01*
G01X485535Y1107248D01*
X485583Y1107187D01*
X485891Y1107010D01*
X485968Y1106999D01*
X486005Y1107009D01*
G02X486369Y1107054I365J-1457D01*
G02X487809Y1105977I0J-1501D01*
G01X487821Y1105935D01*
X487876Y1105871D01*
X488223Y1105706D01*
X488308Y1105704D01*
X488347Y1105721D01*
G02X488827Y1105834I580J-1386D01*
G01X488874Y1105837D01*
X488956Y1105885D01*
X489182Y1106234D01*
X489192Y1106327D01*
X489175Y1106372D01*
G02X489080Y1106897I1407J526D01*
G02X492084I1502J0D01*
G02X490682Y1105398I-1502J0D01*
G01X490635Y1105395D01*
X490553Y1105347D01*
X490327Y1104998D01*
X490317Y1104905D01*
X490334Y1104860D01*
G02X490429Y1104335I-1407J-526D01*
G02X490372Y1103925I-1503J0D01*
G01X490360Y1103881D01*
X490375Y1103792D01*
X490583Y1103500D01*
G03X490733Y1103416I163J115D01*
G01X490734D01*
G02X492149Y1101917I-86J-1499D01*
G02X490647Y1100415I-1502J0D01*
G01X490645D01*
G02X490328Y1100449I1J1502D01*
G01X490284Y1100458D01*
X490196Y1100438D01*
X489919Y1100214D01*
G03X489844Y1100058I125J-156D01*
G01Y1097756D01*
G03X489903Y1097614I200J0D01*
G01X490116Y1097401D01*
G03X490258Y1097342I142J141D01*
G01X491989D01*
G03X492131Y1097401I0J200D01*
G01X496333Y1101603D01*
G02X497393Y1102042I1061J-1062D01*
G01X506255D01*
G02X507315Y1101603I-1J-1501D01*
G01X511517Y1097401D01*
G03X511659Y1097342I142J141D01*
G01X512905D01*
G03X513047Y1097401I0J200D01*
G01X514025Y1098378D01*
G03X514084Y1098520I-141J142D01*
G01Y1099962D01*
G02X514523Y1101022I1501J-1D01*
G01X516937Y1103435D01*
G03X516996Y1103577I-141J142D01*
G01Y1105005D01*
G03X516922Y1105160I-200J0D01*
G01X516681Y1105356D01*
G03X516516Y1105396I-125J-156D01*
G01X516512D01*
G03X516392Y1105318I42J-196D01*
G01X516211Y1105068D01*
X516192Y1104996D01*
X516196Y1104959D01*
G02X516205Y1104792I-1493J-164D01*
G02X513201I-1502J0D01*
G02X514400Y1106263I1502J0D01*
G01X514401D01*
G03X514521Y1106341I-42J196D01*
G01X514702Y1106591D01*
X514721Y1106663D01*
X514717Y1106700D01*
G02X514708Y1106867I1493J164D01*
G02X516210Y1108369I1502J0D01*
G02X517653Y1107285I0J-1502D01*
G01X517663Y1107248D01*
X517711Y1107187D01*
X518019Y1107010D01*
X518096Y1106999D01*
X518133Y1107009D01*
G02X518497Y1107054I365J-1457D01*
G02X519937Y1105977I0J-1501D01*
G01X519949Y1105935D01*
X520004Y1105871D01*
X520351Y1105706D01*
X520436Y1105704D01*
X520475Y1105721D01*
G02X520955Y1105834I580J-1386D01*
G01X521002Y1105837D01*
X521084Y1105885D01*
X521310Y1106234D01*
X521320Y1106327D01*
X521303Y1106372D01*
G02X521208Y1106897I1407J526D01*
G02X524212I1502J0D01*
G02X522810Y1105398I-1502J0D01*
G01X522763Y1105395D01*
X522681Y1105347D01*
X522455Y1104998D01*
X522445Y1104905D01*
X522462Y1104860D01*
G02X522557Y1104335I-1407J-526D01*
G02X522500Y1103925I-1503J0D01*
G01X522488Y1103881D01*
X522503Y1103792D01*
X522711Y1103500D01*
G03X522861Y1103416I163J115D01*
G01X522862D01*
G02X524277Y1101917I-86J-1499D01*
G02X521273I-1502J0D01*
G02X521330Y1102327I1503J0D01*
G01X521342Y1102371D01*
X521327Y1102460D01*
X521119Y1102752D01*
G03X520969Y1102836I-163J-115D01*
G01X520968D01*
G02X520516Y1102933I85J1499D01*
G01X520474Y1102949D01*
X520385Y1102943D01*
X520076Y1102766D01*
G03X519978Y1102626I99J-174D01*
G01Y1102625D01*
G02X519559Y1101810I-1481J246D01*
G01X517145Y1099397D01*
G03X517086Y1099255I141J-142D01*
G37*
G36*
G01X407345Y1093956D02*
G02X410349I1502J0D01*
G02X409770Y1092771I-1502J0D01*
G03X409693Y1092613I123J-158D01*
G01Y1092299D01*
G03X409770Y1092141I200J0D01*
G02X410349Y1090956I-923J-1185D01*
G02X409689Y1089712I-1502J0D01*
G01X409646Y1089683D01*
X409599Y1089589D01*
X409622Y1089142D01*
X409678Y1089054D01*
X409725Y1089029D01*
G02X410051Y1088792I-712J-1322D01*
G01X410052Y1088791D01*
G03X410222Y1088739I137J146D01*
G01X410585Y1088800D01*
X410660Y1088855D01*
X410682Y1088897D01*
G02X411225Y1089482I1333J-692D01*
G01X411226Y1089483D01*
G03X411319Y1089634I-106J169D01*
G01X411353Y1089999D01*
X411319Y1090086D01*
X411284Y1090118D01*
G02X410795Y1091227I1013J1109D01*
G02X413799I1502J0D01*
G02X413087Y1089950I-1501J0D01*
G01X413086Y1089949D01*
G03X412993Y1089798I106J-169D01*
G01X412959Y1089433D01*
X412993Y1089346D01*
X413028Y1089314D01*
G02X413200Y1089128I-1013J-1109D01*
G03X413358Y1089051I158J123D01*
G01X413672D01*
G03X413830Y1089128I0J200D01*
G02X415015Y1089707I1185J-923D01*
G02X416517Y1088205I0J-1502D01*
G02X415938Y1087020I-1502J0D01*
G03X415861Y1086862I123J-158D01*
G01Y1086548D01*
G03X415938Y1086390I200J0D01*
G02X416517Y1085205I-923J-1185D01*
G02X416061Y1084127I-1502J0D01*
G01X416032Y1084099D01*
X416001Y1084026D01*
X415997Y1083661D01*
X416027Y1083588D01*
X416056Y1083559D01*
G02X416491Y1082502I-1067J-1057D01*
G01Y1082501D01*
G02X414989Y1080999I-1502J0D01*
G02X413804Y1081578I0J1502D01*
G03X413646Y1081655I-158J-123D01*
G01X413332D01*
G03X413174Y1081578I0J-200D01*
G02X410804I-1185J923D01*
G03X410646Y1081655I-158J-123D01*
G01X410332D01*
G03X410174Y1081578I0J-200D01*
G02X408989Y1080999I-1185J923D01*
G02X407487Y1082501I0J1502D01*
G02X407943Y1083579I1502J0D01*
G01X407972Y1083607D01*
X408003Y1083680D01*
X408007Y1084045D01*
X407977Y1084118D01*
X407948Y1084147D01*
G02X407513Y1085204I1067J1057D01*
G01Y1085205D01*
G02X407883Y1086192I1501J0D01*
G01Y1086193D01*
X407884D01*
G03X407932Y1086323I-152J130D01*
G01Y1086587D01*
G03X407884Y1086717I-200J0D01*
G01X407883Y1086718D01*
G02X407513Y1087705I1131J987D01*
G02X408173Y1088949I1502J0D01*
G01X408216Y1088978D01*
X408263Y1089072D01*
X408240Y1089519D01*
X408184Y1089607D01*
X408137Y1089632D01*
G02X407345Y1090956I711J1324D01*
G02X407924Y1092141I1502J0D01*
G03X408001Y1092299I-123J158D01*
G01Y1092613D01*
G03X407924Y1092771I-200J0D01*
G02X407345Y1093956I923J1185D01*
G37*
G36*
G01X436244Y1094590D02*
G02X437746Y1093088I0J-1502D01*
G02X437261Y1091982I-1504J0D01*
G03X437196Y1091835I135J-148D01*
G01Y1091541D01*
G03X437261Y1091394I200J1D01*
G02X437746Y1090288I-1019J-1106D01*
G02X436244Y1088786I-1502J0D01*
G02X435405Y1089042I0J1503D01*
G01X435404Y1089043D01*
G03X435228Y1089066I-111J-166D01*
G01X434882Y1088949D01*
X434817Y1088883D01*
X434802Y1088838D01*
G02X434510Y1088330I-1423J480D01*
G01Y1088328D01*
X434509D01*
G03X434461Y1088198I152J-130D01*
G01Y1087934D01*
G03X434509Y1087804I200J0D01*
G01X434510Y1087803D01*
G02Y1085829I-1131J-987D01*
G01Y1085828D01*
X434509D01*
G03X434461Y1085698I152J-130D01*
G01Y1085434D01*
G03X434509Y1085304I200J0D01*
G01X434510Y1085303D01*
G02Y1083329I-1131J-987D01*
G01Y1083328D01*
X434509D01*
G03X434461Y1083198I152J-130D01*
G01Y1082934D01*
G03X434509Y1082804I200J0D01*
G01X434510Y1082803D01*
G02X434880Y1081816I-1131J-987D01*
G02X433378Y1080314I-1502J0D01*
G02X432391Y1080684I0J1501D01*
G01X432390D01*
Y1080685D01*
G03X432260Y1080733I-130J-152D01*
G01X431996D01*
G03X431866Y1080685I0J-200D01*
G01X431865Y1080684D01*
G02X430878Y1080314I-987J1131D01*
G02X429376Y1081816I0J1502D01*
G02X429746Y1082803I1501J0D01*
G01Y1082804D01*
X429747D01*
G03X429795Y1082934I-152J130D01*
G01Y1083198D01*
G03X429747Y1083328I-200J0D01*
G01X429746Y1083329D01*
G02Y1085303I1131J987D01*
G01Y1085304D01*
X429747D01*
G03X429795Y1085434I-152J130D01*
G01Y1085698D01*
G03X429747Y1085828I-200J0D01*
G01X429746Y1085829D01*
G02X429376Y1086816I1131J987D01*
G02X430878Y1088318I1502J0D01*
G02X431926Y1087892I0J-1502D01*
G03X432065Y1087835I140J143D01*
G01X432191D01*
G03X432330Y1087892I-1J200D01*
G02X432359Y1087919I1038J-1086D01*
G01Y1088129D01*
G03X432302Y1088268I-200J-1D01*
G02X431876Y1089316I1076J1048D01*
G02X432246Y1090303I1501J0D01*
G01Y1090304D01*
X432247D01*
G03X432295Y1090434I-152J130D01*
G01Y1090698D01*
G03X432247Y1090828I-200J0D01*
G01X432246Y1090829D01*
G02X431876Y1091816I1131J987D01*
G02X433378Y1093318I1502J0D01*
G01X433380D01*
G02X434165Y1093096I-1J-1502D01*
G01X434207Y1093070D01*
X434305Y1093063D01*
X434698Y1093238D01*
X434758Y1093314D01*
X434767Y1093363D01*
G02X436244Y1094590I1477J-275D01*
G37*
G36*
G01X472775Y1093048D02*
G02X475779I1502J0D01*
G02X475287Y1091936I-1503J0D01*
G01X475255Y1091907D01*
X475220Y1091827D01*
X475230Y1091437D01*
X475268Y1091359D01*
X475302Y1091331D01*
G02X475689Y1090848I-954J-1161D01*
G01X475713Y1090801D01*
X475800Y1090743D01*
X476196Y1090715D01*
G03X476374Y1090800I14J199D01*
G02X477607Y1091444I1233J-858D01*
G02X479109Y1089942I0J-1502D01*
G02X478655Y1088866I-1502J0D01*
G01X478615Y1088827D01*
X478587Y1088722D01*
X478698Y1088330D01*
G03X478845Y1088189I193J54D01*
G01X478846D01*
G02X480019Y1086724I-328J-1465D01*
G02X479649Y1085737I-1501J0D01*
G01Y1085736D01*
X479648D01*
G03X479600Y1085606I152J-130D01*
G01Y1085342D01*
G03X479648Y1085212I200J0D01*
G01X479649Y1085211D01*
G02Y1083237I-1131J-987D01*
G01Y1083236D01*
X479648D01*
G03X479600Y1083106I152J-130D01*
G01Y1082842D01*
G03X479648Y1082712I200J0D01*
G01X479649Y1082711D01*
G02X480019Y1081724I-1131J-987D01*
G02X478517Y1080222I-1502J0D01*
G02X477530Y1080592I0J1501D01*
G01X477529D01*
Y1080593D01*
G03X477399Y1080641I-130J-152D01*
G01X477135D01*
G03X477005Y1080593I0J-200D01*
G01X477004Y1080592D01*
G02X476017Y1080222I-987J1131D01*
G02X474515Y1081724I0J1502D01*
G02X474885Y1082711I1501J0D01*
G01Y1082712D01*
X474886D01*
G03X474934Y1082842I-152J130D01*
G01Y1083106D01*
G03X474886Y1083236I-200J0D01*
G01X474885Y1083237D01*
G02Y1085211I1131J987D01*
G01Y1085212D01*
X474886D01*
G03X474934Y1085342I-152J130D01*
G01Y1085606D01*
G03X474886Y1085736I-200J0D01*
G01X474885Y1085737D01*
G02X474515Y1086724I1131J987D01*
G02X476017Y1088226I1502J0D01*
G02X477004Y1087856I0J-1501D01*
G01X477005D01*
Y1087855D01*
G03X477135Y1087807I130J152D01*
G01X477399D01*
G03X477529Y1087855I0J200D01*
G01X477530Y1087856D01*
G02X477846Y1088068I988J-1131D01*
G03X477739Y1088446I-90J179D01*
G02X477607Y1088440I-134J1496D01*
G02X476266Y1089265I0J1502D01*
G01X476242Y1089312D01*
X476155Y1089370D01*
X475759Y1089398D01*
G03X475581Y1089313I-14J-199D01*
G02X474348Y1088669I-1233J858D01*
G02X472846Y1090171I0J1502D01*
G02X473338Y1091283I1503J0D01*
G01X473370Y1091312D01*
X473405Y1091392D01*
X473395Y1091782D01*
X473357Y1091860D01*
X473323Y1091888D01*
G02X472775Y1093048I954J1160D01*
G37*
G36*
G01X458383Y1018860D02*
G02X461387I1502J0D01*
G02X461380Y1018721I-1502J6D01*
G01Y1018719D01*
X461376Y1018672D01*
X461411Y1018584D01*
X461690Y1018338D01*
G03X461863Y1018292I132J150D01*
G01X461864D01*
G02X462185Y1018327I322J-1467D01*
G02Y1015323I0J-1502D01*
G01X462184D01*
G02X461710Y1015400I1J1502D01*
G01X461675Y1015412D01*
X461602Y1015409D01*
X461289Y1015274D01*
X461237Y1015224D01*
X461221Y1015190D01*
G02X459860Y1014323I-1361J635D01*
G02X458358Y1015825I0J1502D01*
G02X458964Y1017031I1503J0D01*
G01X459002Y1017059D01*
X459045Y1017142D01*
X459048Y1017509D01*
G03X458970Y1017669I-200J2D01*
G02X458383Y1018860I915J1191D01*
G37*
G36*
G01X1782563Y981162D02*
G02X1783787Y980530I0J-1501D01*
G03X1783950Y980446I163J116D01*
G01X1784276D01*
G03X1784439Y980530I0J200D01*
G02X1785663Y981162I1224J-869D01*
G02Y978158I0J-1502D01*
G02X1784439Y978790I0J1501D01*
G03X1784276Y978874I-163J-116D01*
G01X1783950D01*
G03X1783787Y978790I0J-200D01*
G02X1782563Y978158I-1224J869D01*
G02X1781300Y978848I0J1501D01*
G03X1781131Y978940I-168J-108D01*
G01X1780795D01*
G03X1780626Y978848I-1J-200D01*
G02X1779363Y978158I-1263J811D01*
G02Y981162I0J1502D01*
G02X1780626Y980472I0J-1501D01*
G03X1780795Y980380I168J108D01*
G01X1781131D01*
G03X1781300Y980472I1J200D01*
G02X1782563Y981162I1263J-811D01*
G37*
G36*
G01X378016Y955779D02*
G02X377743Y956642I1229J864D01*
G01Y956643D01*
G02X380747I1502J0D01*
G02X379584Y955180I-1502J0D01*
G03X379348Y954560I91J-389D01*
G02X379621Y953697I-1229J-864D01*
G01Y953696D01*
G02X376617I-1502J0D01*
G02X377780Y955159I1502J0D01*
G03X378016Y955779I-91J389D01*
G37*
G36*
G01X120935Y860775D02*
G02X123939I1502J0D01*
G02X123225Y859496I-1503J0D01*
G01X123180Y859469D01*
X123130Y859379D01*
X123129Y858986D01*
G03X123224Y858816I200J0D01*
G02X123727Y858300I-792J-1276D01*
G01Y858299D01*
G03X123898Y858201I172J102D01*
G01X124242Y858199D01*
G03X124414Y858295I1J200D01*
G02X125698Y859017I1284J-781D01*
G02Y856013I0J-1502D01*
G02X124403Y856755I0J1501D01*
G01Y856756D01*
G03X124232Y856854I-172J-102D01*
G01X123888Y856856D01*
G03X123716Y856760I-1J-200D01*
G02X122432Y856038I-1284J781D01*
G02X120930Y857540I0J1502D01*
G02X121644Y858819I1503J0D01*
G01X121689Y858846D01*
X121739Y858936D01*
X121740Y859329D01*
G03X121645Y859499I-200J0D01*
G02X120935Y860775I792J1276D01*
G37*
G36*
G01X49249Y839220D02*
G02X50473Y838588I0J-1501D01*
G03X50636Y838504I163J116D01*
G01X50962D01*
G03X51125Y838588I0J200D01*
G02X52349Y839220I1224J-869D01*
G02Y836216I0J-1502D01*
G02X51125Y836848I0J1501D01*
G03X50962Y836932I-163J-116D01*
G01X50636D01*
G03X50473Y836848I0J-200D01*
G02X49249Y836216I-1224J869D01*
G02X47986Y836906I0J1501D01*
G03X47817Y836998I-168J-108D01*
G01X47481D01*
G03X47312Y836906I-1J-200D01*
G02X46049Y836216I-1263J811D01*
G02Y839220I0J1502D01*
G02X47312Y838530I0J-1501D01*
G03X47481Y838438I168J108D01*
G01X47817D01*
G03X47986Y838530I1J200D01*
G02X49249Y839220I1263J-811D01*
G37*
G36*
G01X381631Y812645D02*
G02Y815649I0J1502D01*
G02X382843Y815035I0J-1503D01*
G01X382870Y814997D01*
X382953Y814954D01*
X383368Y814948D01*
X383452Y814988D01*
X383481Y815026D01*
G02X384666Y815605I1185J-923D01*
G02X386055Y814674I0J-1502D01*
G01Y814673D01*
G03X386215Y814552I184J78D01*
G01X386563Y814509D01*
G03X386747Y814588I24J199D01*
G01X386748Y814589D01*
G02X387958Y815202I1210J-888D01*
G02Y812198I0J-1502D01*
G02X386569Y813129I0J1502D01*
G01Y813130D01*
G03X386409Y813251I-184J-78D01*
G01X386061Y813294D01*
G03X385877Y813215I-24J-199D01*
G01X385876Y813214D01*
G02X384666Y812601I-1210J888D01*
G02X383454Y813215I0J1503D01*
G01X383427Y813253D01*
X383344Y813296D01*
X382929Y813302D01*
X382845Y813262D01*
X382816Y813224D01*
G02X381631Y812645I-1185J923D01*
G37*
G36*
G01X374753Y768252D02*
X375047D01*
G03X375194Y768317I-1J200D01*
G02X376300Y768802I1106J-1019D01*
G02Y765798I0J-1502D01*
G02X375194Y766283I0J1504D01*
G03X375047Y766348I-148J-135D01*
G01X374753D01*
G03X374606Y766283I1J-200D01*
G02X373500Y765798I-1106J1019D01*
G01X373499D01*
G02X372549Y766137I1J1502D01*
G01X372507Y766172D01*
X372401Y766189D01*
X372027Y766044D01*
G03X371901Y765887I72J-187D01*
G01Y765886D01*
G02X370415Y764606I-1486J223D01*
G02Y767610I0J1502D01*
G01X370416D01*
G02X371366Y767271I-1J-1502D01*
G01X371408Y767236D01*
X371514Y767219D01*
X371888Y767364D01*
G03X372014Y767521I-72J187D01*
G01Y767522D01*
G02X373500Y768802I1486J-223D01*
G02X374606Y768317I0J-1504D01*
G03X374753Y768252I148J135D01*
G37*
G36*
G01X513559Y754303D02*
G02X513504Y754302I-55J1501D01*
G02X515006Y755804I0J1502D01*
G01Y755801D01*
G02X514964Y755450I-1502J2D01*
G03X515367Y754956I389J-94D01*
G02X515422Y754957I55J-1501D01*
G02X513920Y753455I0J-1502D01*
G01Y753458D01*
G02X513962Y753809I1502J-2D01*
G03X513559Y754303I-389J94D01*
G37*
G36*
G01X560604Y733386D02*
G02X562001Y734336I1397J-552D01*
G02Y731332I0J-1502D01*
G02X560725Y732042I0J1502D01*
G03X560013Y731978I-340J-211D01*
G02X558616Y731028I-1397J552D01*
G02Y734032I0J1502D01*
G02X559892Y733322I0J-1502D01*
G03X560604Y733386I340J211D01*
G37*
G36*
G01X557268Y716809D02*
Y720211D01*
G02X559070Y722012I1802J-1D01*
G02X560235Y721584I-1J-1803D01*
G03X560237Y721582I142J140D01*
G03X560435Y721548I128J154D01*
G01X560814Y721689D01*
X560882Y721772D01*
X560890Y721826D01*
G02X562374Y723095I1484J-233D01*
G02Y720091I0J-1502D01*
G02X561203Y720652I0J1503D01*
G03X560850Y720495I-156J-125D01*
G02X560872Y720209I-1780J-281D01*
G01Y716809D01*
G02X557268I-1802J0D01*
G37*
G36*
G01X514017Y695757D02*
G02X516951I1467J0D01*
G02X516193Y694473I-1467J0D01*
G01X516144Y694446D01*
X516089Y694351D01*
X516098Y693884D01*
X516156Y693791D01*
X516206Y693766D01*
G02X516677Y693379I-633J-1251D01*
G01X516678Y693378D01*
G03X516826Y693302I157J124D01*
G01X517171Y693285D01*
X517252Y693318D01*
X517282Y693350D01*
G02X518299Y693786I1016J-966D01*
G02X519272Y693394I1J-1402D01*
G01X519301Y693366D01*
X519371Y693338D01*
X519727D01*
X519797Y693366D01*
X519826Y693394D01*
G02X520798Y693786I972J-1010D01*
G01X520799D01*
G02Y690982I0J-1402D01*
G01X520798D01*
G02X519826Y691374I0J1402D01*
G01X519797Y691402D01*
X519727Y691430D01*
X519371D01*
X519301Y691402D01*
X519272Y691374D01*
G02X518300Y690982I-972J1010D01*
G01X518299D01*
G02X517195Y691520I0J1402D01*
G01X517194Y691521D01*
G03X517046Y691597I-157J-124D01*
G01X516701Y691614D01*
X516620Y691581D01*
X516590Y691549D01*
G02X515575Y691113I-1016J966D01*
G01X515573D01*
G02X514171Y692515I0J1402D01*
G02X514872Y693729I1402J0D01*
G01X514873Y693730D01*
G03X514973Y693910I-100J173D01*
G01X514957Y694319D01*
X514896Y694412D01*
X514846Y694436D01*
G02X514017Y695757I638J1321D01*
G37*
G36*
G01X92897Y656857D02*
G02Y659861I0J1502D01*
G02X94085Y659278I0J-1502D01*
G01X94113Y659241D01*
X94197Y659200D01*
X94562Y659202D01*
G03X94720Y659280I-1J200D01*
G01Y659281D01*
G02X95917Y659876I1197J-907D01*
G02X97419Y658374I0J-1502D01*
G02X96991Y657324I-1502J0D01*
G01X96962Y657295D01*
X96933Y657221D01*
X96940Y656894D01*
G03X97002Y656754I200J5D01*
G01X97003Y656753D01*
G02X97475Y655660I-1030J-1093D01*
G02X94471I-1502J0D01*
G02X94899Y656710I1502J0D01*
G01X94928Y656739D01*
X94957Y656813D01*
X94950Y657140D01*
G03X94888Y657280I-200J-5D01*
G01X94887Y657281D01*
G02X94729Y657455I1030J1094D01*
G01X94701Y657492D01*
X94617Y657533D01*
X94252Y657531D01*
G03X94094Y657453I1J-200D01*
G01Y657452D01*
G02X92897Y656857I-1197J907D01*
G37*
G36*
G01X500766Y656992D02*
G02X499528Y656341I-1238J852D01*
G02Y659345I0J1502D01*
G02X500839Y658576I0J-1502D01*
G03X501517Y658545I349J196D01*
G02X502755Y659196I1238J-852D01*
G02Y656192I0J-1502D01*
G02X501444Y656961I0J1502D01*
G03X500766Y656992I-349J-196D01*
G37*
G36*
G01X1574880Y648198D02*
G02X1577186Y645891I-1J-2307D01*
G01Y635242D01*
G02X1576511Y633612I-2306J0D01*
G01X1576351Y633452D01*
G03Y633169I141J-142D01*
G01Y633168D01*
G03X1576560Y633122I141J142D01*
G01X1576561D01*
G02X1577077Y633214I518J-1410D01*
G02Y630210I0J-1502D01*
G02X1575575Y631711I0J1502D01*
G01Y631772D01*
X1575508Y631872D01*
X1575111Y632037D01*
G03X1574892Y631993I-77J-185D01*
G01X1574121Y631222D01*
G03X1574062Y631080I141J-142D01*
G01Y620284D01*
G03X1574131Y620133I200J0D01*
G01X1574358Y619935D01*
G03X1574516Y619888I131J151D01*
G02X1574720Y619902I205J-1488D01*
G02Y616898I0J-1502D01*
G02X1574516Y616912I1J1502D01*
G01X1574473Y616918D01*
X1574391Y616893D01*
X1574131Y616667D01*
G03X1574062Y616516I131J-151D01*
G01Y614416D01*
G03X1574142Y614256I200J0D01*
G01X1574399Y614064D01*
G03X1574575Y614032I120J160D01*
G02X1575001Y614094I427J-1440D01*
G02Y611090I0J-1502D01*
G02X1574575Y611152I1J1502D01*
G01X1574529Y611165D01*
X1574437Y611149D01*
X1574142Y610928D01*
G03X1574062Y610768I120J-160D01*
G01Y608807D01*
G03X1574132Y608655I200J0D01*
G01X1574363Y608458D01*
G03X1574524Y608412I130J152D01*
G02X1574760Y608431I238J-1483D01*
G02Y605427I0J-1502D01*
G02X1574525Y605446I3J1502D01*
G01X1574523D01*
X1574480Y605453D01*
X1574397Y605429D01*
X1574132Y605203D01*
G03X1574062Y605051I130J-152D01*
G01Y594098D01*
G03X1574121Y593956I200J0D01*
G01X1582630Y585447D01*
G02X1583306Y583816I-1631J-1632D01*
G01Y557258D01*
G02X1582630Y555627I-2307J1D01*
G01X1579493Y552490D01*
G02X1577862Y551814I-1632J1631D01*
G02X1575556Y554121I1J2307D01*
G01Y554122D01*
G02X1576231Y555752I2306J0D01*
G01X1578633Y558154D01*
G03X1578692Y558296I-141J142D01*
G01Y582778D01*
G03X1578633Y582920I-200J0D01*
G01X1572571Y588982D01*
G03X1572353Y589026I-142J-141D01*
G01X1572297Y589003D01*
X1572230Y588903D01*
Y582316D01*
G02X1571554Y580685I-2307J1D01*
G01X1566954Y576085D01*
G02X1565323Y575410I-1630J1631D01*
G02X1563016Y577716I-1J2306D01*
G02X1563692Y579347I2307J-1D01*
G01X1567557Y583212D01*
G03X1567616Y583354I-141J142D01*
G01Y633149D01*
G02X1568292Y634780I2307J-1D01*
G01X1569523Y636010D01*
G03X1569582Y636152I-141J142D01*
G01Y649380D01*
G02X1574194I2306J0D01*
G01Y648582D01*
G03X1574260Y648433I200J0D01*
G01X1574514Y648206D01*
X1574594Y648180D01*
X1574637Y648185D01*
G02X1574880Y648198I245J-2294D01*
G37*
G36*
G01X1425814Y619590D02*
G02X1425252Y620661I739J1071D01*
G02X1427856I1302J0D01*
G02X1427294Y619590I-1301J0D01*
G03Y618932I228J-329D01*
G02X1427856Y617861I-739J-1071D01*
G02X1425252I-1302J0D01*
G02X1425814Y618932I1301J0D01*
G03Y619590I-228J329D01*
G37*
G36*
G01X1422270D02*
G02X1421708Y620661I739J1071D01*
G02X1424312I1302J0D01*
G02X1423750Y619590I-1301J0D01*
G03Y618932I228J-329D01*
G02X1424312Y617861I-739J-1071D01*
G02X1421708I-1302J0D01*
G02X1422270Y618932I1301J0D01*
G03Y619590I-228J329D01*
G37*
G36*
G01X1418727D02*
G02X1418165Y620661I739J1071D01*
G02X1420769I1302J0D01*
G02X1420207Y619590I-1301J0D01*
G03Y618932I228J-329D01*
G02X1420769Y617861I-739J-1071D01*
G02X1418165I-1302J0D01*
G02X1418727Y618932I1301J0D01*
G03Y619590I-228J329D01*
G37*
G36*
G01X1415184D02*
G02X1414622Y620661I739J1071D01*
G02X1417226I1302J0D01*
G02X1416664Y619590I-1301J0D01*
G03Y618932I228J-329D01*
G02X1417226Y617861I-739J-1071D01*
G02X1414622I-1302J0D01*
G02X1415184Y618932I1301J0D01*
G03Y619590I-228J329D01*
G37*
G36*
G01X968727D02*
G02X968165Y620661I739J1071D01*
G02X970769I1302J0D01*
G02X970207Y619590I-1301J0D01*
G03Y618932I228J-329D01*
G02X970769Y617861I-739J-1071D01*
G02X968165I-1302J0D01*
G02X968727Y618932I1301J0D01*
G03Y619590I-228J329D01*
G37*
G36*
G01X965183D02*
G02X964621Y620661I739J1071D01*
G02X967225I1302J0D01*
G02X966663Y619590I-1301J0D01*
G03Y618932I228J-329D01*
G02X967225Y617861I-739J-1071D01*
G02X964621I-1302J0D01*
G02X965183Y618932I1301J0D01*
G03Y619590I-228J329D01*
G37*
G36*
G01X961640D02*
G02X961078Y620661I739J1071D01*
G02X963682I1302J0D01*
G02X963120Y619590I-1301J0D01*
G03Y618932I228J-329D01*
G02X963682Y617861I-739J-1071D01*
G02X961078I-1302J0D01*
G02X961640Y618932I1301J0D01*
G03Y619590I-228J329D01*
G37*
G36*
G01X958097D02*
G02X957535Y620661I739J1071D01*
G02X960139I1302J0D01*
G02X959577Y619590I-1301J0D01*
G03Y618932I228J-329D01*
G02X960139Y617861I-739J-1071D01*
G02X957535I-1302J0D01*
G02X958097Y618932I1301J0D01*
G03Y619590I-228J329D01*
G37*
G36*
G01X511640D02*
G02X511078Y620661I739J1071D01*
G02X513682I1302J0D01*
G02X513120Y619590I-1301J0D01*
G03Y618932I228J-329D01*
G02X513682Y617861I-739J-1071D01*
G02X511078I-1302J0D01*
G02X511640Y618932I1301J0D01*
G03Y619590I-228J329D01*
G37*
G36*
G01X508096D02*
G02X507534Y620661I739J1071D01*
G02X510138I1302J0D01*
G02X509576Y619590I-1301J0D01*
G03Y618932I228J-329D01*
G02X510138Y617861I-739J-1071D01*
G02X507534I-1302J0D01*
G02X508096Y618932I1301J0D01*
G03Y619590I-228J329D01*
G37*
G36*
G01X504553D02*
G02X503991Y620661I739J1071D01*
G02X506595I1302J0D01*
G02X506033Y619590I-1301J0D01*
G03Y618932I228J-329D01*
G02X506595Y617861I-739J-1071D01*
G02X503991I-1302J0D01*
G02X504553Y618932I1301J0D01*
G03Y619590I-228J329D01*
G37*
G36*
G01X501010D02*
G02X500448Y620661I739J1071D01*
G02X503052I1302J0D01*
G02X502490Y619590I-1301J0D01*
G03Y618932I228J-329D01*
G02X503052Y617861I-739J-1071D01*
G02X500448I-1302J0D01*
G02X501010Y618932I1301J0D01*
G03Y619590I-228J329D01*
G37*
G36*
G01X54554D02*
G02X53992Y620661I739J1071D01*
G02X56596I1302J0D01*
G02X56034Y619590I-1301J0D01*
G03Y618932I228J-329D01*
G02X56596Y617861I-739J-1071D01*
G02X53992I-1302J0D01*
G02X54554Y618932I1301J0D01*
G03Y619590I-228J329D01*
G37*
G36*
G01X51010D02*
G02X50448Y620661I739J1071D01*
G02X53052I1302J0D01*
G02X52490Y619590I-1301J0D01*
G03Y618932I228J-329D01*
G02X53052Y617861I-739J-1071D01*
G02X50448I-1302J0D01*
G02X51010Y618932I1301J0D01*
G03Y619590I-228J329D01*
G37*
G36*
G01X47467D02*
G02X46905Y620661I739J1071D01*
G02X49509I1302J0D01*
G02X48947Y619590I-1301J0D01*
G03Y618932I228J-329D01*
G02X49509Y617861I-739J-1071D01*
G02X46905I-1302J0D01*
G02X47467Y618932I1301J0D01*
G03Y619590I-228J329D01*
G37*
G36*
G01X43924D02*
G02X43362Y620661I739J1071D01*
G02X45966I1302J0D01*
G02X45404Y619590I-1301J0D01*
G03Y618932I228J-329D01*
G02X45966Y617861I-739J-1071D01*
G02X43362I-1302J0D01*
G02X43924Y618932I1301J0D01*
G03Y619590I-228J329D01*
G37*
G36*
G01X1445098Y576484D02*
G02X1448102I1502J0D01*
G02X1447460Y575253I-1501J0D01*
G03X1447376Y575114I114J-164D01*
G01X1447333Y574778D01*
X1447357Y574697D01*
X1447385Y574665D01*
G02X1447745Y573689I-1143J-976D01*
G02X1447024Y572406I-1502J0D01*
G01X1446980Y572379D01*
X1446929Y572291D01*
X1446921Y571849D01*
X1446968Y571759D01*
X1447011Y571731D01*
G02X1447685Y570478I-828J-1253D01*
G02X1446183Y568976I-1502J0D01*
G02X1445004Y569547I0J1503D01*
G01X1444978Y569580D01*
X1444904Y569619D01*
X1444525Y569648D01*
X1444447Y569620D01*
X1444416Y569591D01*
G02X1443388Y569184I-1028J1095D01*
G02X1441886Y570686I0J1502D01*
G02X1442387Y571806I1502J0D01*
G01X1442416Y571831D01*
X1442450Y571901D01*
X1442475Y572215D01*
G03X1442431Y572356I-199J15D01*
G02X1442095Y573303I1167J947D01*
G02X1443597Y574805I1502J0D01*
G02X1444488Y574512I0J-1501D01*
G01X1444489D01*
X1444520Y574489D01*
X1444596Y574470D01*
X1444952Y574522D01*
X1445021Y574563D01*
X1445044Y574594D01*
G02X1445383Y574920I1198J-906D01*
G03X1445467Y575059I-114J164D01*
G01X1445510Y575395D01*
X1445486Y575476D01*
X1445458Y575508D01*
G02X1445098Y576484I1143J976D01*
G37*
G36*
G01X988011D02*
G02X991015I1502J0D01*
G02X990373Y575253I-1501J0D01*
G03X990289Y575114I114J-164D01*
G01X990246Y574778D01*
X990270Y574697D01*
X990298Y574665D01*
G02X990658Y573689I-1143J-976D01*
G02X989937Y572406I-1502J0D01*
G01X989893Y572379D01*
X989842Y572291D01*
X989834Y571849D01*
X989881Y571759D01*
X989924Y571731D01*
G02X990598Y570478I-828J-1253D01*
G02X989096Y568976I-1502J0D01*
G02X987917Y569547I0J1503D01*
G01X987891Y569580D01*
X987817Y569619D01*
X987438Y569648D01*
X987360Y569620D01*
X987329Y569591D01*
G02X986301Y569184I-1028J1095D01*
G02X984799Y570686I0J1502D01*
G02X985300Y571806I1502J0D01*
G01X985329Y571831D01*
X985363Y571901D01*
X985388Y572215D01*
G03X985344Y572356I-199J15D01*
G02X985008Y573303I1167J947D01*
G02X986510Y574805I1502J0D01*
G02X987401Y574512I0J-1501D01*
G01X987402D01*
X987433Y574489D01*
X987509Y574470D01*
X987865Y574522D01*
X987934Y574563D01*
X987957Y574594D01*
G02X988296Y574920I1198J-906D01*
G03X988380Y575059I-114J164D01*
G01X988423Y575395D01*
X988399Y575476D01*
X988371Y575508D01*
G02X988011Y576484I1143J976D01*
G37*
G36*
G01X530924D02*
G02X533928I1502J0D01*
G02X533286Y575253I-1501J0D01*
G03X533202Y575114I114J-164D01*
G01X533159Y574778D01*
X533183Y574697D01*
X533211Y574665D01*
G02X533571Y573689I-1143J-976D01*
G02X532850Y572406I-1502J0D01*
G01X532806Y572379D01*
X532755Y572291D01*
X532747Y571849D01*
X532794Y571759D01*
X532837Y571731D01*
G02X533511Y570478I-828J-1253D01*
G02X532009Y568976I-1502J0D01*
G02X530830Y569547I0J1503D01*
G01X530804Y569580D01*
X530730Y569619D01*
X530351Y569648D01*
X530273Y569620D01*
X530242Y569591D01*
G02X529214Y569184I-1028J1095D01*
G02X527712Y570686I0J1502D01*
G02X528213Y571806I1502J0D01*
G01X528242Y571831D01*
X528276Y571901D01*
X528301Y572215D01*
G03X528257Y572356I-199J15D01*
G02X527921Y573303I1167J947D01*
G02X529423Y574805I1502J0D01*
G02X530314Y574512I0J-1501D01*
G01X530315D01*
X530346Y574489D01*
X530422Y574470D01*
X530778Y574522D01*
X530847Y574563D01*
X530870Y574594D01*
G02X531209Y574920I1198J-906D01*
G03X531293Y575059I-114J164D01*
G01X531336Y575395D01*
X531312Y575476D01*
X531284Y575508D01*
G02X530924Y576484I1143J976D01*
G37*
G36*
G01X73838D02*
G02X76842I1502J0D01*
G02X76200Y575253I-1501J0D01*
G03X76116Y575114I114J-164D01*
G01X76073Y574778D01*
X76097Y574697D01*
X76125Y574665D01*
G02X76485Y573689I-1143J-976D01*
G02X75764Y572406I-1502J0D01*
G01X75720Y572379D01*
X75669Y572291D01*
X75661Y571849D01*
X75708Y571759D01*
X75751Y571731D01*
G02X76425Y570478I-828J-1253D01*
G02X74923Y568976I-1502J0D01*
G02X73744Y569547I0J1503D01*
G01X73718Y569580D01*
X73644Y569619D01*
X73265Y569648D01*
X73187Y569620D01*
X73156Y569591D01*
G02X72128Y569184I-1028J1095D01*
G02X70626Y570686I0J1502D01*
G02X71127Y571806I1502J0D01*
G01X71156Y571831D01*
X71190Y571901D01*
X71215Y572215D01*
G03X71171Y572356I-199J15D01*
G02X70835Y573303I1167J947D01*
G02X72337Y574805I1502J0D01*
G02X73228Y574512I0J-1501D01*
G01X73229D01*
X73260Y574489D01*
X73336Y574470D01*
X73692Y574522D01*
X73761Y574563D01*
X73784Y574594D01*
G02X74123Y574920I1198J-906D01*
G03X74207Y575059I-114J164D01*
G01X74250Y575395D01*
X74226Y575476D01*
X74198Y575508D01*
G02X73838Y576484I1143J976D01*
G37*
G36*
G01X1447891Y566797D02*
G02X1450895I1502J0D01*
G02X1450263Y565573I-1501J0D01*
G03X1450179Y565410I116J-163D01*
G01Y565084D01*
G03X1450263Y564921I200J0D01*
G02X1450895Y563697I-869J-1224D01*
G02X1450489Y562670I-1502J0D01*
G01X1450463Y562643D01*
X1450435Y562572D01*
Y562222D01*
X1450463Y562151D01*
X1450489Y562124D01*
G02Y560070I-1096J-1027D01*
G01X1450463Y560043D01*
X1450435Y559972D01*
Y559622D01*
X1450463Y559551D01*
X1450489Y559524D01*
G02Y557470I-1096J-1027D01*
G01X1450463Y557443D01*
X1450435Y557372D01*
Y557022D01*
X1450463Y556951D01*
X1450489Y556924D01*
G02Y554870I-1096J-1027D01*
G01X1450463Y554843D01*
X1450435Y554772D01*
Y554422D01*
X1450463Y554351D01*
X1450489Y554324D01*
G02X1450895Y553297I-1096J-1027D01*
G02X1447891I-1502J0D01*
G02X1448297Y554324I1502J0D01*
G01X1448323Y554351D01*
X1448351Y554422D01*
Y554772D01*
X1448323Y554843D01*
X1448297Y554870D01*
G02Y556924I1096J1027D01*
G01X1448323Y556951D01*
X1448351Y557022D01*
Y557372D01*
X1448323Y557443D01*
X1448297Y557470D01*
G02Y559524I1096J1027D01*
G01X1448323Y559551D01*
X1448351Y559622D01*
Y559972D01*
X1448323Y560043D01*
X1448297Y560070D01*
G02Y562124I1096J1027D01*
G01X1448323Y562151D01*
X1448351Y562222D01*
Y562572D01*
X1448323Y562643D01*
X1448297Y562670D01*
G02X1447891Y563697I1096J1027D01*
G02X1448523Y564921I1501J0D01*
G03X1448607Y565084I-116J163D01*
G01Y565410D01*
G03X1448523Y565573I-200J0D01*
G02X1447891Y566797I869J1224D01*
G37*
G36*
G01X990804D02*
G02X993808I1502J0D01*
G02X993176Y565573I-1501J0D01*
G03X993092Y565410I116J-163D01*
G01Y565084D01*
G03X993176Y564921I200J0D01*
G02X993808Y563697I-869J-1224D01*
G02X993402Y562670I-1502J0D01*
G01X993376Y562643D01*
X993348Y562572D01*
Y562222D01*
X993376Y562151D01*
X993402Y562124D01*
G02Y560070I-1096J-1027D01*
G01X993376Y560043D01*
X993348Y559972D01*
Y559622D01*
X993376Y559551D01*
X993402Y559524D01*
G02Y557470I-1096J-1027D01*
G01X993376Y557443D01*
X993348Y557372D01*
Y557022D01*
X993376Y556951D01*
X993402Y556924D01*
G02Y554870I-1096J-1027D01*
G01X993376Y554843D01*
X993348Y554772D01*
Y554422D01*
X993376Y554351D01*
X993402Y554324D01*
G02X993808Y553297I-1096J-1027D01*
G02X990804I-1502J0D01*
G02X991210Y554324I1502J0D01*
G01X991236Y554351D01*
X991264Y554422D01*
Y554772D01*
X991236Y554843D01*
X991210Y554870D01*
G02Y556924I1096J1027D01*
G01X991236Y556951D01*
X991264Y557022D01*
Y557372D01*
X991236Y557443D01*
X991210Y557470D01*
G02Y559524I1096J1027D01*
G01X991236Y559551D01*
X991264Y559622D01*
Y559972D01*
X991236Y560043D01*
X991210Y560070D01*
G02Y562124I1096J1027D01*
G01X991236Y562151D01*
X991264Y562222D01*
Y562572D01*
X991236Y562643D01*
X991210Y562670D01*
G02X990804Y563697I1096J1027D01*
G02X991436Y564921I1501J0D01*
G03X991520Y565084I-116J163D01*
G01Y565410D01*
G03X991436Y565573I-200J0D01*
G02X990804Y566797I869J1224D01*
G37*
G36*
G01X533717D02*
G02X536721I1502J0D01*
G02X536089Y565573I-1501J0D01*
G03X536005Y565410I116J-163D01*
G01Y565084D01*
G03X536089Y564921I200J0D01*
G02X536721Y563697I-869J-1224D01*
G02X536315Y562670I-1502J0D01*
G01X536289Y562643D01*
X536261Y562572D01*
Y562222D01*
X536289Y562151D01*
X536315Y562124D01*
G02Y560070I-1096J-1027D01*
G01X536289Y560043D01*
X536261Y559972D01*
Y559622D01*
X536289Y559551D01*
X536315Y559524D01*
G02Y557470I-1096J-1027D01*
G01X536289Y557443D01*
X536261Y557372D01*
Y557022D01*
X536289Y556951D01*
X536315Y556924D01*
G02Y554870I-1096J-1027D01*
G01X536289Y554843D01*
X536261Y554772D01*
Y554422D01*
X536289Y554351D01*
X536315Y554324D01*
G02X536721Y553297I-1096J-1027D01*
G02X533717I-1502J0D01*
G02X534123Y554324I1502J0D01*
G01X534149Y554351D01*
X534177Y554422D01*
Y554772D01*
X534149Y554843D01*
X534123Y554870D01*
G02Y556924I1096J1027D01*
G01X534149Y556951D01*
X534177Y557022D01*
Y557372D01*
X534149Y557443D01*
X534123Y557470D01*
G02Y559524I1096J1027D01*
G01X534149Y559551D01*
X534177Y559622D01*
Y559972D01*
X534149Y560043D01*
X534123Y560070D01*
G02Y562124I1096J1027D01*
G01X534149Y562151D01*
X534177Y562222D01*
Y562572D01*
X534149Y562643D01*
X534123Y562670D01*
G02X533717Y563697I1096J1027D01*
G02X534349Y564921I1501J0D01*
G03X534433Y565084I-116J163D01*
G01Y565410D01*
G03X534349Y565573I-200J0D01*
G02X533717Y566797I869J1224D01*
G37*
G36*
G01X1446988Y549920D02*
G02Y546916I0J-1502D01*
G02X1446001Y547286I0J1501D01*
G01X1446000D01*
Y547287D01*
G03X1445870Y547335I-130J-152D01*
G01X1445606D01*
G03X1445476Y547287I0J-200D01*
G01X1445475Y547286D01*
G02X1443501I-987J1131D01*
G01X1443500D01*
Y547287D01*
G03X1443370Y547335I-130J-152D01*
G01X1443106D01*
G03X1442976Y547287I0J-200D01*
G01X1442975Y547286D01*
G02X1441001I-987J1131D01*
G01X1441000D01*
Y547287D01*
G03X1440870Y547335I-130J-152D01*
G01X1440606D01*
G03X1440476Y547287I0J-200D01*
G01X1440475Y547286D01*
G02X1440381Y547211I-983J1135D01*
G03X1440379Y547209I140J-142D01*
G03X1440299Y547051I120J-160D01*
G01X1440296Y546731D01*
G03X1440375Y546570I200J-2D01*
G02X1440964Y545377I-914J-1193D01*
G02X1440594Y544390I-1501J0D01*
G01Y544389D01*
X1440593D01*
G03X1440545Y544259I152J-130D01*
G01Y543995D01*
G03X1440593Y543865I200J0D01*
G01X1440594Y543864D01*
G02Y541890I-1131J-987D01*
G01Y541889D01*
X1440593D01*
G03X1440545Y541759I152J-130D01*
G01Y541495D01*
G03X1440593Y541365I200J0D01*
G01X1440594Y541364D01*
G02Y539390I-1131J-987D01*
G01Y539389D01*
X1440593D01*
G03X1440545Y539259I152J-130D01*
G01Y538995D01*
G03X1440593Y538865I200J0D01*
G01X1440594Y538864D01*
G02X1440964Y537877I-1131J-987D01*
G02X1437960I-1502J0D01*
G02X1438330Y538864I1501J0D01*
G01Y538865D01*
X1438331D01*
G03X1438379Y538995I-152J130D01*
G01Y539259D01*
G03X1438331Y539389I-200J0D01*
G01X1438330Y539390D01*
G02Y541364I1131J987D01*
G01Y541365D01*
X1438331D01*
G03X1438379Y541495I-152J130D01*
G01Y541759D01*
G03X1438331Y541889I-200J0D01*
G01X1438330Y541890D01*
G02Y543864I1131J987D01*
G01Y543865D01*
X1438331D01*
G03X1438379Y543995I-152J130D01*
G01Y544259D01*
G03X1438331Y544389I-200J0D01*
G01X1438330Y544390D01*
G02X1437960Y545377I1131J987D01*
G02X1438569Y546585I1501J1D01*
G01X1438571D01*
Y546586D01*
G03X1438651Y546744I-120J160D01*
G01X1438654Y547064D01*
G03X1438575Y547225I-200J2D01*
G02X1437986Y548418I914J1193D01*
G02X1439488Y549920I1502J0D01*
G02X1440475Y549550I0J-1501D01*
G01X1440476D01*
Y549549D01*
G03X1440606Y549501I130J152D01*
G01X1440870D01*
G03X1441000Y549549I0J200D01*
G01X1441001Y549550D01*
G02X1442975I987J-1131D01*
G01X1442976D01*
Y549549D01*
G03X1443106Y549501I130J152D01*
G01X1443370D01*
G03X1443500Y549549I0J200D01*
G01X1443501Y549550D01*
G02X1445475I987J-1131D01*
G01X1445476D01*
Y549549D01*
G03X1445606Y549501I130J152D01*
G01X1445870D01*
G03X1446000Y549549I0J200D01*
G01X1446001Y549550D01*
G02X1446988Y549920I987J-1131D01*
G37*
G36*
G01X533488Y549846D02*
G02Y546842I0J-1502D01*
G02X532501Y547212I0J1501D01*
G01X532500D01*
Y547213D01*
G03X532370Y547261I-130J-152D01*
G01X532106D01*
G03X531976Y547213I0J-200D01*
G01X531975Y547212D01*
G02X530001I-987J1131D01*
G01X530000D01*
Y547213D01*
G03X529870Y547261I-130J-152D01*
G01X529606D01*
G03X529476Y547213I0J-200D01*
G01X529475Y547212D01*
G02X527501I-987J1131D01*
G01X527500D01*
Y547213D01*
G03X527370Y547261I-130J-152D01*
G01X527106D01*
G03X526976Y547213I0J-200D01*
G01X526975Y547212D01*
G02X526586Y546966I-988J1131D01*
G03X526471Y546829I80J-184D01*
G01X526386Y546471D01*
X526408Y546379D01*
X526439Y546342D01*
G02X526790Y545377I-1151J-965D01*
G02X526420Y544390I-1501J0D01*
G01Y544389D01*
X526419D01*
G03X526371Y544259I152J-130D01*
G01Y543995D01*
G03X526419Y543865I200J0D01*
G01X526420Y543864D01*
G02Y541890I-1131J-987D01*
G01Y541889D01*
X526419D01*
G03X526371Y541759I152J-130D01*
G01Y541495D01*
G03X526419Y541365I200J0D01*
G01X526420Y541364D01*
G02Y539390I-1131J-987D01*
G01Y539389D01*
X526419D01*
G03X526371Y539259I152J-130D01*
G01Y538995D01*
G03X526419Y538865I200J0D01*
G01X526420Y538864D01*
G02X526790Y537877I-1131J-987D01*
G02X523786I-1502J0D01*
G02X524156Y538864I1501J0D01*
G01Y538865D01*
X524157D01*
G03X524205Y538995I-152J130D01*
G01Y539259D01*
G03X524157Y539389I-200J0D01*
G01X524156Y539390D01*
G02Y541364I1131J987D01*
G01Y541365D01*
X524157D01*
G03X524205Y541495I-152J130D01*
G01Y541759D01*
G03X524157Y541889I-200J0D01*
G01X524156Y541890D01*
G02Y543864I1131J987D01*
G01Y543865D01*
X524157D01*
G03X524205Y543995I-152J130D01*
G01Y544259D01*
G03X524157Y544389I-200J0D01*
G01X524156Y544390D01*
G02X523786Y545377I1131J987D01*
G02X524690Y546755I1502J0D01*
G03X524805Y546892I-80J184D01*
G01X524890Y547250D01*
X524868Y547342D01*
X524837Y547379D01*
G02X524486Y548344I1151J965D01*
G02X525988Y549846I1502J0D01*
G02X526975Y549476I0J-1501D01*
G01X526976D01*
Y549475D01*
G03X527106Y549427I130J152D01*
G01X527370D01*
G03X527500Y549475I0J200D01*
G01X527501Y549476D01*
G02X529475I987J-1131D01*
G01X529476D01*
Y549475D01*
G03X529606Y549427I130J152D01*
G01X529870D01*
G03X530000Y549475I0J200D01*
G01X530001Y549476D01*
G02X531975I987J-1131D01*
G01X531976D01*
Y549475D01*
G03X532106Y549427I130J152D01*
G01X532370D01*
G03X532500Y549475I0J200D01*
G01X532501Y549476D01*
G02X533488Y549846I987J-1131D01*
G37*
G36*
G01X1433843Y545847D02*
X1434137D01*
G03X1434284Y545912I-1J200D01*
G02X1435390Y546397I1106J-1019D01*
G02X1436892Y544895I0J-1502D01*
G02X1436313Y543710I-1502J0D01*
G03X1436236Y543552I123J-158D01*
G01Y543238D01*
G03X1436313Y543080I200J0D01*
G02X1436892Y541895I-923J-1185D01*
G02X1435390Y540393I-1502J0D01*
G02X1434403Y540763I0J1501D01*
G01X1434402D01*
Y540764D01*
G03X1434272Y540812I-130J-152D01*
G01X1434008D01*
G03X1433878Y540764I0J-200D01*
G01X1433877Y540763D01*
G02X1432890Y540393I-987J1131D01*
G02X1431388Y541895I0J1502D01*
G02X1431860Y542988I1502J0D01*
G01X1431861Y542989D01*
G03X1431922Y543154I-138J145D01*
G01X1431891Y543469D01*
G03X1431797Y543619I-199J-20D01*
G02X1431088Y544895I794J1276D01*
G02X1432590Y546397I1502J0D01*
G02X1433696Y545912I0J-1504D01*
G03X1433843Y545847I148J135D01*
G37*
G36*
G01X976756D02*
X977050D01*
G03X977197Y545912I-1J200D01*
G02X978303Y546397I1106J-1019D01*
G02X979805Y544895I0J-1502D01*
G02X979226Y543710I-1502J0D01*
G03X979149Y543552I123J-158D01*
G01Y543238D01*
G03X979226Y543080I200J0D01*
G02X979805Y541895I-923J-1185D01*
G02X978303Y540393I-1502J0D01*
G02X977316Y540763I0J1501D01*
G01X977315D01*
Y540764D01*
G03X977185Y540812I-130J-152D01*
G01X976921D01*
G03X976791Y540764I0J-200D01*
G01X976790Y540763D01*
G02X975803Y540393I-987J1131D01*
G02X974301Y541895I0J1502D01*
G02X974773Y542988I1502J0D01*
G01X974774Y542989D01*
G03X974835Y543154I-138J145D01*
G01X974804Y543469D01*
G03X974710Y543619I-199J-20D01*
G02X974001Y544895I794J1276D01*
G02X975503Y546397I1502J0D01*
G02X976609Y545912I0J-1504D01*
G03X976756Y545847I148J135D01*
G37*
G36*
G01X519669D02*
X519963D01*
G03X520110Y545912I-1J200D01*
G02X521216Y546397I1106J-1019D01*
G02X522718Y544895I0J-1502D01*
G02X522139Y543710I-1502J0D01*
G03X522062Y543552I123J-158D01*
G01Y543238D01*
G03X522139Y543080I200J0D01*
G02X522718Y541895I-923J-1185D01*
G02X521216Y540393I-1502J0D01*
G02X520229Y540763I0J1501D01*
G01X520228D01*
Y540764D01*
G03X520098Y540812I-130J-152D01*
G01X519834D01*
G03X519704Y540764I0J-200D01*
G01X519703Y540763D01*
G02X518716Y540393I-987J1131D01*
G02X517214Y541895I0J1502D01*
G02X517686Y542988I1502J0D01*
G01X517687Y542989D01*
G03X517748Y543154I-138J145D01*
G01X517717Y543469D01*
G03X517623Y543619I-199J-20D01*
G02X516914Y544895I794J1276D01*
G02X518416Y546397I1502J0D01*
G02X519522Y545912I0J-1504D01*
G03X519669Y545847I148J135D01*
G37*
G36*
G01X62583D02*
X62877D01*
G03X63024Y545912I-1J200D01*
G02X64130Y546397I1106J-1019D01*
G02X65632Y544895I0J-1502D01*
G02X65053Y543710I-1502J0D01*
G03X64976Y543552I123J-158D01*
G01Y543238D01*
G03X65053Y543080I200J0D01*
G02X65632Y541895I-923J-1185D01*
G02X64130Y540393I-1502J0D01*
G02X63143Y540763I0J1501D01*
G01X63142D01*
Y540764D01*
G03X63012Y540812I-130J-152D01*
G01X62748D01*
G03X62618Y540764I0J-200D01*
G01X62617Y540763D01*
G02X61630Y540393I-987J1131D01*
G02X60128Y541895I0J1502D01*
G02X60600Y542988I1502J0D01*
G01X60601Y542989D01*
G03X60662Y543154I-138J145D01*
G01X60631Y543469D01*
G03X60537Y543619I-199J-20D01*
G02X59828Y544895I794J1276D01*
G02X61330Y546397I1502J0D01*
G02X62436Y545912I0J-1504D01*
G03X62583Y545847I148J135D01*
G37*
G36*
G01X1409618Y530446D02*
G02Y533450I0J1502D01*
G02X1410842Y532819I0J-1503D01*
G01X1410869Y532780D01*
X1410953Y532736D01*
X1411321Y532728D01*
G03X1411483Y532805I4J200D01*
G02X1412668Y533384I1185J-923D01*
G02X1413655Y533014I0J-1501D01*
G01X1413656D01*
Y533013D01*
G03X1413786Y532965I130J152D01*
G01X1414050D01*
G03X1414180Y533013I0J200D01*
G01X1414181Y533014D01*
G02X1416155I987J-1131D01*
G01X1416156D01*
Y533013D01*
G03X1416286Y532965I130J152D01*
G01X1416550D01*
G03X1416680Y533013I0J200D01*
G01X1416681Y533014D01*
G02X1417668Y533384I987J-1131D01*
G02X1419170Y531882I0J-1502D01*
G02X1418903Y531027I-1502J0D01*
G01X1418880Y530993D01*
X1418863Y530912D01*
X1418943Y530545D01*
X1418991Y530478D01*
X1419026Y530457D01*
G02X1419755Y529169I-773J-1288D01*
G02X1416751I-1502J0D01*
G02X1417018Y530024I1502J0D01*
G01X1417041Y530058D01*
X1417058Y530139D01*
X1416978Y530506D01*
X1416930Y530573D01*
X1416895Y530594D01*
G02X1416682Y530750I777J1285D01*
G03X1416680Y530751I-88J-173D01*
G03X1416550Y530799I-130J-152D01*
G01X1416286D01*
G03X1416156Y530751I0J-200D01*
G01X1416155Y530750D01*
G02X1414181I-987J1131D01*
G01X1414180D01*
Y530751D01*
G03X1414050Y530799I-130J-152D01*
G01X1413786D01*
G03X1413656Y530751I0J-200D01*
G01X1413655Y530750D01*
G02X1412668Y530380I-987J1131D01*
G02X1411444Y531011I0J1503D01*
G01X1411417Y531050D01*
X1411333Y531094D01*
X1410965Y531102D01*
G03X1410803Y531025I-4J-200D01*
G02X1409618Y530446I-1185J923D01*
G37*
G36*
G01X952531D02*
G02Y533450I0J1502D01*
G02X953755Y532819I0J-1503D01*
G01X953782Y532780D01*
X953866Y532736D01*
X954234Y532728D01*
G03X954396Y532805I4J200D01*
G02X955581Y533384I1185J-923D01*
G02X956568Y533014I0J-1501D01*
G01X956569D01*
Y533013D01*
G03X956699Y532965I130J152D01*
G01X956963D01*
G03X957093Y533013I0J200D01*
G01X957094Y533014D01*
G02X959068I987J-1131D01*
G01X959069D01*
Y533013D01*
G03X959199Y532965I130J152D01*
G01X959463D01*
G03X959593Y533013I0J200D01*
G01X959594Y533014D01*
G02X960581Y533384I987J-1131D01*
G02X962083Y531882I0J-1502D01*
G02X961816Y531027I-1502J0D01*
G01X961793Y530993D01*
X961776Y530912D01*
X961856Y530545D01*
X961904Y530478D01*
X961939Y530457D01*
G02X962668Y529169I-773J-1288D01*
G02X959664I-1502J0D01*
G02X959931Y530024I1502J0D01*
G01X959954Y530058D01*
X959971Y530139D01*
X959891Y530506D01*
X959843Y530573D01*
X959808Y530594D01*
G02X959595Y530750I777J1285D01*
G03X959593Y530751I-88J-173D01*
G03X959463Y530799I-130J-152D01*
G01X959199D01*
G03X959069Y530751I0J-200D01*
G01X959068Y530750D01*
G02X957094I-987J1131D01*
G01X957093D01*
Y530751D01*
G03X956963Y530799I-130J-152D01*
G01X956699D01*
G03X956569Y530751I0J-200D01*
G01X956568Y530750D01*
G02X955581Y530380I-987J1131D01*
G02X954357Y531011I0J1503D01*
G01X954330Y531050D01*
X954246Y531094D01*
X953878Y531102D01*
G03X953716Y531025I-4J-200D01*
G02X952531Y530446I-1185J923D01*
G37*
G36*
G01X495444D02*
G02Y533450I0J1502D01*
G02X496668Y532819I0J-1503D01*
G01X496695Y532780D01*
X496779Y532736D01*
X497147Y532728D01*
G03X497309Y532805I4J200D01*
G02X498494Y533384I1185J-923D01*
G02X499481Y533014I0J-1501D01*
G01X499482D01*
Y533013D01*
G03X499612Y532965I130J152D01*
G01X499876D01*
G03X500006Y533013I0J200D01*
G01X500007Y533014D01*
G02X501981I987J-1131D01*
G01X501982D01*
Y533013D01*
G03X502112Y532965I130J152D01*
G01X502376D01*
G03X502506Y533013I0J200D01*
G01X502507Y533014D01*
G02X503494Y533384I987J-1131D01*
G02X504996Y531882I0J-1502D01*
G02X504729Y531027I-1502J0D01*
G01X504706Y530993D01*
X504689Y530912D01*
X504769Y530545D01*
X504817Y530478D01*
X504852Y530457D01*
G02X505581Y529169I-773J-1288D01*
G02X502577I-1502J0D01*
G02X502844Y530024I1502J0D01*
G01X502867Y530058D01*
X502884Y530139D01*
X502804Y530506D01*
X502756Y530573D01*
X502721Y530594D01*
G02X502508Y530750I777J1285D01*
G03X502506Y530751I-88J-173D01*
G03X502376Y530799I-130J-152D01*
G01X502112D01*
G03X501982Y530751I0J-200D01*
G01X501981Y530750D01*
G02X500007I-987J1131D01*
G01X500006D01*
Y530751D01*
G03X499876Y530799I-130J-152D01*
G01X499612D01*
G03X499482Y530751I0J-200D01*
G01X499481Y530750D01*
G02X498494Y530380I-987J1131D01*
G02X497270Y531011I0J1503D01*
G01X497243Y531050D01*
X497159Y531094D01*
X496791Y531102D01*
G03X496629Y531025I-4J-200D01*
G02X495444Y530446I-1185J923D01*
G37*
G36*
G01X38358D02*
G02Y533450I0J1502D01*
G02X39582Y532819I0J-1503D01*
G01X39609Y532780D01*
X39693Y532736D01*
X40061Y532728D01*
G03X40223Y532805I4J200D01*
G02X41408Y533384I1185J-923D01*
G02X42395Y533014I0J-1501D01*
G01X42396D01*
Y533013D01*
G03X42526Y532965I130J152D01*
G01X42790D01*
G03X42920Y533013I0J200D01*
G01X42921Y533014D01*
G02X44895I987J-1131D01*
G01X44896D01*
Y533013D01*
G03X45026Y532965I130J152D01*
G01X45290D01*
G03X45420Y533013I0J200D01*
G01X45421Y533014D01*
G02X46408Y533384I987J-1131D01*
G02X47910Y531882I0J-1502D01*
G02X47643Y531027I-1502J0D01*
G01X47620Y530993D01*
X47603Y530912D01*
X47683Y530545D01*
X47731Y530478D01*
X47766Y530457D01*
G02X48495Y529169I-773J-1288D01*
G02X45491I-1502J0D01*
G02X45758Y530024I1502J0D01*
G01X45781Y530058D01*
X45798Y530139D01*
X45718Y530506D01*
X45670Y530573D01*
X45635Y530594D01*
G02X45422Y530750I777J1285D01*
G03X45420Y530751I-88J-173D01*
G03X45290Y530799I-130J-152D01*
G01X45026D01*
G03X44896Y530751I0J-200D01*
G01X44895Y530750D01*
G02X42921I-987J1131D01*
G01X42920D01*
Y530751D01*
G03X42790Y530799I-130J-152D01*
G01X42526D01*
G03X42396Y530751I0J-200D01*
G01X42395Y530750D01*
G02X41408Y530380I-987J1131D01*
G02X40184Y531011I0J1503D01*
G01X40157Y531050D01*
X40073Y531094D01*
X39705Y531102D01*
G03X39543Y531025I-4J-200D01*
G02X38358Y530446I-1185J923D01*
G37*
G36*
G01X1316443Y523058D02*
G02X1317945Y524560I1502J0D01*
G02X1319198Y523886I0J-1502D01*
G03X1319369Y523796I167J110D01*
G01X1319708Y523804D01*
G03X1319875Y523901I-4J200D01*
G02X1321164Y524632I1289J-771D01*
G02X1322666Y523130I0J-1502D01*
G02X1322255Y522098I-1501J0D01*
G01X1322254Y522097D01*
G03X1322201Y521940I146J-137D01*
G01X1322235Y521596D01*
X1322279Y521521D01*
X1322315Y521496D01*
G02X1322952Y520268I-865J-1228D01*
G02X1321450Y518766I-1502J0D01*
G02X1320200Y519436I0J1501D01*
G01X1320170Y519481D01*
X1320075Y519528D01*
X1319674Y519502D01*
G03X1319508Y519390I14J-200D01*
G02X1318160Y518551I-1348J663D01*
G02X1316658Y520053I0J1502D01*
G02X1317160Y521174I1503J0D01*
G01X1317161D01*
G03X1317227Y521338I-134J149D01*
G01X1317201Y521701D01*
X1317154Y521780D01*
X1317115Y521806D01*
G02X1316443Y523058I830J1252D01*
G37*
G36*
G01X426066Y502003D02*
G02X429070I1502J0D01*
G02X428508Y500831I-1503J0D01*
G01X428470Y500801D01*
X428431Y500715D01*
X428448Y500297D01*
X428494Y500215D01*
X428534Y500188D01*
G02X429195Y498943I-842J-1245D01*
G02X427693Y497441I-1502J0D01*
G02X426834Y497711I0J1501D01*
G01X426792Y497741D01*
X426691Y497752D01*
X426331Y497600D01*
G03X426211Y497451I77J-185D01*
G01Y497450D01*
G02X425863Y496717I-1480J254D01*
G01X425862Y496716D01*
G03X425814Y496586I152J-130D01*
G01Y496322D01*
G03X425862Y496192I200J0D01*
G01X425863Y496191D01*
G02Y494217I-1131J-987D01*
G01Y494216D01*
X425862D01*
G03X425814Y494086I152J-130D01*
G01Y493822D01*
G03X425862Y493692I200J0D01*
G01X425863Y493691D01*
G02X426233Y492704I-1131J-987D01*
G02X423229I-1502J0D01*
G02X423599Y493691I1501J0D01*
G01Y493692D01*
X423600D01*
G03X423648Y493822I-152J130D01*
G01Y494086D01*
G03X423600Y494216I-200J0D01*
G01X423599Y494217D01*
G02Y496191I1131J987D01*
G01Y496192D01*
X423600D01*
G03X423648Y496322I-152J130D01*
G01Y496586D01*
G03X423600Y496716I-200J0D01*
G01X423599Y496717D01*
G02Y498691I1131J987D01*
G01Y498692D01*
X423600D01*
G03X423648Y498822I-152J130D01*
G01Y499086D01*
G03X423600Y499216I-200J0D01*
G01X423599Y499217D01*
G02X423229Y500204I1131J987D01*
G02X424731Y501706I1502J0D01*
G02X425474Y501509I-1J-1502D01*
G01X425522Y501482D01*
X425632Y501484D01*
X426025Y501733D01*
X426075Y501833D01*
X426070Y501888D01*
G02X426066Y502003I1498J110D01*
G37*
G36*
G01X434287Y501525D02*
G02X435789Y503027I1502J0D01*
G02X437230Y501948I0J-1502D01*
G01Y501946D01*
G03X437352Y501816I192J58D01*
G01X437653Y501705D01*
G03X437830Y501723I70J187D01*
G01X437831Y501724D01*
G02X438644Y501963I813J-1263D01*
G02Y498959I0J-1502D01*
G01X438642D01*
G02X437921Y499144I1J1502D01*
G01X437876Y499169D01*
X437774D01*
X437388Y498958D01*
X437333Y498872D01*
X437330Y498821D01*
G02X435831Y497421I-1499J103D01*
G02X434329Y498923I0J1502D01*
G02X434719Y499933I1503J0D01*
G01X434744Y499961D01*
X434771Y500032D01*
X434766Y500344D01*
G03X434710Y500480I-200J-3D01*
G02X434287Y501525I1079J1045D01*
G37*
G36*
G01X1443674Y499103D02*
X1443968D01*
G03X1444115Y499168I-1J200D01*
G02X1445221Y499653I1106J-1019D01*
G02X1446723Y498151I0J-1502D01*
G02X1446144Y496966I-1502J0D01*
G03X1446067Y496808I123J-158D01*
G01Y496494D01*
G03X1446144Y496336I200J0D01*
G02X1446723Y495151I-923J-1185D01*
G02X1445221Y493649I-1502J0D01*
G02X1444234Y494019I0J1501D01*
G01X1444233D01*
Y494020D01*
G03X1444103Y494068I-130J-152D01*
G01X1443839D01*
G03X1443709Y494020I0J-200D01*
G01X1443708Y494019D01*
G02X1442721Y493649I-987J1131D01*
G02X1441219Y495151I0J1502D01*
G02X1441691Y496244I1502J0D01*
G01X1441692Y496245D01*
G03X1441753Y496410I-138J145D01*
G01X1441722Y496725D01*
G03X1441628Y496875I-199J-20D01*
G02X1440919Y498151I794J1276D01*
G02X1442421Y499653I1502J0D01*
G02X1443527Y499168I0J-1504D01*
G03X1443674Y499103I148J135D01*
G37*
G36*
G01X529500D02*
X529794D01*
G03X529941Y499168I-1J200D01*
G02X531047Y499653I1106J-1019D01*
G02X532549Y498151I0J-1502D01*
G02X531970Y496966I-1502J0D01*
G03X531893Y496808I123J-158D01*
G01Y496494D01*
G03X531970Y496336I200J0D01*
G02X532549Y495151I-923J-1185D01*
G02X531047Y493649I-1502J0D01*
G02X530060Y494019I0J1501D01*
G01X530059D01*
Y494020D01*
G03X529929Y494068I-130J-152D01*
G01X529665D01*
G03X529535Y494020I0J-200D01*
G01X529534Y494019D01*
G02X528547Y493649I-987J1131D01*
G02X527045Y495151I0J1502D01*
G02X527517Y496244I1502J0D01*
G01X527518Y496245D01*
G03X527579Y496410I-138J145D01*
G01X527548Y496725D01*
G03X527454Y496875I-199J-20D01*
G02X526745Y498151I794J1276D01*
G02X528247Y499653I1502J0D01*
G02X529353Y499168I0J-1504D01*
G03X529500Y499103I148J135D01*
G37*
G36*
G01X1299469Y485889D02*
G02X1299306Y485880I-164J1493D01*
G01X1299304D01*
G02X1300806Y487382I0J1502D01*
G01Y487381D01*
G02X1300727Y486901I-1502J1D01*
G03X1301149Y486375I379J-128D01*
G02X1301312Y486384I164J-1493D01*
G01X1301314D01*
G02X1299812Y484882I0J-1502D01*
G01Y484883D01*
G02X1299891Y485363I1502J-1D01*
G03X1299469Y485889I-379J128D01*
G37*
G36*
G01X385296D02*
G02X385133Y485880I-164J1493D01*
G01X385131D01*
G02X386633Y487382I0J1502D01*
G01Y487381D01*
G02X386554Y486901I-1502J1D01*
G03X386976Y486375I379J-128D01*
G02X387139Y486384I164J-1493D01*
G01X387141D01*
G02X385639Y484882I0J-1502D01*
G01Y484883D01*
G02X385718Y485363I1502J-1D01*
G03X385296Y485889I-379J128D01*
G37*
G36*
G01X970895Y465004D02*
G02X973899I1502J0D01*
G02X972540Y463509I-1502J0D01*
G03X972386Y463411I19J-199D01*
G01X972223Y463131D01*
G03X972213Y462948I173J-101D01*
G02X972342Y462339I-1373J-609D01*
G02X971972Y461352I-1501J0D01*
G01Y461351D01*
X971971D01*
G03X971923Y461221I152J-130D01*
G01Y460957D01*
G03X971971Y460827I200J0D01*
G01X971972Y460826D01*
G02Y458852I-1131J-987D01*
G01Y458851D01*
X971971D01*
G03X971923Y458721I152J-130D01*
G01Y458457D01*
G03X971971Y458327I200J0D01*
G01X971972Y458326D01*
G02X972342Y457339I-1131J-987D01*
G02X970840Y455837I-1502J0D01*
G02X969853Y456207I0J1501D01*
G01X969852D01*
Y456208D01*
G03X969722Y456256I-130J-152D01*
G01X969458D01*
G03X969328Y456208I0J-200D01*
G01X969327Y456207D01*
G02X968340Y455837I-987J1131D01*
G02X966838Y457339I0J1502D01*
G02X967208Y458326I1501J0D01*
G01Y458327D01*
X967209D01*
G03X967257Y458457I-152J130D01*
G01Y458721D01*
G03X967209Y458851I-200J0D01*
G01X967208Y458852D01*
G02Y460826I1131J987D01*
G01Y460827D01*
X967209D01*
G03X967257Y460957I-152J130D01*
G01Y461221D01*
G03X967209Y461351I-200J0D01*
G01X967208Y461352D01*
G02X966838Y462339I1131J987D01*
G02X968340Y463841I1502J0D01*
G02X969327Y463471I0J-1501D01*
G01X969328D01*
Y463470D01*
G03X969458Y463422I130J152D01*
G01X969722D01*
G03X969852Y463470I0J200D01*
G01X969853Y463471D01*
G02X970697Y463834I987J-1132D01*
G03X970851Y463932I-19J199D01*
G01X971014Y464212D01*
G03X971024Y464395I-173J101D01*
G02X970895Y465004I1373J609D01*
G37*
G36*
G01X56722D02*
G02X59726I1502J0D01*
G02X58367Y463509I-1502J0D01*
G03X58213Y463411I19J-199D01*
G01X58050Y463131D01*
G03X58040Y462948I173J-101D01*
G02X58169Y462339I-1373J-609D01*
G02X57799Y461352I-1501J0D01*
G01Y461351D01*
X57798D01*
G03X57750Y461221I152J-130D01*
G01Y460957D01*
G03X57798Y460827I200J0D01*
G01X57799Y460826D01*
G02Y458852I-1131J-987D01*
G01Y458851D01*
X57798D01*
G03X57750Y458721I152J-130D01*
G01Y458457D01*
G03X57798Y458327I200J0D01*
G01X57799Y458326D01*
G02X58169Y457339I-1131J-987D01*
G02X56667Y455837I-1502J0D01*
G02X55680Y456207I0J1501D01*
G01X55679D01*
Y456208D01*
G03X55549Y456256I-130J-152D01*
G01X55285D01*
G03X55155Y456208I0J-200D01*
G01X55154Y456207D01*
G02X54167Y455837I-987J1131D01*
G02X52665Y457339I0J1502D01*
G02X53035Y458326I1501J0D01*
G01Y458327D01*
X53036D01*
G03X53084Y458457I-152J130D01*
G01Y458721D01*
G03X53036Y458851I-200J0D01*
G01X53035Y458852D01*
G02Y460826I1131J987D01*
G01Y460827D01*
X53036D01*
G03X53084Y460957I-152J130D01*
G01Y461221D01*
G03X53036Y461351I-200J0D01*
G01X53035Y461352D01*
G02X52665Y462339I1131J987D01*
G02X54167Y463841I1502J0D01*
G02X55154Y463471I0J-1501D01*
G01X55155D01*
Y463470D01*
G03X55285Y463422I130J152D01*
G01X55549D01*
G03X55679Y463470I0J200D01*
G01X55680Y463471D01*
G02X56524Y463834I987J-1132D01*
G03X56678Y463932I-19J199D01*
G01X56841Y464212D01*
G03X56851Y464395I-173J101D01*
G02X56722Y465004I1373J609D01*
G37*
G36*
G01X1425982Y462004D02*
G02X1428986I1502J0D01*
G02X1427627Y460509I-1502J0D01*
G03X1427473Y460411I19J-199D01*
G01X1427310Y460131D01*
G03X1427300Y459948I173J-101D01*
G02X1427429Y459339I-1373J-609D01*
G02X1427059Y458352I-1501J0D01*
G01Y458351D01*
X1427058D01*
G03X1427010Y458221I152J-130D01*
G01Y457957D01*
G03X1427058Y457827I200J0D01*
G01X1427059Y457826D01*
G02Y455852I-1131J-987D01*
G01Y455851D01*
X1427058D01*
G03X1427010Y455721I152J-130D01*
G01Y455457D01*
G03X1427058Y455327I200J0D01*
G01X1427059Y455326D01*
G02X1427429Y454339I-1131J-987D01*
G02X1425927Y452837I-1502J0D01*
G02X1424940Y453207I0J1501D01*
G01X1424939D01*
Y453208D01*
G03X1424809Y453256I-130J-152D01*
G01X1424545D01*
G03X1424415Y453208I0J-200D01*
G01X1424414Y453207D01*
G02X1423427Y452837I-987J1131D01*
G02X1421925Y454339I0J1502D01*
G02X1422295Y455326I1501J0D01*
G01Y455327D01*
X1422296D01*
G03X1422344Y455457I-152J130D01*
G01Y455721D01*
G03X1422296Y455851I-200J0D01*
G01X1422295Y455852D01*
G02Y457826I1131J987D01*
G01Y457827D01*
X1422296D01*
G03X1422344Y457957I-152J130D01*
G01Y458221D01*
G03X1422296Y458351I-200J0D01*
G01X1422295Y458352D01*
G02X1421925Y459339I1131J987D01*
G02X1423427Y460841I1502J0D01*
G02X1424414Y460471I0J-1501D01*
G01X1424415D01*
Y460470D01*
G03X1424545Y460422I130J152D01*
G01X1424809D01*
G03X1424939Y460470I0J200D01*
G01X1424940Y460471D01*
G02X1425784Y460834I987J-1132D01*
G03X1425938Y460932I-19J199D01*
G01X1426101Y461212D01*
G03X1426111Y461395I-173J101D01*
G02X1425982Y462004I1373J609D01*
G37*
G36*
G01X511808D02*
G02X514812I1502J0D01*
G02X513453Y460509I-1502J0D01*
G03X513299Y460411I19J-199D01*
G01X513136Y460131D01*
G03X513126Y459948I173J-101D01*
G02X513255Y459339I-1373J-609D01*
G02X512885Y458352I-1501J0D01*
G01Y458351D01*
X512884D01*
G03X512836Y458221I152J-130D01*
G01Y457957D01*
G03X512884Y457827I200J0D01*
G01X512885Y457826D01*
G02Y455852I-1131J-987D01*
G01Y455851D01*
X512884D01*
G03X512836Y455721I152J-130D01*
G01Y455457D01*
G03X512884Y455327I200J0D01*
G01X512885Y455326D01*
G02X513255Y454339I-1131J-987D01*
G02X511753Y452837I-1502J0D01*
G02X510766Y453207I0J1501D01*
G01X510765D01*
Y453208D01*
G03X510635Y453256I-130J-152D01*
G01X510371D01*
G03X510241Y453208I0J-200D01*
G01X510240Y453207D01*
G02X509253Y452837I-987J1131D01*
G02X507751Y454339I0J1502D01*
G02X508121Y455326I1501J0D01*
G01Y455327D01*
X508122D01*
G03X508170Y455457I-152J130D01*
G01Y455721D01*
G03X508122Y455851I-200J0D01*
G01X508121Y455852D01*
G02Y457826I1131J987D01*
G01Y457827D01*
X508122D01*
G03X508170Y457957I-152J130D01*
G01Y458221D01*
G03X508122Y458351I-200J0D01*
G01X508121Y458352D01*
G02X507751Y459339I1131J987D01*
G02X509253Y460841I1502J0D01*
G02X510240Y460471I0J-1501D01*
G01X510241D01*
Y460470D01*
G03X510371Y460422I130J152D01*
G01X510635D01*
G03X510765Y460470I0J200D01*
G01X510766Y460471D01*
G02X511610Y460834I987J-1132D01*
G03X511764Y460932I-19J199D01*
G01X511927Y461212D01*
G03X511937Y461395I-173J101D01*
G02X511808Y462004I1373J609D01*
G37*
G36*
G01X1731357Y450937D02*
X1731671D01*
G03X1731829Y451014I0J200D01*
G02X1733014Y451593I1185J-923D01*
G02Y448589I0J-1502D01*
G02X1731829Y449168I0J1502D01*
G03X1731671Y449245I-158J-123D01*
G01X1731356D01*
G03X1731199Y449168I1J-200D01*
G02X1731127Y449083I-1181J928D01*
G01X1731097Y449050D01*
X1731071Y448966D01*
X1731119Y448619D01*
G03X1731209Y448477I198J26D01*
G02X1731906Y447209I-805J-1268D01*
G02X1730404Y445707I-1502J0D01*
G02X1729219Y446286I0J1502D01*
G03X1729061Y446363I-158J-123D01*
G01X1728747D01*
G03X1728589Y446286I0J-200D01*
G02X1727404Y445707I-1185J923D01*
G02X1725902Y447209I0J1502D01*
G01Y447229D01*
G03X1725821Y447392I-200J2D01*
G01X1725521Y447614D01*
X1725427Y447629D01*
X1725380Y447614D01*
G02X1724924Y447543I-456J1431D01*
G01X1724923D01*
G02X1726425Y449045I0J1502D01*
G01Y449025D01*
G03X1726506Y448862I200J-2D01*
G01X1726806Y448640D01*
X1726900Y448625D01*
X1726947Y448640D01*
G02X1727403Y448711I456J-1431D01*
G01X1727404D01*
G02X1728589Y448132I0J-1502D01*
G03X1728747Y448055I158J123D01*
G01X1729062D01*
G03X1729219Y448132I-1J200D01*
G02X1729291Y448217I1181J-928D01*
G01X1729321Y448250D01*
X1729347Y448334D01*
X1729299Y448681D01*
G03X1729209Y448823I-198J-26D01*
G02X1728512Y450091I805J1268D01*
G02X1730014Y451593I1502J0D01*
G02X1731199Y451014I0J-1502D01*
G03X1731357Y450937I158J123D01*
G37*
G36*
G01X1274270D02*
X1274584D01*
G03X1274742Y451014I0J200D01*
G02X1275927Y451593I1185J-923D01*
G02Y448589I0J-1502D01*
G02X1274742Y449168I0J1502D01*
G03X1274584Y449245I-158J-123D01*
G01X1274270D01*
G03X1274112Y449168I0J-200D01*
G02X1274001Y449041I-1185J923D01*
G01X1273968Y449008D01*
X1273939Y448918D01*
X1273997Y448553D01*
G03X1274100Y448408I197J31D01*
G02X1274899Y447081I-702J-1327D01*
G02X1273397Y445579I-1502J0D01*
G02X1272212Y446158I0J1502D01*
G03X1272054Y446235I-158J-123D01*
G01X1271740D01*
G03X1271582Y446158I0J-200D01*
G02X1270397Y445579I-1185J923D01*
G02X1268895Y447081I0J1502D01*
G02X1268902Y447226I1502J0D01*
G01X1268907Y447277D01*
X1268866Y447372D01*
X1268555Y447610D01*
G03X1268363Y447639I-122J-158D01*
G02X1267836Y447543I-528J1406D01*
G02X1269338Y449045I0J1502D01*
G02X1269331Y448900I-1502J0D01*
G01X1269326Y448849D01*
X1269367Y448754D01*
X1269678Y448516D01*
G03X1269870Y448487I122J158D01*
G02X1270397Y448583I528J-1406D01*
G02X1271582Y448004I0J-1502D01*
G03X1271740Y447927I158J123D01*
G01X1272054D01*
G03X1272212Y448004I0J200D01*
G02X1272323Y448131I1185J-923D01*
G01X1272356Y448164D01*
X1272385Y448254D01*
X1272327Y448619D01*
G03X1272224Y448764I-197J-31D01*
G02X1271425Y450091I702J1327D01*
G02X1272927Y451593I1502J0D01*
G02X1274112Y451014I0J-1502D01*
G03X1274270Y450937I158J123D01*
G37*
G36*
G01X360097D02*
X360411D01*
G03X360569Y451014I0J200D01*
G02X361754Y451593I1185J-923D01*
G02Y448589I0J-1502D01*
G02X360569Y449168I0J1502D01*
G03X360411Y449245I-158J-123D01*
G01X360096D01*
G03X359939Y449168I1J-200D01*
G02X359790Y449004I-1183J925D01*
G01X359755Y448970D01*
X359723Y448878D01*
X359782Y448504D01*
G03X359892Y448354I198J30D01*
G01X359893D01*
G02X360743Y447001I-652J-1353D01*
G02X359241Y445499I-1502J0D01*
G02X358056Y446078I0J1502D01*
G03X357898Y446155I-158J-123D01*
G01X357584D01*
G03X357426Y446078I0J-200D01*
G02X356241Y445499I-1185J923D01*
G02X354739Y447001I0J1502D01*
G02X354755Y447216I1502J-4D01*
G01Y447218D01*
G03X354681Y447402I-198J27D01*
G01X354368Y447651D01*
X354263Y447667D01*
X354213Y447647D01*
G02X353665Y447543I-549J1398D01*
G01X353663D01*
G02X355165Y449045I0J1502D01*
G02X355149Y448830I-1502J4D01*
G01Y448828D01*
G03X355223Y448644I198J-27D01*
G01X355536Y448395D01*
X355641Y448379D01*
X355691Y448399D01*
G02X356239Y448503I549J-1398D01*
G01X356241D01*
G02X357426Y447924I0J-1502D01*
G03X357584Y447847I158J123D01*
G01X357899D01*
G03X358056Y447924I-1J200D01*
G02X358205Y448088I1183J-925D01*
G01X358240Y448122D01*
X358272Y448214D01*
X358213Y448588D01*
G03X358103Y448738I-198J-30D01*
G01X358102D01*
G02X357252Y450091I652J1353D01*
G02X358754Y451593I1502J0D01*
G02X359939Y451014I0J-1502D01*
G03X360097Y450937I158J123D01*
G37*
G36*
G01X1794554Y443889D02*
G02X1793483Y443327I-1071J739D01*
G02Y445931I0J1302D01*
G02X1794554Y445369I0J-1301D01*
G03X1795212I329J228D01*
G02X1796283Y445931I1071J-739D01*
G02Y443327I0J-1302D01*
G02X1795212Y443889I0J1301D01*
G03X1794554I-329J-228D01*
G37*
G36*
G01X1337467D02*
G02X1336396Y443327I-1071J739D01*
G02Y445931I0J1302D01*
G02X1337467Y445369I0J-1301D01*
G03X1338125I329J228D01*
G02X1339196Y445931I1071J-739D01*
G02Y443327I0J-1302D01*
G02X1338125Y443889I0J1301D01*
G03X1337467I-329J-228D01*
G37*
G36*
G01X423294D02*
G02X422223Y443327I-1071J739D01*
G02Y445931I0J1302D01*
G02X423294Y445369I0J-1301D01*
G03X423952I329J228D01*
G02X425023Y445931I1071J-739D01*
G02Y443327I0J-1302D01*
G02X423952Y443889I0J1301D01*
G03X423294I-329J-228D01*
G37*
G36*
G01X1794554Y440346D02*
G02X1793483Y439784I-1071J739D01*
G02Y442388I0J1302D01*
G02X1794554Y441826I0J-1301D01*
G03X1795212I329J228D01*
G02X1796283Y442388I1071J-739D01*
G02Y439784I0J-1302D01*
G02X1795212Y440346I0J1301D01*
G03X1794554I-329J-228D01*
G37*
G36*
G01X1337467D02*
G02X1336396Y439784I-1071J739D01*
G02Y442388I0J1302D01*
G02X1337467Y441826I0J-1301D01*
G03X1338125I329J228D01*
G02X1339196Y442388I1071J-739D01*
G02Y439784I0J-1302D01*
G02X1338125Y440346I0J1301D01*
G03X1337467I-329J-228D01*
G37*
G36*
G01X423294D02*
G02X422223Y439784I-1071J739D01*
G02Y442388I0J1302D01*
G02X423294Y441826I0J-1301D01*
G03X423952I329J228D01*
G02X425023Y442388I1071J-739D01*
G02Y439784I0J-1302D01*
G02X423952Y440346I0J1301D01*
G03X423294I-329J-228D01*
G37*
G36*
G01X1794554Y436803D02*
G02X1793483Y436241I-1071J739D01*
G02Y438845I0J1302D01*
G02X1794554Y438283I0J-1301D01*
G03X1795212I329J228D01*
G02X1796283Y438845I1071J-739D01*
G02Y436241I0J-1302D01*
G02X1795212Y436803I0J1301D01*
G03X1794554I-329J-228D01*
G37*
G36*
G01X1337467D02*
G02X1336396Y436241I-1071J739D01*
G02Y438845I0J1302D01*
G02X1337467Y438283I0J-1301D01*
G03X1338125I329J228D01*
G02X1339196Y438845I1071J-739D01*
G02Y436241I0J-1302D01*
G02X1338125Y436803I0J1301D01*
G03X1337467I-329J-228D01*
G37*
G36*
G01X423294D02*
G02X422223Y436241I-1071J739D01*
G02Y438845I0J1302D01*
G02X423294Y438283I0J-1301D01*
G03X423952I329J228D01*
G02X425023Y438845I1071J-739D01*
G02Y436241I0J-1302D01*
G02X423952Y436803I0J1301D01*
G03X423294I-329J-228D01*
G37*
G36*
G01X1794554Y433259D02*
G02X1793483Y432697I-1071J739D01*
G02Y435301I0J1302D01*
G02X1794554Y434739I0J-1301D01*
G03X1795212I329J228D01*
G02X1796283Y435301I1071J-739D01*
G02Y432697I0J-1302D01*
G02X1795212Y433259I0J1301D01*
G03X1794554I-329J-228D01*
G37*
G36*
G01X1337467D02*
G02X1336396Y432697I-1071J739D01*
G02Y435301I0J1302D01*
G02X1337467Y434739I0J-1301D01*
G03X1338125I329J228D01*
G02X1339196Y435301I1071J-739D01*
G02Y432697I0J-1302D01*
G02X1338125Y433259I0J1301D01*
G03X1337467I-329J-228D01*
G37*
G36*
G01X423294D02*
G02X422223Y432697I-1071J739D01*
G02Y435301I0J1302D01*
G02X423294Y434739I0J-1301D01*
G03X423952I329J228D01*
G02X425023Y435301I1071J-739D01*
G02Y432697I0J-1302D01*
G02X423952Y433259I0J1301D01*
G03X423294I-329J-228D01*
G37*
G36*
G01X1751530Y410385D02*
X1751844D01*
G03X1752002Y410462I0J200D01*
G02X1753187Y411041I1185J-923D01*
G02X1754689Y409539I0J-1502D01*
G02X1754319Y408552I-1501J0D01*
G01Y408551D01*
X1754318D01*
G03X1754270Y408421I152J-130D01*
G01Y408157D01*
G03X1754318Y408027I200J0D01*
G01X1754319Y408026D01*
G02X1754689Y407039I-1131J-987D01*
G02X1753187Y405537I-1502J0D01*
G02X1752094Y406009I0J1502D01*
G01X1752093Y406010D01*
G03X1751928Y406071I-145J-138D01*
G01X1751613Y406040D01*
G03X1751463Y405946I20J-199D01*
G02X1750187Y405237I-1276J794D01*
G02X1748685Y406739I0J1502D01*
G02X1749170Y407845I1504J0D01*
G03X1749235Y407992I-135J148D01*
G01Y408286D01*
G03X1749170Y408433I-200J-1D01*
G02X1748685Y409539I1019J1106D01*
G02X1750187Y411041I1502J0D01*
G02X1751372Y410462I0J-1502D01*
G03X1751530Y410385I158J123D01*
G37*
G36*
G01X1294443D02*
X1294757D01*
G03X1294915Y410462I0J200D01*
G02X1296100Y411041I1185J-923D01*
G02X1297602Y409539I0J-1502D01*
G02X1297232Y408552I-1501J0D01*
G01Y408551D01*
X1297231D01*
G03X1297183Y408421I152J-130D01*
G01Y408157D01*
G03X1297231Y408027I200J0D01*
G01X1297232Y408026D01*
G02X1297602Y407039I-1131J-987D01*
G02X1296100Y405537I-1502J0D01*
G02X1295007Y406009I0J1502D01*
G01X1295006Y406010D01*
G03X1294841Y406071I-145J-138D01*
G01X1294526Y406040D01*
G03X1294376Y405946I20J-199D01*
G02X1293100Y405237I-1276J794D01*
G02X1291598Y406739I0J1502D01*
G02X1292083Y407845I1504J0D01*
G03X1292148Y407992I-135J148D01*
G01Y408286D01*
G03X1292083Y408433I-200J-1D01*
G02X1291598Y409539I1019J1106D01*
G02X1293100Y411041I1502J0D01*
G02X1294285Y410462I0J-1502D01*
G03X1294443Y410385I158J123D01*
G37*
G36*
G01X380270D02*
X380584D01*
G03X380742Y410462I0J200D01*
G02X381927Y411041I1185J-923D01*
G02X383429Y409539I0J-1502D01*
G02X383059Y408552I-1501J0D01*
G01Y408551D01*
X383058D01*
G03X383010Y408421I152J-130D01*
G01Y408157D01*
G03X383058Y408027I200J0D01*
G01X383059Y408026D01*
G02X383429Y407039I-1131J-987D01*
G02X381927Y405537I-1502J0D01*
G02X380834Y406009I0J1502D01*
G01X380833Y406010D01*
G03X380668Y406071I-145J-138D01*
G01X380353Y406040D01*
G03X380203Y405946I20J-199D01*
G02X378927Y405237I-1276J794D01*
G02X377425Y406739I0J1502D01*
G02X377910Y407845I1504J0D01*
G03X377975Y407992I-135J148D01*
G01Y408286D01*
G03X377910Y408433I-200J-1D01*
G02X377425Y409539I1019J1106D01*
G02X378927Y411041I1502J0D01*
G02X380112Y410462I0J-1502D01*
G03X380270Y410385I158J123D01*
G37*
G36*
G01X1461136Y390891D02*
G02X1459873Y390203I-1263J815D01*
G02Y393207I0J1502D01*
G02X1461194Y392419I0J-1501D01*
G03X1461882Y392393I352J190D01*
G02X1463145Y393081I1263J-815D01*
G02Y390077I0J-1502D01*
G02X1461824Y390865I0J1501D01*
G03X1461136Y390891I-352J-190D01*
G37*
G36*
G01X1639648Y378798D02*
G02X1638340Y378034I-1308J738D01*
G02Y381038I0J1502D01*
G02X1639618Y380325I0J-1502D01*
G03X1640307Y380338I341J210D01*
G02X1641615Y381102I1308J-738D01*
G02Y378098I0J-1502D01*
G02X1640337Y378811I0J1502D01*
G03X1639648Y378798I-341J-210D01*
G37*
G36*
G01X1764004Y379426D02*
G02X1763995Y379589I1493J164D01*
G01Y379591D01*
G02X1765497Y378089I1502J0D01*
G01X1765496D01*
G02X1765016Y378168I1J1502D01*
G03X1764490Y377746I-128J-379D01*
G02X1764499Y377583I-1493J-164D01*
G01Y377581D01*
G02X1762997Y379083I-1502J0D01*
G01X1762998D01*
G02X1763478Y379004I-1J-1502D01*
G03X1764004Y379426I128J379D01*
G37*
G36*
G01X1306917D02*
G02X1306908Y379589I1493J164D01*
G01Y379591D01*
G02X1308410Y378089I1502J0D01*
G01X1308409D01*
G02X1307929Y378168I1J1502D01*
G03X1307403Y377746I-128J-379D01*
G02X1307412Y377583I-1493J-164D01*
G01Y377581D01*
G02X1305910Y379083I-1502J0D01*
G01X1305911D01*
G02X1306391Y379004I-1J-1502D01*
G03X1306917Y379426I128J379D01*
G37*
G36*
G01X392744D02*
G02X392735Y379589I1493J164D01*
G01Y379591D01*
G02X394237Y378089I1502J0D01*
G01X394236D01*
G02X393756Y378168I1J1502D01*
G03X393230Y377746I-128J-379D01*
G02X393239Y377583I-1493J-164D01*
G01Y377581D01*
G02X391737Y379083I-1502J0D01*
G01X391738D01*
G02X392218Y379004I-1J-1502D01*
G03X392744Y379426I128J379D01*
G37*
G36*
G01X1330840Y358794D02*
G02X1330420Y359836I1083J1042D01*
G02X1333424I1502J0D01*
G02X1332280Y358377I-1502J0D01*
G03X1332087Y357712I96J-388D01*
G02X1332507Y356670I-1083J-1042D01*
G02X1329503I-1502J0D01*
G02X1330647Y358129I1502J0D01*
G03X1330840Y358794I-96J388D01*
G37*
G36*
G01X409382Y345528D02*
Y347733D01*
G02X409764Y348655I1306J-1D01*
G01X416488Y355379D01*
G03X416538Y355579I-141J142D01*
G01X416420Y355970D01*
X416338Y356043D01*
X416283Y356054D01*
G02X415072Y357528I292J1474D01*
G02X418076I1502J0D01*
G02X417824Y356696I-1502J1D01*
G03X417932Y356394I167J-111D01*
G03X417998Y356385I60J191D01*
G02X418036Y356386I53J-1306D01*
G01X425348D01*
G03X425437Y356407I0J200D01*
G01X425439Y356408D01*
G02X426138Y356581I700J-1329D01*
G02X427614Y355360I0J-1503D01*
G01X427621Y355320D01*
X427666Y355253D01*
X427975Y355050D01*
X428053Y355035D01*
X428093Y355044D01*
G02X428420Y355080I327J-1467D01*
G02Y352076I0J-1502D01*
G02X426944Y353297I0J1503D01*
G01X426937Y353337D01*
X426892Y353404D01*
X426583Y353607D01*
X426505Y353622D01*
X426465Y353613D01*
G02X426138Y353577I-327J1467D01*
G02X425441Y353749I1J1502D01*
G03X425437Y353751I-91J-178D01*
G01X425416Y353762D01*
X425372Y353772D01*
X418660D01*
G03X418518Y353713I0J-200D01*
G01X412053Y347249D01*
G03X411994Y347107I141J-142D01*
G01Y345528D01*
G03X412017Y345435I200J0D01*
G02X412190Y344736I-1329J-700D01*
G02X409186I-1502J0D01*
G02X409359Y345435I1502J-1D01*
G03X409382Y345528I-177J93D01*
G37*
G36*
G01X1665010Y352646D02*
G02X1663650Y351781I-1360J637D01*
G02Y354785I0J1502D01*
G02X1664825Y354219I0J-1503D01*
G03X1665500Y354298I313J249D01*
G02X1666860Y355163I1360J-637D01*
G02Y352159I0J-1502D01*
G02X1665685Y352725I0J1503D01*
G03X1665010Y352646I-313J-249D01*
G37*
G36*
G01X1572868Y343287D02*
G02X1571625Y342629I-1243J845D01*
G02Y345633I0J1502D01*
G02X1572870Y344971I0J-1502D01*
G03X1573532I331J224D01*
G02X1574775Y345629I1243J-845D01*
G02Y342625I0J-1502D01*
G02X1573530Y343287I0J1502D01*
G03X1572868I-331J-224D01*
G37*
G36*
G01X444775Y336906D02*
G02X443508Y336211I-1267J807D01*
G02Y339215I0J1502D01*
G02X444656Y338681I0J-1501D01*
G03X445299Y338724I306J258D01*
G02X446566Y339419I1267J-807D01*
G02Y336415I0J-1502D01*
G02X445418Y336949I0J1501D01*
G03X444775Y336906I-306J-258D01*
G37*
G36*
G01X1313754Y336510D02*
G02X1316758I1502J0D01*
G02X1316325Y335455I-1502J0D01*
G03X1316267Y335304I142J-141D01*
G01X1316285Y334968D01*
X1316323Y334893D01*
X1316355Y334866D01*
G02X1316899Y333709I-958J-1157D01*
G02X1315397Y332207I-1502J0D01*
G02X1313931Y333381I0J1502D01*
G01X1313919Y333433D01*
X1313847Y333512D01*
X1313463Y333631D01*
G03X1313267Y333585I-58J-191D01*
G02X1312240Y333179I-1027J1096D01*
G02X1313742Y334681I0J1502D01*
G02X1313740Y334599I-1502J-4D01*
G03X1314111Y334485I200J-11D01*
G02X1314328Y334764I1286J-776D01*
G03X1314386Y334915I-142J141D01*
G01X1314368Y335251D01*
X1314330Y335326D01*
X1314298Y335353D01*
G02X1313754Y336510I958J1157D01*
G37*
G36*
G01X411169Y333418D02*
G02X414173I1502J0D01*
G02X413740Y332363I-1502J0D01*
G03X413682Y332212I142J-141D01*
G01X413700Y331876D01*
X413738Y331801D01*
X413770Y331774D01*
G02X414314Y330617I-958J-1157D01*
G02X412812Y329115I-1502J0D01*
G02X411346Y330289I0J1502D01*
G01X411334Y330341D01*
X411262Y330420D01*
X410878Y330539D01*
G03X410682Y330493I-58J-191D01*
G02X409655Y330087I-1027J1096D01*
G02X411157Y331589I0J1502D01*
G02X411155Y331507I-1502J-4D01*
G03X411526Y331393I200J-11D01*
G02X411743Y331672I1286J-776D01*
G03X411801Y331823I-142J141D01*
G01X411783Y332159D01*
X411745Y332234D01*
X411713Y332261D01*
G02X411169Y333418I958J1157D01*
G37*
G36*
G01X1447979Y331612D02*
G02X1447232Y332910I754J1298D01*
G02X1450236I1502J0D01*
G02X1449747Y331801I-1502J0D01*
G03X1449815Y331159I269J-296D01*
G02X1450562Y329861I-754J-1298D01*
G02X1447558I-1502J0D01*
G02X1448047Y330970I1502J0D01*
G03X1447979Y331612I-269J296D01*
G37*
G36*
G01X1685415Y313706D02*
G02X1684837Y314890I924J1184D01*
G02X1687841I1502J0D01*
G02X1687086Y313587I-1502J0D01*
G03X1687039Y312924I199J-347D01*
G02X1687617Y311740I-924J-1184D01*
G02X1684613I-1502J0D01*
G02X1685368Y313043I1502J0D01*
G03X1685415Y313706I-199J347D01*
G37*
G36*
G01X771241D02*
G02X770663Y314890I924J1184D01*
G02X773667I1502J0D01*
G02X772912Y313587I-1502J0D01*
G03X772865Y312924I199J-347D01*
G02X773443Y311740I-924J-1184D01*
G02X770439I-1502J0D01*
G02X771194Y313043I1502J0D01*
G03X771241Y313706I-199J347D01*
G37*
G36*
G01X314155D02*
G02X313577Y314890I924J1184D01*
G02X316581I1502J0D01*
G02X315826Y313587I-1502J0D01*
G03X315779Y312924I199J-347D01*
G02X316357Y311740I-924J-1184D01*
G02X313353I-1502J0D01*
G02X314108Y313043I1502J0D01*
G03X314155Y313706I-199J347D01*
G37*
G36*
G01X808684Y312562D02*
G02X807987Y313830I805J1268D01*
G02X810991I1502J0D01*
G02X810276Y312551I-1501J0D01*
G03X810271Y311872I209J-341D01*
G02X810968Y310604I-805J-1268D01*
G02X807964I-1502J0D01*
G02X808679Y311883I1501J0D01*
G03X808684Y312562I-209J341D01*
G37*
G36*
G01X1505671Y245418D02*
G02X1505304Y245372I-369J1456D01*
G02X1506806Y246874I0J1502D01*
G02X1506690Y246295I-1503J0D01*
G03X1507157Y245753I369J-154D01*
G02X1507524Y245799I369J-1456D01*
G02X1506022Y244297I0J-1502D01*
G02X1506138Y244876I1503J0D01*
G03X1505671Y245418I-369J154D01*
G37*
G36*
G01X1403309D02*
G02X1402942Y245372I-369J1456D01*
G02X1404444Y246874I0J1502D01*
G02X1404328Y246295I-1503J0D01*
G03X1404795Y245753I369J-154D01*
G02X1405162Y245799I369J-1456D01*
G02X1403660Y244297I0J-1502D01*
G02X1403776Y244876I1503J0D01*
G03X1403309Y245418I-369J154D01*
G37*
G36*
G01X1048584D02*
G02X1048217Y245372I-369J1456D01*
G02X1049719Y246874I0J1502D01*
G02X1049603Y246295I-1503J0D01*
G03X1050070Y245753I369J-154D01*
G02X1050437Y245799I369J-1456D01*
G02X1048935Y244297I0J-1502D01*
G02X1049051Y244876I1503J0D01*
G03X1048584Y245418I-369J154D01*
G37*
G36*
G01X591498D02*
G02X591131Y245372I-369J1456D01*
G02X592633Y246874I0J1502D01*
G02X592517Y246295I-1503J0D01*
G03X592984Y245753I369J-154D01*
G02X593351Y245799I369J-1456D01*
G02X591849Y244297I0J-1502D01*
G02X591965Y244876I1503J0D01*
G03X591498Y245418I-369J154D01*
G37*
G36*
G01X489136D02*
G02X488769Y245372I-369J1456D01*
G02X490271Y246874I0J1502D01*
G02X490155Y246295I-1503J0D01*
G03X490622Y245753I369J-154D01*
G02X490989Y245799I369J-1456D01*
G02X489487Y244297I0J-1502D01*
G02X489603Y244876I1503J0D01*
G03X489136Y245418I-369J154D01*
G37*
G36*
G01X32049D02*
G02X31682Y245372I-369J1456D01*
G02X33184Y246874I0J1502D01*
G02X33068Y246295I-1503J0D01*
G03X33535Y245753I369J-154D01*
G02X33902Y245799I369J-1456D01*
G02X32400Y244297I0J-1502D01*
G02X32516Y244876I1503J0D01*
G03X32049Y245418I-369J154D01*
G37*
G36*
G01X1750107Y213197D02*
G02X1751609Y211695I0J-1502D01*
G02X1751137Y210602I-1502J0D01*
G01X1751136Y210601D01*
G03X1751075Y210436I138J-145D01*
G01X1751106Y210121D01*
G03X1751200Y209971I199J20D01*
G02X1751909Y208695I-794J-1276D01*
G02X1750407Y207193I-1502J0D01*
G02X1749301Y207678I0J1504D01*
G03X1749154Y207743I-148J-135D01*
G01X1748860D01*
G03X1748713Y207678I1J-200D01*
G02X1747607Y207193I-1106J1019D01*
G02X1746105Y208695I0J1502D01*
G02X1746684Y209880I1502J0D01*
G03X1746761Y210038I-123J158D01*
G01Y210352D01*
G03X1746684Y210510I-200J0D01*
G02X1746105Y211695I923J1185D01*
G02X1747607Y213197I1502J0D01*
G02X1748594Y212827I0J-1501D01*
G01X1748595D01*
Y212826D01*
G03X1748725Y212778I130J152D01*
G01X1748989D01*
G03X1749119Y212826I0J200D01*
G01X1749120Y212827D01*
G02X1750107Y213197I987J-1131D01*
G37*
G36*
G01X1647745D02*
G02X1649247Y211695I0J-1502D01*
G02X1648775Y210602I-1502J0D01*
G01X1648774Y210601D01*
G03X1648713Y210436I138J-145D01*
G01X1648744Y210121D01*
G03X1648838Y209971I199J20D01*
G02X1649547Y208695I-794J-1276D01*
G02X1648045Y207193I-1502J0D01*
G02X1646939Y207678I0J1504D01*
G03X1646792Y207743I-148J-135D01*
G01X1646498D01*
G03X1646351Y207678I1J-200D01*
G02X1645245Y207193I-1106J1019D01*
G02X1643743Y208695I0J1502D01*
G02X1644322Y209880I1502J0D01*
G03X1644399Y210038I-123J158D01*
G01Y210352D01*
G03X1644322Y210510I-200J0D01*
G02X1643743Y211695I923J1185D01*
G02X1645245Y213197I1502J0D01*
G02X1646232Y212827I0J-1501D01*
G01X1646233D01*
Y212826D01*
G03X1646363Y212778I130J152D01*
G01X1646627D01*
G03X1646757Y212826I0J200D01*
G01X1646758Y212827D01*
G02X1647745Y213197I987J-1131D01*
G37*
G36*
G01X1545383D02*
G02X1546885Y211695I0J-1502D01*
G02X1546413Y210602I-1502J0D01*
G01X1546412Y210601D01*
G03X1546351Y210436I138J-145D01*
G01X1546382Y210121D01*
G03X1546476Y209971I199J20D01*
G02X1547185Y208695I-794J-1276D01*
G02X1545683Y207193I-1502J0D01*
G02X1544577Y207678I0J1504D01*
G03X1544430Y207743I-148J-135D01*
G01X1544136D01*
G03X1543989Y207678I1J-200D01*
G02X1542883Y207193I-1106J1019D01*
G02X1541381Y208695I0J1502D01*
G02X1541960Y209880I1502J0D01*
G03X1542037Y210038I-123J158D01*
G01Y210352D01*
G03X1541960Y210510I-200J0D01*
G02X1541381Y211695I923J1185D01*
G02X1542883Y213197I1502J0D01*
G02X1543870Y212827I0J-1501D01*
G01X1543871D01*
Y212826D01*
G03X1544001Y212778I130J152D01*
G01X1544265D01*
G03X1544395Y212826I0J200D01*
G01X1544396Y212827D01*
G02X1545383Y213197I987J-1131D01*
G37*
G36*
G01X1443021D02*
G02X1444523Y211695I0J-1502D01*
G02X1444051Y210602I-1502J0D01*
G01X1444050Y210601D01*
G03X1443989Y210436I138J-145D01*
G01X1444020Y210121D01*
G03X1444114Y209971I199J20D01*
G02X1444823Y208695I-794J-1276D01*
G02X1443321Y207193I-1502J0D01*
G02X1442215Y207678I0J1504D01*
G03X1442068Y207743I-148J-135D01*
G01X1441774D01*
G03X1441627Y207678I1J-200D01*
G02X1440521Y207193I-1106J1019D01*
G02X1439019Y208695I0J1502D01*
G02X1439598Y209880I1502J0D01*
G03X1439675Y210038I-123J158D01*
G01Y210352D01*
G03X1439598Y210510I-200J0D01*
G02X1439019Y211695I923J1185D01*
G02X1440521Y213197I1502J0D01*
G02X1441508Y212827I0J-1501D01*
G01X1441509D01*
Y212826D01*
G03X1441639Y212778I130J152D01*
G01X1441903D01*
G03X1442033Y212826I0J200D01*
G01X1442034Y212827D01*
G02X1443021Y213197I987J-1131D01*
G37*
G36*
G01X1293020D02*
G02X1294522Y211695I0J-1502D01*
G02X1294050Y210602I-1502J0D01*
G01X1294049Y210601D01*
G03X1293988Y210436I138J-145D01*
G01X1294019Y210121D01*
G03X1294113Y209971I199J20D01*
G02X1294822Y208695I-794J-1276D01*
G02X1293320Y207193I-1502J0D01*
G02X1292214Y207678I0J1504D01*
G03X1292067Y207743I-148J-135D01*
G01X1291773D01*
G03X1291626Y207678I1J-200D01*
G02X1290520Y207193I-1106J1019D01*
G02X1289018Y208695I0J1502D01*
G02X1289597Y209880I1502J0D01*
G03X1289674Y210038I-123J158D01*
G01Y210352D01*
G03X1289597Y210510I-200J0D01*
G02X1289018Y211695I923J1185D01*
G02X1290520Y213197I1502J0D01*
G02X1291507Y212827I0J-1501D01*
G01X1291508D01*
Y212826D01*
G03X1291638Y212778I130J152D01*
G01X1291902D01*
G03X1292032Y212826I0J200D01*
G01X1292033Y212827D01*
G02X1293020Y213197I987J-1131D01*
G37*
G36*
G01X1190658D02*
G02X1192160Y211695I0J-1502D01*
G02X1191688Y210602I-1502J0D01*
G01X1191687Y210601D01*
G03X1191626Y210436I138J-145D01*
G01X1191657Y210121D01*
G03X1191751Y209971I199J20D01*
G02X1192460Y208695I-794J-1276D01*
G02X1190958Y207193I-1502J0D01*
G02X1189852Y207678I0J1504D01*
G03X1189705Y207743I-148J-135D01*
G01X1189411D01*
G03X1189264Y207678I1J-200D01*
G02X1188158Y207193I-1106J1019D01*
G02X1186656Y208695I0J1502D01*
G02X1187235Y209880I1502J0D01*
G03X1187312Y210038I-123J158D01*
G01Y210352D01*
G03X1187235Y210510I-200J0D01*
G02X1186656Y211695I923J1185D01*
G02X1188158Y213197I1502J0D01*
G02X1189145Y212827I0J-1501D01*
G01X1189146D01*
Y212826D01*
G03X1189276Y212778I130J152D01*
G01X1189540D01*
G03X1189670Y212826I0J200D01*
G01X1189671Y212827D01*
G02X1190658Y213197I987J-1131D01*
G37*
G36*
G01X1088296D02*
G02X1089798Y211695I0J-1502D01*
G02X1089326Y210602I-1502J0D01*
G01X1089325Y210601D01*
G03X1089264Y210436I138J-145D01*
G01X1089295Y210121D01*
G03X1089389Y209971I199J20D01*
G02X1090098Y208695I-794J-1276D01*
G02X1088596Y207193I-1502J0D01*
G02X1087490Y207678I0J1504D01*
G03X1087343Y207743I-148J-135D01*
G01X1087049D01*
G03X1086902Y207678I1J-200D01*
G02X1085796Y207193I-1106J1019D01*
G02X1084294Y208695I0J1502D01*
G02X1084873Y209880I1502J0D01*
G03X1084950Y210038I-123J158D01*
G01Y210352D01*
G03X1084873Y210510I-200J0D01*
G02X1084294Y211695I923J1185D01*
G02X1085796Y213197I1502J0D01*
G02X1086783Y212827I0J-1501D01*
G01X1086784D01*
Y212826D01*
G03X1086914Y212778I130J152D01*
G01X1087178D01*
G03X1087308Y212826I0J200D01*
G01X1087309Y212827D01*
G02X1088296Y213197I987J-1131D01*
G37*
G36*
G01X985934D02*
G02X987436Y211695I0J-1502D01*
G02X986964Y210602I-1502J0D01*
G01X986963Y210601D01*
G03X986902Y210436I138J-145D01*
G01X986933Y210121D01*
G03X987027Y209971I199J20D01*
G02X987736Y208695I-794J-1276D01*
G02X986234Y207193I-1502J0D01*
G02X985128Y207678I0J1504D01*
G03X984981Y207743I-148J-135D01*
G01X984687D01*
G03X984540Y207678I1J-200D01*
G02X983434Y207193I-1106J1019D01*
G02X981932Y208695I0J1502D01*
G02X982511Y209880I1502J0D01*
G03X982588Y210038I-123J158D01*
G01Y210352D01*
G03X982511Y210510I-200J0D01*
G02X981932Y211695I923J1185D01*
G02X983434Y213197I1502J0D01*
G02X984421Y212827I0J-1501D01*
G01X984422D01*
Y212826D01*
G03X984552Y212778I130J152D01*
G01X984816D01*
G03X984946Y212826I0J200D01*
G01X984947Y212827D01*
G02X985934Y213197I987J-1131D01*
G37*
G36*
G01X835934D02*
G02X837436Y211695I0J-1502D01*
G02X836964Y210602I-1502J0D01*
G01X836963Y210601D01*
G03X836902Y210436I138J-145D01*
G01X836933Y210121D01*
G03X837027Y209971I199J20D01*
G02X837736Y208695I-794J-1276D01*
G02X836234Y207193I-1502J0D01*
G02X835128Y207678I0J1504D01*
G03X834981Y207743I-148J-135D01*
G01X834687D01*
G03X834540Y207678I1J-200D01*
G02X833434Y207193I-1106J1019D01*
G02X831932Y208695I0J1502D01*
G02X832511Y209880I1502J0D01*
G03X832588Y210038I-123J158D01*
G01Y210352D01*
G03X832511Y210510I-200J0D01*
G02X831932Y211695I923J1185D01*
G02X833434Y213197I1502J0D01*
G02X834421Y212827I0J-1501D01*
G01X834422D01*
Y212826D01*
G03X834552Y212778I130J152D01*
G01X834816D01*
G03X834946Y212826I0J200D01*
G01X834947Y212827D01*
G02X835934Y213197I987J-1131D01*
G37*
G36*
G01X733572D02*
G02X735074Y211695I0J-1502D01*
G02X734602Y210602I-1502J0D01*
G01X734601Y210601D01*
G03X734540Y210436I138J-145D01*
G01X734571Y210121D01*
G03X734665Y209971I199J20D01*
G02X735374Y208695I-794J-1276D01*
G02X733872Y207193I-1502J0D01*
G02X732766Y207678I0J1504D01*
G03X732619Y207743I-148J-135D01*
G01X732325D01*
G03X732178Y207678I1J-200D01*
G02X731072Y207193I-1106J1019D01*
G02X729570Y208695I0J1502D01*
G02X730149Y209880I1502J0D01*
G03X730226Y210038I-123J158D01*
G01Y210352D01*
G03X730149Y210510I-200J0D01*
G02X729570Y211695I923J1185D01*
G02X731072Y213197I1502J0D01*
G02X732059Y212827I0J-1501D01*
G01X732060D01*
Y212826D01*
G03X732190Y212778I130J152D01*
G01X732454D01*
G03X732584Y212826I0J200D01*
G01X732585Y212827D01*
G02X733572Y213197I987J-1131D01*
G37*
G36*
G01X631210D02*
G02X632712Y211695I0J-1502D01*
G02X632240Y210602I-1502J0D01*
G01X632239Y210601D01*
G03X632178Y210436I138J-145D01*
G01X632209Y210121D01*
G03X632303Y209971I199J20D01*
G02X633012Y208695I-794J-1276D01*
G02X631510Y207193I-1502J0D01*
G02X630404Y207678I0J1504D01*
G03X630257Y207743I-148J-135D01*
G01X629963D01*
G03X629816Y207678I1J-200D01*
G02X628710Y207193I-1106J1019D01*
G02X627208Y208695I0J1502D01*
G02X627787Y209880I1502J0D01*
G03X627864Y210038I-123J158D01*
G01Y210352D01*
G03X627787Y210510I-200J0D01*
G02X627208Y211695I923J1185D01*
G02X628710Y213197I1502J0D01*
G02X629697Y212827I0J-1501D01*
G01X629698D01*
Y212826D01*
G03X629828Y212778I130J152D01*
G01X630092D01*
G03X630222Y212826I0J200D01*
G01X630223Y212827D01*
G02X631210Y213197I987J-1131D01*
G37*
G36*
G01X528848D02*
G02X530350Y211695I0J-1502D01*
G02X529878Y210602I-1502J0D01*
G01X529877Y210601D01*
G03X529816Y210436I138J-145D01*
G01X529847Y210121D01*
G03X529941Y209971I199J20D01*
G02X530650Y208695I-794J-1276D01*
G02X529148Y207193I-1502J0D01*
G02X528042Y207678I0J1504D01*
G03X527895Y207743I-148J-135D01*
G01X527601D01*
G03X527454Y207678I1J-200D01*
G02X526348Y207193I-1106J1019D01*
G02X524846Y208695I0J1502D01*
G02X525425Y209880I1502J0D01*
G03X525502Y210038I-123J158D01*
G01Y210352D01*
G03X525425Y210510I-200J0D01*
G02X524846Y211695I923J1185D01*
G02X526348Y213197I1502J0D01*
G02X527335Y212827I0J-1501D01*
G01X527336D01*
Y212826D01*
G03X527466Y212778I130J152D01*
G01X527730D01*
G03X527860Y212826I0J200D01*
G01X527861Y212827D01*
G02X528848Y213197I987J-1131D01*
G37*
G36*
G01X378847D02*
G02X380349Y211695I0J-1502D01*
G02X379877Y210602I-1502J0D01*
G01X379876Y210601D01*
G03X379815Y210436I138J-145D01*
G01X379846Y210121D01*
G03X379940Y209971I199J20D01*
G02X380649Y208695I-794J-1276D01*
G02X379147Y207193I-1502J0D01*
G02X378041Y207678I0J1504D01*
G03X377894Y207743I-148J-135D01*
G01X377600D01*
G03X377453Y207678I1J-200D01*
G02X376347Y207193I-1106J1019D01*
G02X374845Y208695I0J1502D01*
G02X375424Y209880I1502J0D01*
G03X375501Y210038I-123J158D01*
G01Y210352D01*
G03X375424Y210510I-200J0D01*
G02X374845Y211695I923J1185D01*
G02X376347Y213197I1502J0D01*
G02X377334Y212827I0J-1501D01*
G01X377335D01*
Y212826D01*
G03X377465Y212778I130J152D01*
G01X377729D01*
G03X377859Y212826I0J200D01*
G01X377860Y212827D01*
G02X378847Y213197I987J-1131D01*
G37*
G36*
G01X276485D02*
G02X277987Y211695I0J-1502D01*
G02X277515Y210602I-1502J0D01*
G01X277514Y210601D01*
G03X277453Y210436I138J-145D01*
G01X277484Y210121D01*
G03X277578Y209971I199J20D01*
G02X278287Y208695I-794J-1276D01*
G02X276785Y207193I-1502J0D01*
G02X275679Y207678I0J1504D01*
G03X275532Y207743I-148J-135D01*
G01X275238D01*
G03X275091Y207678I1J-200D01*
G02X273985Y207193I-1106J1019D01*
G02X272483Y208695I0J1502D01*
G02X273062Y209880I1502J0D01*
G03X273139Y210038I-123J158D01*
G01Y210352D01*
G03X273062Y210510I-200J0D01*
G02X272483Y211695I923J1185D01*
G02X273985Y213197I1502J0D01*
G02X274972Y212827I0J-1501D01*
G01X274973D01*
Y212826D01*
G03X275103Y212778I130J152D01*
G01X275367D01*
G03X275497Y212826I0J200D01*
G01X275498Y212827D01*
G02X276485Y213197I987J-1131D01*
G37*
G36*
G01X174123D02*
G02X175625Y211695I0J-1502D01*
G02X175153Y210602I-1502J0D01*
G01X175152Y210601D01*
G03X175091Y210436I138J-145D01*
G01X175122Y210121D01*
G03X175216Y209971I199J20D01*
G02X175925Y208695I-794J-1276D01*
G02X174423Y207193I-1502J0D01*
G02X173317Y207678I0J1504D01*
G03X173170Y207743I-148J-135D01*
G01X172876D01*
G03X172729Y207678I1J-200D01*
G02X171623Y207193I-1106J1019D01*
G02X170121Y208695I0J1502D01*
G02X170700Y209880I1502J0D01*
G03X170777Y210038I-123J158D01*
G01Y210352D01*
G03X170700Y210510I-200J0D01*
G02X170121Y211695I923J1185D01*
G02X171623Y213197I1502J0D01*
G02X172610Y212827I0J-1501D01*
G01X172611D01*
Y212826D01*
G03X172741Y212778I130J152D01*
G01X173005D01*
G03X173135Y212826I0J200D01*
G01X173136Y212827D01*
G02X174123Y213197I987J-1131D01*
G37*
G36*
G01X71761D02*
G02X73263Y211695I0J-1502D01*
G02X72791Y210602I-1502J0D01*
G01X72790Y210601D01*
G03X72729Y210436I138J-145D01*
G01X72760Y210121D01*
G03X72854Y209971I199J20D01*
G02X73563Y208695I-794J-1276D01*
G02X72061Y207193I-1502J0D01*
G02X70955Y207678I0J1504D01*
G03X70808Y207743I-148J-135D01*
G01X70514D01*
G03X70367Y207678I1J-200D01*
G02X69261Y207193I-1106J1019D01*
G02X67759Y208695I0J1502D01*
G02X68338Y209880I1502J0D01*
G03X68415Y210038I-123J158D01*
G01Y210352D01*
G03X68338Y210510I-200J0D01*
G02X67759Y211695I923J1185D01*
G02X69261Y213197I1502J0D01*
G02X70248Y212827I0J-1501D01*
G01X70249D01*
Y212826D01*
G03X70379Y212778I130J152D01*
G01X70643D01*
G03X70773Y212826I0J200D01*
G01X70774Y212827D01*
G02X71761Y213197I987J-1131D01*
G37*
G36*
G01X1706429Y201748D02*
G02X1707931Y203250I1502J0D01*
G02X1709024Y202778I0J-1502D01*
G01X1709025Y202777D01*
G03X1709190Y202716I145J138D01*
G01X1709505Y202747D01*
G03X1709655Y202841I-20J199D01*
G02X1710931Y203550I1276J-794D01*
G02X1712433Y202048I0J-1502D01*
G02X1711948Y200942I-1504J0D01*
G03X1711883Y200795I135J-148D01*
G01Y200501D01*
G03X1711948Y200354I200J1D01*
G02X1712433Y199248I-1019J-1106D01*
G02X1710931Y197746I-1502J0D01*
G02X1709746Y198325I0J1502D01*
G03X1709588Y198402I-158J-123D01*
G01X1709274D01*
G03X1709116Y198325I0J-200D01*
G02X1707931Y197746I-1185J923D01*
G02X1706429Y199248I0J1502D01*
G02X1706799Y200235I1501J0D01*
G01Y200236D01*
X1706800D01*
G03X1706848Y200366I-152J130D01*
G01Y200630D01*
G03X1706800Y200760I-200J0D01*
G01X1706799Y200761D01*
G02X1706429Y201748I1131J987D01*
G37*
G36*
G01X1604067D02*
G02X1605569Y203250I1502J0D01*
G02X1606662Y202778I0J-1502D01*
G01X1606663Y202777D01*
G03X1606828Y202716I145J138D01*
G01X1607143Y202747D01*
G03X1607293Y202841I-20J199D01*
G02X1608569Y203550I1276J-794D01*
G02X1610071Y202048I0J-1502D01*
G02X1609586Y200942I-1504J0D01*
G03X1609521Y200795I135J-148D01*
G01Y200501D01*
G03X1609586Y200354I200J1D01*
G02X1610071Y199248I-1019J-1106D01*
G02X1608569Y197746I-1502J0D01*
G02X1607384Y198325I0J1502D01*
G03X1607226Y198402I-158J-123D01*
G01X1606912D01*
G03X1606754Y198325I0J-200D01*
G02X1605569Y197746I-1185J923D01*
G02X1604067Y199248I0J1502D01*
G02X1604437Y200235I1501J0D01*
G01Y200236D01*
X1604438D01*
G03X1604486Y200366I-152J130D01*
G01Y200630D01*
G03X1604438Y200760I-200J0D01*
G01X1604437Y200761D01*
G02X1604067Y201748I1131J987D01*
G37*
G36*
G01X1501705D02*
G02X1503207Y203250I1502J0D01*
G02X1504300Y202778I0J-1502D01*
G01X1504301Y202777D01*
G03X1504466Y202716I145J138D01*
G01X1504781Y202747D01*
G03X1504931Y202841I-20J199D01*
G02X1506207Y203550I1276J-794D01*
G02X1507709Y202048I0J-1502D01*
G02X1507224Y200942I-1504J0D01*
G03X1507159Y200795I135J-148D01*
G01Y200501D01*
G03X1507224Y200354I200J1D01*
G02X1507709Y199248I-1019J-1106D01*
G02X1506207Y197746I-1502J0D01*
G02X1505022Y198325I0J1502D01*
G03X1504864Y198402I-158J-123D01*
G01X1504550D01*
G03X1504392Y198325I0J-200D01*
G02X1503207Y197746I-1185J923D01*
G02X1501705Y199248I0J1502D01*
G02X1502075Y200235I1501J0D01*
G01Y200236D01*
X1502076D01*
G03X1502124Y200366I-152J130D01*
G01Y200630D01*
G03X1502076Y200760I-200J0D01*
G01X1502075Y200761D01*
G02X1501705Y201748I1131J987D01*
G37*
G36*
G01X1249342D02*
G02X1250844Y203250I1502J0D01*
G02X1251937Y202778I0J-1502D01*
G01X1251938Y202777D01*
G03X1252103Y202716I145J138D01*
G01X1252418Y202747D01*
G03X1252568Y202841I-20J199D01*
G02X1253844Y203550I1276J-794D01*
G02X1255346Y202048I0J-1502D01*
G02X1254861Y200942I-1504J0D01*
G03X1254796Y200795I135J-148D01*
G01Y200501D01*
G03X1254861Y200354I200J1D01*
G02X1255346Y199248I-1019J-1106D01*
G02X1253844Y197746I-1502J0D01*
G02X1252659Y198325I0J1502D01*
G03X1252501Y198402I-158J-123D01*
G01X1252187D01*
G03X1252029Y198325I0J-200D01*
G02X1250844Y197746I-1185J923D01*
G02X1249342Y199248I0J1502D01*
G02X1249712Y200235I1501J0D01*
G01Y200236D01*
X1249713D01*
G03X1249761Y200366I-152J130D01*
G01Y200630D01*
G03X1249713Y200760I-200J0D01*
G01X1249712Y200761D01*
G02X1249342Y201748I1131J987D01*
G37*
G36*
G01X1146980D02*
G02X1148482Y203250I1502J0D01*
G02X1149575Y202778I0J-1502D01*
G01X1149576Y202777D01*
G03X1149741Y202716I145J138D01*
G01X1150056Y202747D01*
G03X1150206Y202841I-20J199D01*
G02X1151482Y203550I1276J-794D01*
G02X1152984Y202048I0J-1502D01*
G02X1152499Y200942I-1504J0D01*
G03X1152434Y200795I135J-148D01*
G01Y200501D01*
G03X1152499Y200354I200J1D01*
G02X1152984Y199248I-1019J-1106D01*
G02X1151482Y197746I-1502J0D01*
G02X1150297Y198325I0J1502D01*
G03X1150139Y198402I-158J-123D01*
G01X1149825D01*
G03X1149667Y198325I0J-200D01*
G02X1148482Y197746I-1185J923D01*
G02X1146980Y199248I0J1502D01*
G02X1147350Y200235I1501J0D01*
G01Y200236D01*
X1147351D01*
G03X1147399Y200366I-152J130D01*
G01Y200630D01*
G03X1147351Y200760I-200J0D01*
G01X1147350Y200761D01*
G02X1146980Y201748I1131J987D01*
G37*
G36*
G01X1044618D02*
G02X1046120Y203250I1502J0D01*
G02X1047213Y202778I0J-1502D01*
G01X1047214Y202777D01*
G03X1047379Y202716I145J138D01*
G01X1047694Y202747D01*
G03X1047844Y202841I-20J199D01*
G02X1049120Y203550I1276J-794D01*
G02X1050622Y202048I0J-1502D01*
G02X1050137Y200942I-1504J0D01*
G03X1050072Y200795I135J-148D01*
G01Y200501D01*
G03X1050137Y200354I200J1D01*
G02X1050622Y199248I-1019J-1106D01*
G02X1049120Y197746I-1502J0D01*
G02X1047935Y198325I0J1502D01*
G03X1047777Y198402I-158J-123D01*
G01X1047463D01*
G03X1047305Y198325I0J-200D01*
G02X1046120Y197746I-1185J923D01*
G02X1044618Y199248I0J1502D01*
G02X1044988Y200235I1501J0D01*
G01Y200236D01*
X1044989D01*
G03X1045037Y200366I-152J130D01*
G01Y200630D01*
G03X1044989Y200760I-200J0D01*
G01X1044988Y200761D01*
G02X1044618Y201748I1131J987D01*
G37*
G36*
G01X792256D02*
G02X793758Y203250I1502J0D01*
G02X794851Y202778I0J-1502D01*
G01X794852Y202777D01*
G03X795017Y202716I145J138D01*
G01X795332Y202747D01*
G03X795482Y202841I-20J199D01*
G02X796758Y203550I1276J-794D01*
G02X798260Y202048I0J-1502D01*
G02X797775Y200942I-1504J0D01*
G03X797710Y200795I135J-148D01*
G01Y200501D01*
G03X797775Y200354I200J1D01*
G02X798260Y199248I-1019J-1106D01*
G02X796758Y197746I-1502J0D01*
G02X795573Y198325I0J1502D01*
G03X795415Y198402I-158J-123D01*
G01X795101D01*
G03X794943Y198325I0J-200D01*
G02X793758Y197746I-1185J923D01*
G02X792256Y199248I0J1502D01*
G02X792626Y200235I1501J0D01*
G01Y200236D01*
X792627D01*
G03X792675Y200366I-152J130D01*
G01Y200630D01*
G03X792627Y200760I-200J0D01*
G01X792626Y200761D01*
G02X792256Y201748I1131J987D01*
G37*
G36*
G01X689894D02*
G02X691396Y203250I1502J0D01*
G02X692489Y202778I0J-1502D01*
G01X692490Y202777D01*
G03X692655Y202716I145J138D01*
G01X692970Y202747D01*
G03X693120Y202841I-20J199D01*
G02X694396Y203550I1276J-794D01*
G02X695898Y202048I0J-1502D01*
G02X695413Y200942I-1504J0D01*
G03X695348Y200795I135J-148D01*
G01Y200501D01*
G03X695413Y200354I200J1D01*
G02X695898Y199248I-1019J-1106D01*
G02X694396Y197746I-1502J0D01*
G02X693211Y198325I0J1502D01*
G03X693053Y198402I-158J-123D01*
G01X692739D01*
G03X692581Y198325I0J-200D01*
G02X691396Y197746I-1185J923D01*
G02X689894Y199248I0J1502D01*
G02X690264Y200235I1501J0D01*
G01Y200236D01*
X690265D01*
G03X690313Y200366I-152J130D01*
G01Y200630D01*
G03X690265Y200760I-200J0D01*
G01X690264Y200761D01*
G02X689894Y201748I1131J987D01*
G37*
G36*
G01X587532D02*
G02X589034Y203250I1502J0D01*
G02X590127Y202778I0J-1502D01*
G01X590128Y202777D01*
G03X590293Y202716I145J138D01*
G01X590608Y202747D01*
G03X590758Y202841I-20J199D01*
G02X592034Y203550I1276J-794D01*
G02X593536Y202048I0J-1502D01*
G02X593051Y200942I-1504J0D01*
G03X592986Y200795I135J-148D01*
G01Y200501D01*
G03X593051Y200354I200J1D01*
G02X593536Y199248I-1019J-1106D01*
G02X592034Y197746I-1502J0D01*
G02X590849Y198325I0J1502D01*
G03X590691Y198402I-158J-123D01*
G01X590377D01*
G03X590219Y198325I0J-200D01*
G02X589034Y197746I-1185J923D01*
G02X587532Y199248I0J1502D01*
G02X587902Y200235I1501J0D01*
G01Y200236D01*
X587903D01*
G03X587951Y200366I-152J130D01*
G01Y200630D01*
G03X587903Y200760I-200J0D01*
G01X587902Y200761D01*
G02X587532Y201748I1131J987D01*
G37*
G36*
G01X335169D02*
G02X336671Y203250I1502J0D01*
G02X337764Y202778I0J-1502D01*
G01X337765Y202777D01*
G03X337930Y202716I145J138D01*
G01X338245Y202747D01*
G03X338395Y202841I-20J199D01*
G02X339671Y203550I1276J-794D01*
G02X341173Y202048I0J-1502D01*
G02X340688Y200942I-1504J0D01*
G03X340623Y200795I135J-148D01*
G01Y200501D01*
G03X340688Y200354I200J1D01*
G02X341173Y199248I-1019J-1106D01*
G02X339671Y197746I-1502J0D01*
G02X338486Y198325I0J1502D01*
G03X338328Y198402I-158J-123D01*
G01X338014D01*
G03X337856Y198325I0J-200D01*
G02X336671Y197746I-1185J923D01*
G02X335169Y199248I0J1502D01*
G02X335539Y200235I1501J0D01*
G01Y200236D01*
X335540D01*
G03X335588Y200366I-152J130D01*
G01Y200630D01*
G03X335540Y200760I-200J0D01*
G01X335539Y200761D01*
G02X335169Y201748I1131J987D01*
G37*
G36*
G01X232807D02*
G02X234309Y203250I1502J0D01*
G02X235402Y202778I0J-1502D01*
G01X235403Y202777D01*
G03X235568Y202716I145J138D01*
G01X235883Y202747D01*
G03X236033Y202841I-20J199D01*
G02X237309Y203550I1276J-794D01*
G02X238811Y202048I0J-1502D01*
G02X238326Y200942I-1504J0D01*
G03X238261Y200795I135J-148D01*
G01Y200501D01*
G03X238326Y200354I200J1D01*
G02X238811Y199248I-1019J-1106D01*
G02X237309Y197746I-1502J0D01*
G02X236124Y198325I0J1502D01*
G03X235966Y198402I-158J-123D01*
G01X235652D01*
G03X235494Y198325I0J-200D01*
G02X234309Y197746I-1185J923D01*
G02X232807Y199248I0J1502D01*
G02X233177Y200235I1501J0D01*
G01Y200236D01*
X233178D01*
G03X233226Y200366I-152J130D01*
G01Y200630D01*
G03X233178Y200760I-200J0D01*
G01X233177Y200761D01*
G02X232807Y201748I1131J987D01*
G37*
G36*
G01X130445D02*
G02X131947Y203250I1502J0D01*
G02X133040Y202778I0J-1502D01*
G01X133041Y202777D01*
G03X133206Y202716I145J138D01*
G01X133521Y202747D01*
G03X133671Y202841I-20J199D01*
G02X134947Y203550I1276J-794D01*
G02X136449Y202048I0J-1502D01*
G02X135964Y200942I-1504J0D01*
G03X135899Y200795I135J-148D01*
G01Y200501D01*
G03X135964Y200354I200J1D01*
G02X136449Y199248I-1019J-1106D01*
G02X134947Y197746I-1502J0D01*
G02X133762Y198325I0J1502D01*
G03X133604Y198402I-158J-123D01*
G01X133290D01*
G03X133132Y198325I0J-200D01*
G02X131947Y197746I-1185J923D01*
G02X130445Y199248I0J1502D01*
G02X130815Y200235I1501J0D01*
G01Y200236D01*
X130816D01*
G03X130864Y200366I-152J130D01*
G01Y200630D01*
G03X130816Y200760I-200J0D01*
G01X130815Y200761D01*
G02X130445Y201748I1131J987D01*
G37*
G36*
G01X1011641Y201149D02*
G02X1013116Y202366I1475J-285D01*
G02Y199362I0J-1502D01*
G02X1012360Y199566I0J1503D01*
G03X1011766Y199297I-202J-345D01*
G02X1010291Y198080I-1475J285D01*
G02Y201084I0J1502D01*
G02X1011047Y200880I0J-1503D01*
G03X1011641Y201149I202J345D01*
G37*
G36*
G01X297622Y190988D02*
G02Y193992I0J1502D01*
G02X298790Y193434I0J-1501D01*
G01X298822Y193394D01*
X298917Y193356D01*
X299304Y193400D01*
G03X299461Y193512I-23J199D01*
G02X300814Y194361I1353J-654D01*
G02X302316Y192859I0J-1502D01*
G02X302174Y192222I-1502J0D01*
G01X302150Y192171D01*
X302163Y192059D01*
X302452Y191688D01*
X302556Y191649D01*
X302612Y191660D01*
G02X302894Y191687I284J-1475D01*
G01X302897D01*
G02X301395Y190185I0J-1502D01*
G02X301537Y190822I1502J0D01*
G01X301561Y190873D01*
X301548Y190985D01*
X301259Y191356D01*
X301155Y191395D01*
X301099Y191384D01*
G02X300817Y191357I-284J1475D01*
G01X300814D01*
G02X299646Y191915I0J1501D01*
G01X299614Y191955D01*
X299519Y191993D01*
X299132Y191949D01*
G03X298975Y191837I23J-199D01*
G02X297622Y190988I-1353J654D01*
G37*
G36*
G01X1749627Y184221D02*
G02X1751129Y185723I1502J0D01*
G02X1752249Y185222I0J-1502D01*
G01X1752274Y185193D01*
X1752344Y185159D01*
X1752658Y185134D01*
G03X1752799Y185178I15J199D01*
G02X1753746Y185514I947J-1167D01*
G02X1755248Y184012I0J-1502D01*
G02X1754955Y183121I-1501J0D01*
G01Y183120D01*
X1754932Y183089D01*
X1754913Y183013D01*
X1754965Y182657D01*
X1755006Y182588D01*
X1755037Y182565D01*
G02X1755363Y182226I-906J-1198D01*
G03X1755502Y182142I164J114D01*
G01X1755838Y182099D01*
X1755919Y182123D01*
X1755951Y182151D01*
G02X1756927Y182511I976J-1143D01*
G02Y179507I0J-1502D01*
G02X1755696Y180149I0J1501D01*
G03X1755557Y180233I-164J-114D01*
G01X1755221Y180276D01*
X1755140Y180252D01*
X1755108Y180224D01*
G02X1754132Y179864I-976J1143D01*
G02X1752849Y180585I0J1502D01*
G01X1752822Y180629D01*
X1752734Y180680D01*
X1752292Y180688D01*
X1752202Y180641D01*
X1752174Y180598D01*
G02X1750921Y179924I-1253J828D01*
G02X1749419Y181426I0J1502D01*
G02X1749990Y182605I1503J0D01*
G01X1750023Y182631D01*
X1750062Y182705D01*
X1750091Y183084D01*
X1750063Y183162D01*
X1750034Y183193D01*
G02X1749627Y184221I1095J1028D01*
G37*
G36*
G01X1647265D02*
G02X1648767Y185723I1502J0D01*
G02X1649887Y185222I0J-1502D01*
G01X1649912Y185193D01*
X1649982Y185159D01*
X1650296Y185134D01*
G03X1650437Y185178I15J199D01*
G02X1651384Y185514I947J-1167D01*
G02X1652886Y184012I0J-1502D01*
G02X1652593Y183121I-1501J0D01*
G01Y183120D01*
X1652570Y183089D01*
X1652551Y183013D01*
X1652603Y182657D01*
X1652644Y182588D01*
X1652675Y182565D01*
G02X1653001Y182226I-906J-1198D01*
G03X1653140Y182142I164J114D01*
G01X1653476Y182099D01*
X1653557Y182123D01*
X1653589Y182151D01*
G02X1654565Y182511I976J-1143D01*
G02Y179507I0J-1502D01*
G02X1653334Y180149I0J1501D01*
G03X1653195Y180233I-164J-114D01*
G01X1652859Y180276D01*
X1652778Y180252D01*
X1652746Y180224D01*
G02X1651770Y179864I-976J1143D01*
G02X1650487Y180585I0J1502D01*
G01X1650460Y180629D01*
X1650372Y180680D01*
X1649930Y180688D01*
X1649840Y180641D01*
X1649812Y180598D01*
G02X1648559Y179924I-1253J828D01*
G02X1647057Y181426I0J1502D01*
G02X1647628Y182605I1503J0D01*
G01X1647661Y182631D01*
X1647700Y182705D01*
X1647729Y183084D01*
X1647701Y183162D01*
X1647672Y183193D01*
G02X1647265Y184221I1095J1028D01*
G37*
G36*
G01X1544903D02*
G02X1546405Y185723I1502J0D01*
G02X1547525Y185222I0J-1502D01*
G01X1547550Y185193D01*
X1547620Y185159D01*
X1547934Y185134D01*
G03X1548075Y185178I15J199D01*
G02X1549022Y185514I947J-1167D01*
G02X1550524Y184012I0J-1502D01*
G02X1550231Y183121I-1501J0D01*
G01Y183120D01*
X1550208Y183089D01*
X1550189Y183013D01*
X1550241Y182657D01*
X1550282Y182588D01*
X1550313Y182565D01*
G02X1550639Y182226I-906J-1198D01*
G03X1550778Y182142I164J114D01*
G01X1551114Y182099D01*
X1551195Y182123D01*
X1551227Y182151D01*
G02X1552203Y182511I976J-1143D01*
G02Y179507I0J-1502D01*
G02X1550972Y180149I0J1501D01*
G03X1550833Y180233I-164J-114D01*
G01X1550497Y180276D01*
X1550416Y180252D01*
X1550384Y180224D01*
G02X1549408Y179864I-976J1143D01*
G02X1548125Y180585I0J1502D01*
G01X1548098Y180629D01*
X1548010Y180680D01*
X1547568Y180688D01*
X1547478Y180641D01*
X1547450Y180598D01*
G02X1546197Y179924I-1253J828D01*
G02X1544695Y181426I0J1502D01*
G02X1545266Y182605I1503J0D01*
G01X1545299Y182631D01*
X1545338Y182705D01*
X1545367Y183084D01*
X1545339Y183162D01*
X1545310Y183193D01*
G02X1544903Y184221I1095J1028D01*
G37*
G36*
G01X1442541D02*
G02X1444043Y185723I1502J0D01*
G02X1445163Y185222I0J-1502D01*
G01X1445188Y185193D01*
X1445258Y185159D01*
X1445572Y185134D01*
G03X1445713Y185178I15J199D01*
G02X1446660Y185514I947J-1167D01*
G02X1448162Y184012I0J-1502D01*
G02X1447869Y183121I-1501J0D01*
G01Y183120D01*
X1447846Y183089D01*
X1447827Y183013D01*
X1447879Y182657D01*
X1447920Y182588D01*
X1447951Y182565D01*
G02X1448277Y182226I-906J-1198D01*
G03X1448416Y182142I164J114D01*
G01X1448752Y182099D01*
X1448833Y182123D01*
X1448865Y182151D01*
G02X1449841Y182511I976J-1143D01*
G02Y179507I0J-1502D01*
G02X1448610Y180149I0J1501D01*
G03X1448471Y180233I-164J-114D01*
G01X1448135Y180276D01*
X1448054Y180252D01*
X1448022Y180224D01*
G02X1447046Y179864I-976J1143D01*
G02X1445763Y180585I0J1502D01*
G01X1445736Y180629D01*
X1445648Y180680D01*
X1445206Y180688D01*
X1445116Y180641D01*
X1445088Y180598D01*
G02X1443835Y179924I-1253J828D01*
G02X1442333Y181426I0J1502D01*
G02X1442904Y182605I1503J0D01*
G01X1442937Y182631D01*
X1442976Y182705D01*
X1443005Y183084D01*
X1442977Y183162D01*
X1442948Y183193D01*
G02X1442541Y184221I1095J1028D01*
G37*
G36*
G01X1292540D02*
G02X1294042Y185723I1502J0D01*
G02X1295162Y185222I0J-1502D01*
G01X1295187Y185193D01*
X1295257Y185159D01*
X1295571Y185134D01*
G03X1295712Y185178I15J199D01*
G02X1296659Y185514I947J-1167D01*
G02X1298161Y184012I0J-1502D01*
G02X1297868Y183121I-1501J0D01*
G01Y183120D01*
X1297845Y183089D01*
X1297826Y183013D01*
X1297878Y182657D01*
X1297919Y182588D01*
X1297950Y182565D01*
G02X1298276Y182226I-906J-1198D01*
G03X1298415Y182142I164J114D01*
G01X1298751Y182099D01*
X1298832Y182123D01*
X1298864Y182151D01*
G02X1299840Y182511I976J-1143D01*
G02Y179507I0J-1502D01*
G02X1298609Y180149I0J1501D01*
G03X1298470Y180233I-164J-114D01*
G01X1298134Y180276D01*
X1298053Y180252D01*
X1298021Y180224D01*
G02X1297045Y179864I-976J1143D01*
G02X1295762Y180585I0J1502D01*
G01X1295735Y180629D01*
X1295647Y180680D01*
X1295205Y180688D01*
X1295115Y180641D01*
X1295087Y180598D01*
G02X1293834Y179924I-1253J828D01*
G02X1292332Y181426I0J1502D01*
G02X1292903Y182605I1503J0D01*
G01X1292936Y182631D01*
X1292975Y182705D01*
X1293004Y183084D01*
X1292976Y183162D01*
X1292947Y183193D01*
G02X1292540Y184221I1095J1028D01*
G37*
G36*
G01X1190178D02*
G02X1191680Y185723I1502J0D01*
G02X1192800Y185222I0J-1502D01*
G01X1192825Y185193D01*
X1192895Y185159D01*
X1193209Y185134D01*
G03X1193350Y185178I15J199D01*
G02X1194297Y185514I947J-1167D01*
G02X1195799Y184012I0J-1502D01*
G02X1195506Y183121I-1501J0D01*
G01Y183120D01*
X1195483Y183089D01*
X1195464Y183013D01*
X1195516Y182657D01*
X1195557Y182588D01*
X1195588Y182565D01*
G02X1195914Y182226I-906J-1198D01*
G03X1196053Y182142I164J114D01*
G01X1196389Y182099D01*
X1196470Y182123D01*
X1196502Y182151D01*
G02X1197478Y182511I976J-1143D01*
G02Y179507I0J-1502D01*
G02X1196247Y180149I0J1501D01*
G03X1196108Y180233I-164J-114D01*
G01X1195772Y180276D01*
X1195691Y180252D01*
X1195659Y180224D01*
G02X1194683Y179864I-976J1143D01*
G02X1193400Y180585I0J1502D01*
G01X1193373Y180629D01*
X1193285Y180680D01*
X1192843Y180688D01*
X1192753Y180641D01*
X1192725Y180598D01*
G02X1191472Y179924I-1253J828D01*
G02X1189970Y181426I0J1502D01*
G02X1190541Y182605I1503J0D01*
G01X1190574Y182631D01*
X1190613Y182705D01*
X1190642Y183084D01*
X1190614Y183162D01*
X1190585Y183193D01*
G02X1190178Y184221I1095J1028D01*
G37*
G36*
G01X1087816D02*
G02X1089318Y185723I1502J0D01*
G02X1090438Y185222I0J-1502D01*
G01X1090463Y185193D01*
X1090533Y185159D01*
X1090847Y185134D01*
G03X1090988Y185178I15J199D01*
G02X1091935Y185514I947J-1167D01*
G02X1093437Y184012I0J-1502D01*
G02X1093144Y183121I-1501J0D01*
G01Y183120D01*
X1093121Y183089D01*
X1093102Y183013D01*
X1093154Y182657D01*
X1093195Y182588D01*
X1093226Y182565D01*
G02X1093552Y182226I-906J-1198D01*
G03X1093691Y182142I164J114D01*
G01X1094027Y182099D01*
X1094108Y182123D01*
X1094140Y182151D01*
G02X1095116Y182511I976J-1143D01*
G02Y179507I0J-1502D01*
G02X1093885Y180149I0J1501D01*
G03X1093746Y180233I-164J-114D01*
G01X1093410Y180276D01*
X1093329Y180252D01*
X1093297Y180224D01*
G02X1092321Y179864I-976J1143D01*
G02X1091038Y180585I0J1502D01*
G01X1091011Y180629D01*
X1090923Y180680D01*
X1090481Y180688D01*
X1090391Y180641D01*
X1090363Y180598D01*
G02X1089110Y179924I-1253J828D01*
G02X1087608Y181426I0J1502D01*
G02X1088179Y182605I1503J0D01*
G01X1088212Y182631D01*
X1088251Y182705D01*
X1088280Y183084D01*
X1088252Y183162D01*
X1088223Y183193D01*
G02X1087816Y184221I1095J1028D01*
G37*
G36*
G01X985454D02*
G02X986956Y185723I1502J0D01*
G02X988076Y185222I0J-1502D01*
G01X988101Y185193D01*
X988171Y185159D01*
X988485Y185134D01*
G03X988626Y185178I15J199D01*
G02X989573Y185514I947J-1167D01*
G02X991075Y184012I0J-1502D01*
G02X990782Y183121I-1501J0D01*
G01Y183120D01*
X990759Y183089D01*
X990740Y183013D01*
X990792Y182657D01*
X990833Y182588D01*
X990864Y182565D01*
G02X991190Y182226I-906J-1198D01*
G03X991329Y182142I164J114D01*
G01X991665Y182099D01*
X991746Y182123D01*
X991778Y182151D01*
G02X992754Y182511I976J-1143D01*
G02Y179507I0J-1502D01*
G02X991523Y180149I0J1501D01*
G03X991384Y180233I-164J-114D01*
G01X991048Y180276D01*
X990967Y180252D01*
X990935Y180224D01*
G02X989959Y179864I-976J1143D01*
G02X988676Y180585I0J1502D01*
G01X988649Y180629D01*
X988561Y180680D01*
X988119Y180688D01*
X988029Y180641D01*
X988001Y180598D01*
G02X986748Y179924I-1253J828D01*
G02X985246Y181426I0J1502D01*
G02X985817Y182605I1503J0D01*
G01X985850Y182631D01*
X985889Y182705D01*
X985918Y183084D01*
X985890Y183162D01*
X985861Y183193D01*
G02X985454Y184221I1095J1028D01*
G37*
G36*
G01X835454D02*
G02X836956Y185723I1502J0D01*
G02X838076Y185222I0J-1502D01*
G01X838101Y185193D01*
X838171Y185159D01*
X838485Y185134D01*
G03X838626Y185178I15J199D01*
G02X839573Y185514I947J-1167D01*
G02X841075Y184012I0J-1502D01*
G02X840782Y183121I-1501J0D01*
G01Y183120D01*
X840759Y183089D01*
X840740Y183013D01*
X840792Y182657D01*
X840833Y182588D01*
X840864Y182565D01*
G02X841190Y182226I-906J-1198D01*
G03X841329Y182142I164J114D01*
G01X841665Y182099D01*
X841746Y182123D01*
X841778Y182151D01*
G02X842754Y182511I976J-1143D01*
G02Y179507I0J-1502D01*
G02X841523Y180149I0J1501D01*
G03X841384Y180233I-164J-114D01*
G01X841048Y180276D01*
X840967Y180252D01*
X840935Y180224D01*
G02X839959Y179864I-976J1143D01*
G02X838676Y180585I0J1502D01*
G01X838649Y180629D01*
X838561Y180680D01*
X838119Y180688D01*
X838029Y180641D01*
X838001Y180598D01*
G02X836748Y179924I-1253J828D01*
G02X835246Y181426I0J1502D01*
G02X835817Y182605I1503J0D01*
G01X835850Y182631D01*
X835889Y182705D01*
X835918Y183084D01*
X835890Y183162D01*
X835861Y183193D01*
G02X835454Y184221I1095J1028D01*
G37*
G36*
G01X733092D02*
G02X734594Y185723I1502J0D01*
G02X735714Y185222I0J-1502D01*
G01X735739Y185193D01*
X735809Y185159D01*
X736123Y185134D01*
G03X736264Y185178I15J199D01*
G02X737211Y185514I947J-1167D01*
G02X738713Y184012I0J-1502D01*
G02X738420Y183121I-1501J0D01*
G01Y183120D01*
X738397Y183089D01*
X738378Y183013D01*
X738430Y182657D01*
X738471Y182588D01*
X738502Y182565D01*
G02X738828Y182226I-906J-1198D01*
G03X738967Y182142I164J114D01*
G01X739303Y182099D01*
X739384Y182123D01*
X739416Y182151D01*
G02X740392Y182511I976J-1143D01*
G02Y179507I0J-1502D01*
G02X739161Y180149I0J1501D01*
G03X739022Y180233I-164J-114D01*
G01X738686Y180276D01*
X738605Y180252D01*
X738573Y180224D01*
G02X737597Y179864I-976J1143D01*
G02X736314Y180585I0J1502D01*
G01X736287Y180629D01*
X736199Y180680D01*
X735757Y180688D01*
X735667Y180641D01*
X735639Y180598D01*
G02X734386Y179924I-1253J828D01*
G02X732884Y181426I0J1502D01*
G02X733455Y182605I1503J0D01*
G01X733488Y182631D01*
X733527Y182705D01*
X733556Y183084D01*
X733528Y183162D01*
X733499Y183193D01*
G02X733092Y184221I1095J1028D01*
G37*
G36*
G01X630730D02*
G02X632232Y185723I1502J0D01*
G02X633352Y185222I0J-1502D01*
G01X633377Y185193D01*
X633447Y185159D01*
X633761Y185134D01*
G03X633902Y185178I15J199D01*
G02X634849Y185514I947J-1167D01*
G02X636351Y184012I0J-1502D01*
G02X636058Y183121I-1501J0D01*
G01Y183120D01*
X636035Y183089D01*
X636016Y183013D01*
X636068Y182657D01*
X636109Y182588D01*
X636140Y182565D01*
G02X636466Y182226I-906J-1198D01*
G03X636605Y182142I164J114D01*
G01X636941Y182099D01*
X637022Y182123D01*
X637054Y182151D01*
G02X638030Y182511I976J-1143D01*
G02Y179507I0J-1502D01*
G02X636799Y180149I0J1501D01*
G03X636660Y180233I-164J-114D01*
G01X636324Y180276D01*
X636243Y180252D01*
X636211Y180224D01*
G02X635235Y179864I-976J1143D01*
G02X633952Y180585I0J1502D01*
G01X633925Y180629D01*
X633837Y180680D01*
X633395Y180688D01*
X633305Y180641D01*
X633277Y180598D01*
G02X632024Y179924I-1253J828D01*
G02X630522Y181426I0J1502D01*
G02X631093Y182605I1503J0D01*
G01X631126Y182631D01*
X631165Y182705D01*
X631194Y183084D01*
X631166Y183162D01*
X631137Y183193D01*
G02X630730Y184221I1095J1028D01*
G37*
G36*
G01X528368D02*
G02X529870Y185723I1502J0D01*
G02X530990Y185222I0J-1502D01*
G01X531015Y185193D01*
X531085Y185159D01*
X531399Y185134D01*
G03X531540Y185178I15J199D01*
G02X532487Y185514I947J-1167D01*
G02X533989Y184012I0J-1502D01*
G02X533696Y183121I-1501J0D01*
G01Y183120D01*
X533673Y183089D01*
X533654Y183013D01*
X533706Y182657D01*
X533747Y182588D01*
X533778Y182565D01*
G02X534104Y182226I-906J-1198D01*
G03X534243Y182142I164J114D01*
G01X534579Y182099D01*
X534660Y182123D01*
X534692Y182151D01*
G02X535668Y182511I976J-1143D01*
G02Y179507I0J-1502D01*
G02X534437Y180149I0J1501D01*
G03X534298Y180233I-164J-114D01*
G01X533962Y180276D01*
X533881Y180252D01*
X533849Y180224D01*
G02X532873Y179864I-976J1143D01*
G02X531590Y180585I0J1502D01*
G01X531563Y180629D01*
X531475Y180680D01*
X531033Y180688D01*
X530943Y180641D01*
X530915Y180598D01*
G02X529662Y179924I-1253J828D01*
G02X528160Y181426I0J1502D01*
G02X528731Y182605I1503J0D01*
G01X528764Y182631D01*
X528803Y182705D01*
X528832Y183084D01*
X528804Y183162D01*
X528775Y183193D01*
G02X528368Y184221I1095J1028D01*
G37*
G36*
G01X378367D02*
G02X379869Y185723I1502J0D01*
G02X380989Y185222I0J-1502D01*
G01X381014Y185193D01*
X381084Y185159D01*
X381398Y185134D01*
G03X381539Y185178I15J199D01*
G02X382486Y185514I947J-1167D01*
G02X383988Y184012I0J-1502D01*
G02X383695Y183121I-1501J0D01*
G01Y183120D01*
X383672Y183089D01*
X383653Y183013D01*
X383705Y182657D01*
X383746Y182588D01*
X383777Y182565D01*
G02X384103Y182226I-906J-1198D01*
G03X384242Y182142I164J114D01*
G01X384578Y182099D01*
X384659Y182123D01*
X384691Y182151D01*
G02X385667Y182511I976J-1143D01*
G02Y179507I0J-1502D01*
G02X384436Y180149I0J1501D01*
G03X384297Y180233I-164J-114D01*
G01X383961Y180276D01*
X383880Y180252D01*
X383848Y180224D01*
G02X382872Y179864I-976J1143D01*
G02X381589Y180585I0J1502D01*
G01X381562Y180629D01*
X381474Y180680D01*
X381032Y180688D01*
X380942Y180641D01*
X380914Y180598D01*
G02X379661Y179924I-1253J828D01*
G02X378159Y181426I0J1502D01*
G02X378730Y182605I1503J0D01*
G01X378763Y182631D01*
X378802Y182705D01*
X378831Y183084D01*
X378803Y183162D01*
X378774Y183193D01*
G02X378367Y184221I1095J1028D01*
G37*
G36*
G01X276005D02*
G02X277507Y185723I1502J0D01*
G02X278627Y185222I0J-1502D01*
G01X278652Y185193D01*
X278722Y185159D01*
X279036Y185134D01*
G03X279177Y185178I15J199D01*
G02X280124Y185514I947J-1167D01*
G02X281626Y184012I0J-1502D01*
G02X281333Y183121I-1501J0D01*
G01Y183120D01*
X281310Y183089D01*
X281291Y183013D01*
X281343Y182657D01*
X281384Y182588D01*
X281415Y182565D01*
G02X281741Y182226I-906J-1198D01*
G03X281880Y182142I164J114D01*
G01X282216Y182099D01*
X282297Y182123D01*
X282329Y182151D01*
G02X283305Y182511I976J-1143D01*
G02Y179507I0J-1502D01*
G02X282074Y180149I0J1501D01*
G03X281935Y180233I-164J-114D01*
G01X281599Y180276D01*
X281518Y180252D01*
X281486Y180224D01*
G02X280510Y179864I-976J1143D01*
G02X279227Y180585I0J1502D01*
G01X279200Y180629D01*
X279112Y180680D01*
X278670Y180688D01*
X278580Y180641D01*
X278552Y180598D01*
G02X277299Y179924I-1253J828D01*
G02X275797Y181426I0J1502D01*
G02X276368Y182605I1503J0D01*
G01X276401Y182631D01*
X276440Y182705D01*
X276469Y183084D01*
X276441Y183162D01*
X276412Y183193D01*
G02X276005Y184221I1095J1028D01*
G37*
G36*
G01X173643D02*
G02X175145Y185723I1502J0D01*
G02X176265Y185222I0J-1502D01*
G01X176290Y185193D01*
X176360Y185159D01*
X176674Y185134D01*
G03X176815Y185178I15J199D01*
G02X177762Y185514I947J-1167D01*
G02X179264Y184012I0J-1502D01*
G02X178971Y183121I-1501J0D01*
G01Y183120D01*
X178948Y183089D01*
X178929Y183013D01*
X178981Y182657D01*
X179022Y182588D01*
X179053Y182565D01*
G02X179379Y182226I-906J-1198D01*
G03X179518Y182142I164J114D01*
G01X179854Y182099D01*
X179935Y182123D01*
X179967Y182151D01*
G02X180943Y182511I976J-1143D01*
G02Y179507I0J-1502D01*
G02X179712Y180149I0J1501D01*
G03X179573Y180233I-164J-114D01*
G01X179237Y180276D01*
X179156Y180252D01*
X179124Y180224D01*
G02X178148Y179864I-976J1143D01*
G02X176865Y180585I0J1502D01*
G01X176838Y180629D01*
X176750Y180680D01*
X176308Y180688D01*
X176218Y180641D01*
X176190Y180598D01*
G02X174937Y179924I-1253J828D01*
G02X173435Y181426I0J1502D01*
G02X174006Y182605I1503J0D01*
G01X174039Y182631D01*
X174078Y182705D01*
X174107Y183084D01*
X174079Y183162D01*
X174050Y183193D01*
G02X173643Y184221I1095J1028D01*
G37*
G36*
G01X71281D02*
G02X72783Y185723I1502J0D01*
G02X73903Y185222I0J-1502D01*
G01X73928Y185193D01*
X73998Y185159D01*
X74312Y185134D01*
G03X74453Y185178I15J199D01*
G02X75400Y185514I947J-1167D01*
G02X76902Y184012I0J-1502D01*
G02X76609Y183121I-1501J0D01*
G01Y183120D01*
X76586Y183089D01*
X76567Y183013D01*
X76619Y182657D01*
X76660Y182588D01*
X76691Y182565D01*
G02X77017Y182226I-906J-1198D01*
G03X77156Y182142I164J114D01*
G01X77492Y182099D01*
X77573Y182123D01*
X77605Y182151D01*
G02X78581Y182511I976J-1143D01*
G02Y179507I0J-1502D01*
G02X77350Y180149I0J1501D01*
G03X77211Y180233I-164J-114D01*
G01X76875Y180276D01*
X76794Y180252D01*
X76762Y180224D01*
G02X75786Y179864I-976J1143D01*
G02X74503Y180585I0J1502D01*
G01X74476Y180629D01*
X74388Y180680D01*
X73946Y180688D01*
X73856Y180641D01*
X73828Y180598D01*
G02X72575Y179924I-1253J828D01*
G02X71073Y181426I0J1502D01*
G02X71644Y182605I1503J0D01*
G01X71677Y182631D01*
X71716Y182705D01*
X71745Y183084D01*
X71717Y183162D01*
X71688Y183193D01*
G02X71281Y184221I1095J1028D01*
G37*
G36*
G01X1672089Y151610D02*
G02X1670795Y150871I-1294J763D01*
G02Y153875I0J1502D01*
G02X1671989Y153285I0J-1503D01*
G03X1672651Y153325I318J243D01*
G02X1673945Y154064I1294J-763D01*
G02Y151060I0J-1502D01*
G02X1672751Y151650I0J1503D01*
G03X1672089Y151610I-318J-243D01*
G37*
G36*
G01X1569727D02*
G02X1568433Y150871I-1294J763D01*
G02Y153875I0J1502D01*
G02X1569627Y153285I0J-1503D01*
G03X1570289Y153325I318J243D01*
G02X1571583Y154064I1294J-763D01*
G02Y151060I0J-1502D01*
G02X1570389Y151650I0J1503D01*
G03X1569727Y151610I-318J-243D01*
G37*
G36*
G01X1467365D02*
G02X1466071Y150871I-1294J763D01*
G02Y153875I0J1502D01*
G02X1467265Y153285I0J-1503D01*
G03X1467927Y153325I318J243D01*
G02X1469221Y154064I1294J-763D01*
G02Y151060I0J-1502D01*
G02X1468027Y151650I0J1503D01*
G03X1467365Y151610I-318J-243D01*
G37*
G36*
G01X1365003D02*
G02X1363709Y150871I-1294J763D01*
G02Y153875I0J1502D01*
G02X1364903Y153285I0J-1503D01*
G03X1365565Y153325I318J243D01*
G02X1366859Y154064I1294J-763D01*
G02Y151060I0J-1502D01*
G02X1365665Y151650I0J1503D01*
G03X1365003Y151610I-318J-243D01*
G37*
G36*
G01X1215002D02*
G02X1213708Y150871I-1294J763D01*
G02Y153875I0J1502D01*
G02X1214902Y153285I0J-1503D01*
G03X1215564Y153325I318J243D01*
G02X1216858Y154064I1294J-763D01*
G02Y151060I0J-1502D01*
G02X1215664Y151650I0J1503D01*
G03X1215002Y151610I-318J-243D01*
G37*
G36*
G01X1112640D02*
G02X1111346Y150871I-1294J763D01*
G02Y153875I0J1502D01*
G02X1112540Y153285I0J-1503D01*
G03X1113202Y153325I318J243D01*
G02X1114496Y154064I1294J-763D01*
G02Y151060I0J-1502D01*
G02X1113302Y151650I0J1503D01*
G03X1112640Y151610I-318J-243D01*
G37*
G36*
G01X1010278D02*
G02X1008984Y150871I-1294J763D01*
G02Y153875I0J1502D01*
G02X1010178Y153285I0J-1503D01*
G03X1010840Y153325I318J243D01*
G02X1012134Y154064I1294J-763D01*
G02Y151060I0J-1502D01*
G02X1010940Y151650I0J1503D01*
G03X1010278Y151610I-318J-243D01*
G37*
G36*
G01X907916D02*
G02X906622Y150871I-1294J763D01*
G02Y153875I0J1502D01*
G02X907816Y153285I0J-1503D01*
G03X908478Y153325I318J243D01*
G02X909772Y154064I1294J-763D01*
G02Y151060I0J-1502D01*
G02X908578Y151650I0J1503D01*
G03X907916Y151610I-318J-243D01*
G37*
G36*
G01X757916D02*
G02X756622Y150871I-1294J763D01*
G02Y153875I0J1502D01*
G02X757816Y153285I0J-1503D01*
G03X758478Y153325I318J243D01*
G02X759772Y154064I1294J-763D01*
G02Y151060I0J-1502D01*
G02X758578Y151650I0J1503D01*
G03X757916Y151610I-318J-243D01*
G37*
G36*
G01X655554D02*
G02X654260Y150871I-1294J763D01*
G02Y153875I0J1502D01*
G02X655454Y153285I0J-1503D01*
G03X656116Y153325I318J243D01*
G02X657410Y154064I1294J-763D01*
G02Y151060I0J-1502D01*
G02X656216Y151650I0J1503D01*
G03X655554Y151610I-318J-243D01*
G37*
G36*
G01X553192D02*
G02X551898Y150871I-1294J763D01*
G02Y153875I0J1502D01*
G02X553092Y153285I0J-1503D01*
G03X553754Y153325I318J243D01*
G02X555048Y154064I1294J-763D01*
G02Y151060I0J-1502D01*
G02X553854Y151650I0J1503D01*
G03X553192Y151610I-318J-243D01*
G37*
G36*
G01X450830D02*
G02X449536Y150871I-1294J763D01*
G02Y153875I0J1502D01*
G02X450730Y153285I0J-1503D01*
G03X451392Y153325I318J243D01*
G02X452686Y154064I1294J-763D01*
G02Y151060I0J-1502D01*
G02X451492Y151650I0J1503D01*
G03X450830Y151610I-318J-243D01*
G37*
G36*
G01X300829D02*
G02X299535Y150871I-1294J763D01*
G02Y153875I0J1502D01*
G02X300729Y153285I0J-1503D01*
G03X301391Y153325I318J243D01*
G02X302685Y154064I1294J-763D01*
G02Y151060I0J-1502D01*
G02X301491Y151650I0J1503D01*
G03X300829Y151610I-318J-243D01*
G37*
G36*
G01X198467D02*
G02X197173Y150871I-1294J763D01*
G02Y153875I0J1502D01*
G02X198367Y153285I0J-1503D01*
G03X199029Y153325I318J243D01*
G02X200323Y154064I1294J-763D01*
G02Y151060I0J-1502D01*
G02X199129Y151650I0J1503D01*
G03X198467Y151610I-318J-243D01*
G37*
G36*
G01X96105D02*
G02X94811Y150871I-1294J763D01*
G02Y153875I0J1502D01*
G02X96005Y153285I0J-1503D01*
G03X96667Y153325I318J243D01*
G02X97961Y154064I1294J-763D01*
G02Y151060I0J-1502D01*
G02X96767Y151650I0J1503D01*
G03X96105Y151610I-318J-243D01*
G37*
G36*
G01X91100Y143321D02*
G02X90835Y144172I1237J852D01*
G02X93839I1502J0D01*
G02X92696Y142713I-1503J0D01*
G03X92461Y142098I95J-389D01*
G02X92726Y141247I-1237J-852D01*
G02X89722I-1502J0D01*
G02X90865Y142706I1503J0D01*
G03X91100Y143321I-95J389D01*
G37*
G36*
G01X1450830Y33256D02*
G02X1449685Y32726I-1145J972D01*
G02Y35730I0J1502D01*
G02X1450935Y35061I0J-1502D01*
G03X1451572Y35024I332J222D01*
G02X1452717Y35554I1145J-972D01*
G02Y32550I0J-1502D01*
G02X1451467Y33219I0J1502D01*
G03X1450830Y33256I-332J-222D01*
G37*
G36*
G01X1329461Y32041D02*
G02X1328003Y30901I-1458J362D01*
G02Y33905I0J1502D01*
G01X1328004D01*
G02X1328970Y33553I0J-1502D01*
G03X1329615Y33762I257J306D01*
G02X1331073Y34902I1458J-362D01*
G02Y31898I0J-1502D01*
G01X1331072D01*
G02X1330106Y32250I0J1502D01*
G03X1329461Y32041I-257J-306D01*
G37*
G36*
G01X415318Y32063D02*
G02X413904Y31067I-1414J506D01*
G02Y34071I0J1502D01*
G02X414856Y33731I0J-1503D01*
G03X415486Y33906I253J310D01*
G02X416900Y34902I1414J-506D01*
G02Y31898I0J-1502D01*
G02X415948Y32238I0J1503D01*
G03X415318Y32063I-253J-310D01*
G37*
G36*
G01X477506Y662491D02*
G02X477124Y661569I-1306J1D01*
G01X473075Y657521D01*
G03X473016Y657379I141J-142D01*
G01Y636104D01*
G03X473140Y635919I200J0D01*
G01X473196Y635895D01*
X473314Y635919D01*
X481256Y643861D01*
G03X481303Y644069I-142J141D01*
G01X481162Y644465D01*
X481071Y644536D01*
X481014Y644542D01*
G02X479663Y646036I151J1494D01*
G02X481165Y647538I1502J0D01*
G02X482659Y646187I0J-1502D01*
G01X482665Y646130D01*
X482736Y646039D01*
X483132Y645898D01*
G03X483340Y645945I67J189D01*
G01X489004Y651609D01*
G02X490634Y652284I1630J-1631D01*
G01X501341D01*
G03X501483Y652343I0J200D01*
G01X513121Y663982D01*
G03X513180Y664124I-141J142D01*
G01Y666711D01*
G02X513856Y668342I2307J-1D01*
G01X515787Y670273D01*
G02X517417Y670948I1630J-1631D01*
G01X519804D01*
G02X521434Y670273I0J-2306D01*
G01X523499Y668208D01*
G02X523570Y668133I-1639J-1623D01*
G03X523785Y668080I147J135D01*
G01X523879Y668113D01*
G03X524012Y668301I-67J188D01*
G01Y676338D01*
G03X523884Y676525I-200J0D01*
G01X523535Y676659D01*
G03X523315Y676606I-71J-187D01*
G02X522200Y676111I-1115J1008D01*
G02Y679115I0J1502D01*
G02X523315Y678620I0J-1503D01*
G03X523535Y678567I149J134D01*
G01X523884Y678701D01*
G03X524012Y678888I-72J187D01*
G01Y681917D01*
G03X523953Y682059I-200J0D01*
G01X521175Y684836D01*
G03X521095Y684885I-142J-141D01*
G01X521094D01*
G02X520038Y686319I446J1434D01*
G02X521540Y687821I1502J0D01*
G02X522974Y686766I0J-1502D01*
G01Y686764D01*
G03X523023Y686684I190J62D01*
G01X526242Y683465D01*
G02X526624Y682543I-924J-923D01*
G01Y666654D01*
G02X526589Y666351I-1306J-3D01*
G01X526578Y666307D01*
X526598Y666217D01*
X526821Y665934D01*
G03X526978Y665858I157J124D01*
G01X529664D01*
G02Y662254I0J-1802D01*
G01X526264D01*
G02X524614Y663331I0J1802D01*
G01Y663332D01*
G03X524468Y663447I-183J-82D01*
G01X524143Y663509D01*
G03X523964Y663453I-37J-197D01*
G01X506559Y646047D01*
G03X506516Y645830I142J-141D01*
G01X506539Y645773D01*
X506640Y645706D01*
X519564D01*
G02X520486Y645324I-1J-1306D01*
G01X522143Y643667D01*
G03X522223Y643618I142J141D01*
G01X522224D01*
G02X523280Y642184I-446J-1434D01*
G02X521778Y640682I-1502J0D01*
G02X520344Y641737I0J1502D01*
G01Y641739D01*
G03X520295Y641819I-190J-62D01*
G01X519080Y643035D01*
G03X518938Y643094I-142J-141D01*
G01X493085D01*
G03X492943Y643035I0J-200D01*
G01X480235Y630327D01*
G03X480176Y630185I141J-142D01*
G01Y595593D01*
G03X480300Y595408I200J0D01*
G01X480356Y595384D01*
X480474Y595408D01*
X485169Y600103D01*
G02X486093Y600486I924J-923D01*
G01X504627D01*
G03X504769Y600545I0J200D01*
G01X510190Y605965D01*
G03X510248Y606120I-142J141D01*
G01X510227Y606421D01*
G03X510149Y606566I-199J-14D01*
G02X509952Y606745I908J1197D01*
G03X509805Y606810I-148J-135D01*
G01X509511D01*
G03X509364Y606745I1J-200D01*
G02X507152I-1106J1017D01*
G03X507005Y606810I-148J-135D01*
G01X506711D01*
G03X506564Y606745I1J-200D01*
G02X504352I-1106J1017D01*
G03X504205Y606810I-148J-135D01*
G01X503911D01*
G03X503764Y606745I1J-200D01*
G02X502658Y606260I-1106J1019D01*
G02X501156Y607762I0J1502D01*
G02X501641Y608868I1504J0D01*
G03X501706Y609015I-135J148D01*
G01Y609309D01*
G03X501641Y609456I-200J-1D01*
G02X501156Y610562I1019J1106D01*
G02X502658Y612064I1502J0D01*
G02X503764Y611579I0J-1504D01*
G03X503911Y611514I148J135D01*
G01X504205D01*
G03X504352Y611579I-1J200D01*
G02X506564I1106J-1017D01*
G03X506711Y611514I148J135D01*
G01X507005D01*
G03X507152Y611579I-1J200D01*
G02X509364I1106J-1017D01*
G03X509511Y611514I148J135D01*
G01X509805D01*
G03X509952Y611579I-1J200D01*
G02X511058Y612064I1106J-1019D01*
G02X512560Y610562I0J-1502D01*
G02X512075Y609456I-1504J0D01*
G03X512010Y609309I135J-148D01*
G01Y609015D01*
G03X512075Y608868I200J1D01*
G02X512254Y608671I-1018J-1105D01*
G01X512280Y608636D01*
X512356Y608596D01*
X512700Y608572D01*
G03X512855Y608630I14J200D01*
G01X515364Y611140D01*
G02X516286Y611522I923J-924D01*
G01X521958D01*
G02X522880Y611140I-1J-1306D01*
G01X525694Y608326D01*
G02X526076Y607404I-924J-923D01*
G01Y606429D01*
G03X526099Y606336I200J0D01*
G02X526272Y605637I-1329J-700D01*
G02X524770Y604135I-1502J0D01*
G02X523598Y604697I0J1503D01*
G01X523564Y604739D01*
X523466Y604778D01*
X523017Y604710D01*
X522935Y604644D01*
X522915Y604594D01*
G02X520770Y603136I-2145J849D01*
G02X519888Y603312I2J2307D01*
G01X519801Y603348D01*
G02X519402Y603561I881J2131D01*
G01X518782Y603975D01*
G03X518519Y603940I-112J-166D01*
G01Y603939D01*
G02X518401Y603812I-1748J1505D01*
G01X508517Y593928D01*
G02X506886Y593252I-1632J1631D01*
G01X488633D01*
G03X488491Y593193I0J-200D01*
G01X486265Y590968D01*
G03X486206Y590826I141J-142D01*
G01Y581238D01*
G03X486265Y581096I200J0D01*
G01X490131Y577231D01*
G02X490806Y575601I-1631J-1630D01*
G01Y554599D01*
G03X490878Y554446I200J1D01*
G01X491147Y554221D01*
X491231Y554198D01*
X491275Y554206D01*
G02X491534Y554228I256J-1480D01*
G02Y551224I0J-1502D01*
G02X491275Y551246I-3J1502D01*
G01X491231Y551254D01*
X491147Y551231D01*
X490878Y551006D01*
G03X490806Y550853I128J-154D01*
G01Y548430D01*
G03X490876Y548278I200J0D01*
G01X491109Y548081D01*
G03X491270Y548036I129J152D01*
G01X491271D01*
G02X491511Y548055I238J-1483D01*
G02Y545051I0J-1502D01*
G02X491271Y545070I-2J1502D01*
G01X491270D01*
G03X491109Y545025I-32J-197D01*
G01X490876Y544828D01*
G03X490806Y544676I130J-152D01*
G01Y543022D01*
G03X490874Y542872I200J0D01*
G01X491100Y542673D01*
G03X491256Y542625I132J150D01*
G01X491257D01*
G02X491445Y542637I189J-1490D01*
G02Y539633I0J-1502D01*
G02X491257Y539645I1J1502D01*
G01X491256D01*
G03X491100Y539597I-24J-198D01*
G01X490874Y539398D01*
G03X490806Y539248I132J-150D01*
G01Y536710D01*
G03X490890Y536547I200J0D01*
G01X491194Y536329D01*
X491289Y536315D01*
X491335Y536331D01*
G02X491818Y536411I484J-1422D01*
G02Y533407I0J-1502D01*
G02X491335Y533487I1J1502D01*
G01X491289Y533503D01*
X491194Y533489D01*
X490890Y533271D01*
G03X490806Y533108I116J-163D01*
G01Y463699D01*
G02X490131Y462069I-2306J0D01*
G01X467625Y439564D01*
G03X467566Y439422I141J-142D01*
G01Y396841D01*
G02X466891Y395211I-2306J0D01*
G01X458251Y386571D01*
G03X458192Y386429I141J-142D01*
G01Y367702D01*
G02X453578I-2307J0D01*
G01Y371036D01*
G03X453455Y371221I-200J0D01*
G01X453399Y371244D01*
X453281Y371221D01*
X452483Y370423D01*
G02X450853Y369748I-1630J1631D01*
G01X450852D01*
G02X448546Y372054I0J2306D01*
G01Y372055D01*
G02X449221Y373685I2306J0D01*
G01X450635Y375098D01*
G03X450694Y375240I-141J142D01*
G01Y379683D01*
G03X450570Y379868I-200J0D01*
G01X450514Y379892D01*
X450396Y379868D01*
X449806Y379278D01*
G03X449757Y379198I141J-142D01*
G01Y379197D01*
G02X448770Y378209I-1434J446D01*
G01X448768D01*
G03X448688Y378160I62J-190D01*
G01X443465Y372938D01*
G03X443406Y372796I141J-142D01*
G01Y370347D01*
G02X443024Y369425I-1306J1D01*
G01X438575Y364976D01*
G02X437653Y364594I-923J924D01*
G01X417280D01*
G03X417138Y364535I0J-200D01*
G01X414277Y361674D01*
G03X414218Y361532I141J-142D01*
G01Y354610D01*
G02X413836Y353688I-1306J1D01*
G01X406165Y346018D01*
G03X406106Y345876I141J-142D01*
G01Y331699D01*
G02X405724Y330777I-1306J1D01*
G01X402823Y327876D01*
G02X401901Y327494I-923J924D01*
G01X397281D01*
G02X396359Y327876I1J1306D01*
G01X388956Y335279D01*
G02X388574Y336201I924J923D01*
G01Y343494D01*
G03X388515Y343636I-200J0D01*
G01X357567Y374583D01*
G02X357184Y375507I923J924D01*
G01Y376383D01*
G03X357163Y376472I-200J0D01*
G01X357162Y376474D01*
G02X356989Y377173I1329J700D01*
G02X359993I1502J0D01*
G02X359821Y376476I-1502J1D01*
G03X359819Y376472I178J-91D01*
G01X359808Y376451D01*
X359798Y376407D01*
Y376131D01*
G03X359857Y375989I200J0D01*
G01X390804Y345042D01*
G02X391186Y344120I-924J-923D01*
G01Y336827D01*
G03X391245Y336685I200J0D01*
G01X394311Y333620D01*
G03X394528Y333577I141J142D01*
G01X394585Y333600D01*
X394652Y333701D01*
Y335206D01*
G02X394820Y336068I2306J-2D01*
G01X394837Y336110D01*
X394832Y336198D01*
X394664Y336509D01*
G03X394529Y336610I-176J-95D01*
G01X394528D01*
G02X393080Y338377I354J1767D01*
G01Y341777D01*
G02X396686I1803J0D01*
G01Y338674D01*
G03X396809Y338489I200J0D01*
G01X396865Y338466D01*
X396983Y338489D01*
X398035Y339540D01*
G03X398094Y339682I-141J142D01*
G01Y349191D01*
G02X398769Y350821I2306J0D01*
G01X399572Y351624D01*
G03X399631Y351758I-141J142D01*
G01X399642Y352069D01*
X399617Y352141D01*
X399592Y352169D01*
G02X399226Y353152I1137J983D01*
G02X400701Y354654I1502J0D01*
G01X400741D01*
X400812Y354685D01*
X401037Y354914D01*
G03X401094Y355054I-143J140D01*
G01Y366816D01*
G03X400894Y367016I-200J0D01*
G01X383989D01*
G02X383067Y367398I1J1306D01*
G01X380872Y369593D01*
G03X380792Y369642I-142J-141D01*
G01X380791D01*
G02X379735Y371076I446J1434D01*
G02X381237Y372578I1502J0D01*
G02X382671Y371523I0J-1502D01*
G01Y371521D01*
G03X382720Y371441I190J62D01*
G01X384473Y369687D01*
G03X384615Y369628I142J141D01*
G01X401736D01*
G03X401878Y369687I0J200D01*
G01X411358Y379168D01*
G02X412280Y379550I923J-924D01*
G01X429720D01*
G03X429862Y379609I0J200D01*
G01X452361Y402108D01*
G03X452420Y402250I-141J142D01*
G01Y448586D01*
G03X452361Y448728I-200J0D01*
G01X444029Y457059D01*
G03X443887Y457118I-142J-141D01*
G01X432855D01*
G02X431931Y457501I0J1306D01*
G01X429308Y460124D01*
G03X429228Y460173I-142J-141D01*
G01X429227D01*
G02X428171Y461607I446J1434D01*
G02X429673Y463109I1502J0D01*
G02X431107Y462054I0J-1502D01*
G01Y462052D01*
G03X431156Y461972I190J62D01*
G01X431511Y461617D01*
G03X431715Y461568I142J141D01*
G01X432107Y461696D01*
X432180Y461782D01*
X432189Y461838D01*
G02X433673Y463109I1484J-231D01*
G02X435175Y461607I0J-1502D01*
G02X434621Y460442I-1502J0D01*
G01X434571Y460401D01*
X434537Y460280D01*
X434685Y459865D01*
G03X434873Y459732I188J67D01*
G01X444511D01*
G02X445435Y459349I0J-1306D01*
G01X454650Y450134D01*
G02X455032Y449212I-924J-923D01*
G01Y447092D01*
G03X455156Y446907I200J0D01*
G01X455212Y446883D01*
X455330Y446907D01*
X474215Y465791D01*
G03X474274Y465933I-141J142D01*
G01Y468619D01*
G03X474207Y468769I-200J1D01*
G01X473984Y468968D01*
G03X473828Y469017I-133J-150D01*
G02X473658Y469007I-173J1492D01*
G02Y472011I0J1502D01*
G02X473828Y472001I-3J-1502D01*
G01X473871Y471996D01*
X473951Y472022D01*
X474207Y472249D01*
G03X474274Y472399I-133J149D01*
G01Y473619D01*
G03X474207Y473769I-200J1D01*
G01X473984Y473968D01*
G03X473828Y474017I-133J-150D01*
G02X473658Y474007I-173J1492D01*
G02X472156Y475509I0J1502D01*
G02X472825Y476759I1502J0D01*
G01X472854Y476779D01*
X472896Y476837D01*
X472986Y477159D01*
X472980Y477230D01*
X472964Y477263D01*
G02X472740Y478253I2083J992D01*
G01Y501521D01*
G03X472617Y501706I-200J0D01*
G01X472561Y501729D01*
X472443Y501706D01*
X470041Y499304D01*
G03X469992Y499224I141J-142D01*
G01Y499223D01*
G02X468558Y498167I-1434J446D01*
G02X467056Y499669I0J1502D01*
G02X468111Y501103I1502J0D01*
G01X468113D01*
G03X468193Y501152I-62J190D01*
G01X471871Y504830D01*
G03X471930Y504972I-141J142D01*
G01Y522489D01*
G03X471807Y522674I-200J0D01*
G01X471751Y522697D01*
X471633Y522674D01*
X461011Y512052D01*
G03X460952Y511910I141J-142D01*
G01Y510276D01*
G03X460973Y510187I200J0D01*
G01X460974Y510185D01*
G02X461147Y509486I-1329J-700D01*
G02X458143I-1502J0D01*
G02X458315Y510183I1502J-1D01*
G03X458317Y510187I-178J91D01*
G01X458328Y510208D01*
X458338Y510252D01*
Y512534D01*
G02X458721Y513458I1306J0D01*
G01X470461Y525198D01*
G03X470520Y525340I-141J142D01*
G01Y544170D01*
G03X470402Y544353I-200J1D01*
G01X470069Y544502D01*
G03X469853Y544468I-82J-183D01*
G02X468850Y544084I-1003J1118D01*
G02Y547088I0J1502D01*
G02X469853Y546704I0J-1502D01*
G03X470069Y546670I134J149D01*
G01X470402Y546819D01*
G03X470520Y547002I-82J182D01*
G01Y569626D01*
G03X470461Y569768I-200J0D01*
G01X469376Y570853D01*
G02X468994Y571775I924J923D01*
G01Y658663D01*
G03X468870Y658848I-200J0D01*
G01X468814Y658872D01*
X468696Y658848D01*
X457835Y647987D01*
G03X457776Y647845I141J-142D01*
G01Y639092D01*
G03X457797Y639003I200J0D01*
G01X457798Y639001D01*
G02X457971Y638302I-1329J-700D01*
G02X454967I-1502J0D01*
G02X455139Y638999I1502J-1D01*
G03X455141Y639003I-178J91D01*
G01X455152Y639024D01*
X455162Y639068D01*
Y648469D01*
G02X455545Y649393I1306J0D01*
G01X471229Y665077D01*
G03X471288Y665219I-141J142D01*
G01Y716281D01*
G03X471229Y716423I-200J0D01*
G01X460727Y726925D01*
G03X460585Y726984I-142J-141D01*
G01X425783D01*
G03X425694Y726963I0J-200D01*
G01X425692Y726962D01*
G02X424993Y726789I-700J1329D01*
G02X423491Y728291I0J1502D01*
G02X423663Y728988I1502J-1D01*
G03X423665Y728992I-178J91D01*
G01X423676Y729013D01*
X423686Y729057D01*
Y729267D01*
G02X424069Y730191I1306J0D01*
G01X437123Y743245D01*
G03X437182Y743387I-141J142D01*
G01Y758169D01*
G03X437059Y758354I-200J0D01*
G01X437003Y758377D01*
X436885Y758354D01*
X427465Y748935D01*
G02X426400Y748494I-1065J1065D01*
G01X372300D01*
G02Y751506I0J1506D01*
G01X425693D01*
G03X425835Y751565I0J200D01*
G01X435113Y760844D01*
G03X435172Y760986I-141J142D01*
G01Y792579D01*
G02X435614Y793644I1507J-1D01*
G01X457435Y815465D01*
G03X457494Y815607I-141J142D01*
G01Y831900D01*
G02X457935Y832965I1506J0D01*
G01X473635Y848665D01*
G02X474700Y849106I1065J-1065D01*
G01X479700D01*
G02Y846094I0J-1506D01*
G01X475407D01*
G03X475265Y846035I0J-200D01*
G01X460565Y831335D01*
G03X460506Y831193I141J-142D01*
G01Y829897D01*
G03X460706Y829697I200J0D01*
G01X460764D01*
X460860Y829756D01*
X460885Y829807D01*
G02X461128Y830143I1167J-588D01*
G01X470916Y839931D01*
G03X470965Y840011I-141J142D01*
G01Y840012D01*
G02X472399Y841068I1434J-446D01*
G02X473901Y839566I0J-1502D01*
G02X472846Y838132I-1502J0D01*
G01X472844D01*
G03X472764Y838083I62J-190D01*
G01X463417Y828737D01*
G03X463358Y828595I141J-142D01*
G01Y813795D01*
G02X462976Y812873I-1306J1D01*
G01X459390Y809288D01*
G03X459340Y809092I142J-141D01*
G01X459437Y808754D01*
G03X459583Y808615I192J56D01*
G02X460717Y807449I-338J-1463D01*
G01X460728Y807395D01*
X460802Y807314D01*
X461193Y807196D01*
G03X461393Y807246I58J191D01*
G01X472289Y818142D01*
G03X472348Y818284I-141J142D01*
G01Y820442D01*
G03X472325Y820535I-200J0D01*
G02X472152Y821234I1329J700D01*
G02X475156I1502J0D01*
G02X474983Y820535I-1502J1D01*
G03X474960Y820442I177J-93D01*
G01Y817658D01*
G02X474578Y816736I-1306J1D01*
G01X443267Y785426D01*
G03X443208Y785284I141J-142D01*
G01Y754350D01*
G03X443267Y754208I200J0D01*
G01X477124Y720352D01*
G02X477506Y719430I-924J-923D01*
G01Y662491D01*
G37*
G36*
G01X68778Y872319D02*
G02Y875323I0J1502D01*
G02X70059Y874606I0J-1503D01*
G03X70721Y874577I341J209D01*
G02X71928Y875185I1207J-894D01*
G02Y872181I0J-1502D01*
G02X70647Y872898I0J1503D01*
G03X69985Y872927I-341J-209D01*
G02X68778Y872319I-1207J894D01*
G37*
G36*
G01X90658Y876674D02*
G02X90079Y877859I923J1185D01*
G02X93083I1502J0D01*
G02X92504Y876674I-1502J0D01*
G03X92429Y876546I123J-158D01*
G03X92427Y876516I198J-28D01*
G01Y876202D01*
G03X92429Y876172I200J-2D01*
G03X92504Y876044I198J30D01*
G02X93083Y874859I-923J-1185D01*
G02X90079I-1502J0D01*
G02X90658Y876044I1502J0D01*
G03X90733Y876172I-123J158D01*
G03X90735Y876202I-198J28D01*
G01Y876516D01*
G03X90733Y876546I-200J2D01*
G03X90658Y876674I-198J-30D01*
G37*
G36*
G01X66779Y911645D02*
X66778Y911646D01*
G02X65959Y912983I682J1337D01*
G02X68963I1502J0D01*
G02X68648Y912063I-1502J0D01*
G01X68647Y912062D01*
X68645Y912060D01*
G03X68610Y911985I160J-120D01*
G01X68600Y911940D01*
X68677Y911595D01*
G03X68715Y911515I195J44D01*
G01X68716D01*
G03X68780Y911461I158J122D01*
G01X68782Y911460D01*
X68783Y911459D01*
G02X69602Y910122I-682J-1337D01*
G02X66598I-1502J0D01*
G02X66913Y911042I1502J0D01*
G01X66914Y911043D01*
X66916Y911045D01*
G03X66951Y911120I-160J120D01*
G01X66961Y911165D01*
X66884Y911510D01*
G03X66846Y911590I-195J-44D01*
G01X66845D01*
G03X66781Y911644I-158J-122D01*
G01X66779Y911645D01*
G37*
G36*
G01X76665Y949260D02*
Y949261D01*
G02X79669I1502J0D01*
G02X78375Y947773I-1503J0D01*
G03X78128Y947116I56J-396D01*
G02X78493Y946135I-1137J-982D01*
G01Y946134D01*
G02X75489I-1502J0D01*
G02X76783Y947622I1503J0D01*
G03X77030Y948279I-56J396D01*
G02X76665Y949260I1137J982D01*
G37*
G36*
G01X92382Y1007314D02*
G03X93069Y1007348I333J221D01*
G02X94398Y1008150I1329J-700D01*
G02Y1005146I0J-1502D01*
G02X93144Y1005821I0J1502D01*
G03X92457Y1005787I-333J-221D01*
G02X91128Y1004985I-1329J700D01*
G02Y1007989I0J1502D01*
G02X92382Y1007314I0J-1502D01*
G37*
G36*
G01X87452Y1024880D02*
X87426Y1025259D01*
X87387Y1025334D01*
X87354Y1025360D01*
G02X86785Y1026537I933J1177D01*
G02X89789I1502J0D01*
G02X89372Y1025498I-1503J0D01*
G01X89342Y1025467D01*
X89314Y1025388D01*
X89340Y1025009D01*
X89379Y1024934D01*
X89412Y1024908D01*
G02X89981Y1023731I-933J-1177D01*
G02X86977I-1502J0D01*
G02X87394Y1024770I1503J0D01*
G01X87424Y1024801D01*
X87452Y1024880D01*
G37*
G36*
G01X123378Y1117691D02*
G02X126382I1502J0D01*
G02X125821Y1116520I-1503J0D01*
G01X125785Y1116491D01*
X125746Y1116408D01*
X125751Y1116046D01*
G03X125830Y1115889I200J2D01*
G02X126427Y1114691I-905J-1199D01*
G02X123423I-1502J0D01*
G02X123984Y1115862I1503J0D01*
G01X124020Y1115891D01*
X124059Y1115974D01*
X124054Y1116336D01*
G03X123975Y1116493I-200J-2D01*
G02X123378Y1117691I905J1199D01*
G37*
G36*
G01Y1130291D02*
G02X126382I1502J0D01*
G02X125821Y1129120I-1503J0D01*
G01X125785Y1129091D01*
X125746Y1129008D01*
X125751Y1128646D01*
G03X125830Y1128489I200J2D01*
G02X126427Y1127291I-905J-1199D01*
G02X123423I-1502J0D01*
G02X123984Y1128462I1503J0D01*
G01X124020Y1128491D01*
X124059Y1128574D01*
X124054Y1128936D01*
G03X123975Y1129093I-200J-2D01*
G02X123378Y1130291I905J1199D01*
G37*
G36*
G01X165649Y1134470D02*
G02Y1131864I0J-1303D01*
G01X161909D01*
G02Y1134470I0J1303D01*
G01X165649D01*
G37*
G36*
G01X173129Y1138210D02*
G02Y1135604I0J-1303D01*
G01X169389D01*
G02Y1138210I0J1303D01*
G01X173129D01*
G37*
G36*
G01X159786Y1055428D02*
G02X159231Y1056594I947J1166D01*
G02X162235I1502J0D01*
G02X161596Y1055365I-1501J0D01*
G03X161574Y1054727I230J-327D01*
G02X162129Y1053561I-947J-1166D01*
G02X159125I-1502J0D01*
G02X159764Y1054790I1501J0D01*
G03X159786Y1055428I-230J327D01*
G37*
G36*
G01X146948Y1138210D02*
G02Y1135604I0J-1303D01*
G01X143208D01*
G02Y1138210I0J1303D01*
G01X146948D01*
G37*
G36*
G01X360838Y1230107D02*
X360834Y1230151D01*
G02X360830Y1230265I1498J110D01*
G02X362332Y1228763I1502J0D01*
G02X362204Y1228768I-5J1502D01*
G01X362159Y1228772D01*
X362077Y1228743D01*
X361798Y1228466D01*
X361767Y1228384D01*
X361771Y1228340D01*
G02X361775Y1228226I-1498J-110D01*
G02X360273Y1226724I-1502J0D01*
G02X360005Y1226748I-1J1502D01*
G01X359956Y1226757D01*
X359863Y1226728D01*
X359560Y1226425D01*
X359531Y1226332D01*
X359540Y1226283D01*
G02X359564Y1226016I-1478J-267D01*
G02X358062Y1227518I-1502J0D01*
G02X358330Y1227494I1J-1502D01*
G01X358379Y1227485D01*
X358472Y1227514D01*
X358775Y1227817D01*
X358804Y1227910D01*
X358795Y1227959D01*
G02X358771Y1228226I1478J267D01*
G02X360273Y1229728I1502J0D01*
G02X360401Y1229723I5J-1502D01*
G01X360446Y1229719D01*
X360528Y1229748D01*
X360807Y1230025D01*
X360838Y1230107D01*
G37*
G36*
G01X363581Y1213755D02*
X363569Y1213807D01*
G02X363527Y1214158I1460J353D01*
G02X365029Y1212656I1502J0D01*
G02X364678Y1212698I2J1502D01*
G01X364626Y1212710D01*
X364527Y1212682D01*
X364211Y1212366D01*
X364183Y1212267D01*
X364195Y1212215D01*
G02X364237Y1211864I-1460J-353D01*
G02X362735Y1210362I-1502J0D01*
G02X362591Y1210369I1J1502D01*
G01X362546Y1210373D01*
X362462Y1210343D01*
X362180Y1210061D01*
X362150Y1209978D01*
X362154Y1209933D01*
G02X362161Y1209789I-1495J-145D01*
G02X360659Y1211291I-1502J0D01*
G02X360803Y1211284I-1J-1502D01*
G01X360848Y1211280D01*
X360932Y1211310D01*
X361214Y1211592D01*
X361244Y1211675D01*
X361240Y1211720D01*
G02X361233Y1211864I1495J145D01*
G02X362735Y1213366I1502J0D01*
G02X363086Y1213324I-2J-1502D01*
G01X363138Y1213312D01*
X363237Y1213340D01*
X363553Y1213656D01*
X363581Y1213755D01*
G37*
G36*
G01X312213Y1198350D02*
X312204Y1198399D01*
G02X312183Y1198621I1181J224D01*
G02X313385Y1197419I1202J0D01*
G02X313163Y1197440I2J1202D01*
G01X313114Y1197449D01*
X313021Y1197420D01*
X312716Y1197115D01*
X312687Y1197022D01*
X312696Y1196973D01*
G02X312717Y1196751I-1181J-224D01*
G02X310313I-1202J0D01*
G02X310334Y1196973I1202J-2D01*
G01X310343Y1197022D01*
X310314Y1197115D01*
X310009Y1197420D01*
X309916Y1197449D01*
X309867Y1197440D01*
G02X309645Y1197419I-224J1181D01*
G02X310847Y1198621I0J1202D01*
G02X310826Y1198399I-1202J2D01*
G01X310817Y1198350D01*
X310846Y1198257D01*
X311151Y1197952D01*
X311244Y1197923D01*
X311293Y1197932D01*
G02X311515Y1197953I224J-1181D01*
G02X311737Y1197932I-2J-1202D01*
G01X311786Y1197923D01*
X311879Y1197952D01*
X312184Y1198257D01*
X312213Y1198350D01*
G37*
G36*
G01X358469Y1191769D02*
G02X357297Y1191207I-1172J941D01*
G02Y1194211I0J1502D01*
G02X358673Y1193311I0J-1502D01*
G03X359351Y1193222I366J161D01*
G02X360523Y1193784I1172J-941D01*
G02Y1190780I0J-1502D01*
G02X359147Y1191680I0J1502D01*
G03X358469Y1191769I-366J-161D01*
G37*
G36*
G01X289772Y1190870D02*
X289763Y1190919D01*
G02X289742Y1191141I1181J224D01*
G02X292146I1202J0D01*
G02X292125Y1190919I-1202J2D01*
G01X292116Y1190870D01*
X292145Y1190777D01*
X292450Y1190472D01*
X292543Y1190443D01*
X292592Y1190452D01*
G02X292814Y1190473I224J-1181D01*
G02X291612Y1189271I0J-1202D01*
G02X291633Y1189493I1202J-2D01*
G01X291642Y1189542D01*
X291613Y1189635D01*
X291308Y1189940D01*
X291215Y1189969D01*
X291166Y1189960D01*
G02X290944Y1189939I-224J1181D01*
G02X290722Y1189960I2J1202D01*
G01X290673Y1189969D01*
X290580Y1189940D01*
X290275Y1189635D01*
X290246Y1189542D01*
X290255Y1189493D01*
G02X290276Y1189271I-1181J-224D01*
G02X289074Y1190473I-1202J0D01*
G02X289296Y1190452I-2J-1202D01*
G01X289345Y1190443D01*
X289438Y1190472D01*
X289743Y1190777D01*
X289772Y1190870D01*
G37*
G36*
G01X299123Y1189000D02*
X299114Y1189049D01*
G02X299093Y1189271I1181J224D01*
G02X300295Y1188069I1202J0D01*
G02X300073Y1188090I2J1202D01*
G01X300024Y1188099D01*
X299931Y1188070D01*
X299626Y1187765D01*
X299597Y1187672D01*
X299606Y1187623D01*
G02X299627Y1187401I-1181J-224D01*
G02X299606Y1187179I-1202J2D01*
G01X299597Y1187130D01*
X299626Y1187037D01*
X299931Y1186732D01*
X300024Y1186703D01*
X300073Y1186712D01*
G02X300295Y1186733I224J-1181D01*
G02X299093Y1185531I0J-1202D01*
G02X299114Y1185753I1202J-2D01*
G01X299123Y1185802D01*
X299094Y1185895D01*
X298789Y1186200D01*
X298696Y1186229D01*
X298647Y1186220D01*
G02X298425Y1186199I-224J1181D01*
G02Y1188603I0J1202D01*
G02X298647Y1188582I-2J-1202D01*
G01X298696Y1188573D01*
X298789Y1188602D01*
X299094Y1188907D01*
X299123Y1189000D01*
G37*
G36*
G01X341689Y1188868D02*
X341708Y1188921D01*
G02X343121Y1189914I1413J-509D01*
G02Y1186910I0J-1502D01*
G02X341893Y1187548I0J1501D01*
G01X341860Y1187594D01*
X341758Y1187638D01*
X341295Y1187576D01*
X341208Y1187506D01*
X341189Y1187453D01*
G02X339776Y1186460I-1413J509D01*
G02X339582Y1186473I3J1502D01*
G01X339539Y1186478D01*
X339457Y1186453D01*
X339166Y1186197D01*
X339131Y1186119D01*
Y1186075D01*
G02X336127Y1186071I-1502J-4D01*
G02X336142Y1186280I1502J-3D01*
G01X336148Y1186327D01*
X336119Y1186415D01*
X335829Y1186708D01*
X335741Y1186738D01*
X335694Y1186732D01*
G02X335502Y1186720I-190J1490D01*
G02X337004Y1188222I0J1502D01*
G02X336989Y1188013I-1502J3D01*
G01X336983Y1187966D01*
X337012Y1187878D01*
X337302Y1187585D01*
X337390Y1187555D01*
X337437Y1187561D01*
G02X337629Y1187573I190J-1490D01*
G02X337823Y1187560I-3J-1502D01*
G01X337866Y1187555D01*
X337948Y1187580D01*
X338239Y1187836D01*
X338274Y1187914D01*
Y1187958D01*
G02X339776Y1189464I1502J4D01*
G02X341004Y1188826I0J-1501D01*
G01X341037Y1188780D01*
X341139Y1188736D01*
X341602Y1188798D01*
X341689Y1188868D01*
G37*
G36*
G01X446466Y1210699D02*
Y1211035D01*
X446441Y1211102D01*
X446417Y1211130D01*
G02X446047Y1212117I1131J987D01*
G02X449051I1502J0D01*
G02X448681Y1211130I-1501J0D01*
G01X448657Y1211102D01*
X448632Y1211035D01*
Y1210699D01*
X448657Y1210632D01*
X448681Y1210604D01*
G02Y1208630I-1131J-987D01*
G01X448657Y1208602D01*
X448632Y1208535D01*
Y1208199D01*
X448657Y1208132D01*
X448681Y1208104D01*
G02Y1206130I-1131J-987D01*
G01X448657Y1206102D01*
X448632Y1206035D01*
Y1205699D01*
X448657Y1205632D01*
X448681Y1205604D01*
G02X449051Y1204617I-1131J-987D01*
G02X446047I-1502J0D01*
G02X446417Y1205604I1501J0D01*
G01X446441Y1205632D01*
X446466Y1205699D01*
Y1206035D01*
X446441Y1206102D01*
X446417Y1206130D01*
G02Y1208104I1131J987D01*
G01X446441Y1208132D01*
X446466Y1208199D01*
Y1208535D01*
X446441Y1208602D01*
X446417Y1208630D01*
G02Y1210604I1131J987D01*
G01X446441Y1210632D01*
X446466Y1210699D01*
G37*
G36*
G01X419536D02*
Y1211035D01*
X419511Y1211102D01*
X419487Y1211130D01*
G02X419117Y1212117I1131J987D01*
G02X422121I1502J0D01*
G02X421751Y1211130I-1501J0D01*
G01X421727Y1211102D01*
X421702Y1211035D01*
Y1210699D01*
X421727Y1210632D01*
X421751Y1210604D01*
G02Y1208630I-1131J-987D01*
G01X421727Y1208602D01*
X421702Y1208535D01*
Y1208199D01*
X421727Y1208132D01*
X421751Y1208104D01*
G02Y1206130I-1131J-987D01*
G01X421727Y1206102D01*
X421702Y1206035D01*
Y1205699D01*
X421727Y1205632D01*
X421751Y1205604D01*
G02X422121Y1204617I-1131J-987D01*
G02X419117I-1502J0D01*
G02X419487Y1205604I1501J0D01*
G01X419511Y1205632D01*
X419536Y1205699D01*
Y1206035D01*
X419511Y1206102D01*
X419487Y1206130D01*
G02Y1208104I1131J987D01*
G01X419511Y1208132D01*
X419536Y1208199D01*
Y1208535D01*
X419511Y1208602D01*
X419487Y1208630D01*
G02Y1210604I1131J987D01*
G01X419511Y1210632D01*
X419536Y1210699D01*
G37*
G36*
G01X432166Y1210487D02*
Y1210823D01*
X432141Y1210890D01*
X432117Y1210918D01*
G02X431747Y1211905I1131J987D01*
G02X434751I1502J0D01*
G02X434381Y1210918I-1501J0D01*
G01X434357Y1210890D01*
X434332Y1210823D01*
Y1210487D01*
X434357Y1210420D01*
X434381Y1210392D01*
G02Y1208418I-1131J-987D01*
G01X434357Y1208390D01*
X434332Y1208323D01*
Y1207987D01*
X434357Y1207920D01*
X434381Y1207892D01*
G02Y1205918I-1131J-987D01*
G01X434357Y1205890D01*
X434332Y1205823D01*
Y1205487D01*
X434357Y1205420D01*
X434381Y1205392D01*
G02X434751Y1204405I-1131J-987D01*
G02X431747I-1502J0D01*
G02X432117Y1205392I1501J0D01*
G01X432141Y1205420D01*
X432166Y1205487D01*
Y1205823D01*
X432141Y1205890D01*
X432117Y1205918D01*
G02Y1207892I1131J987D01*
G01X432141Y1207920D01*
X432166Y1207987D01*
Y1208323D01*
X432141Y1208390D01*
X432117Y1208418D01*
G02Y1210392I1131J987D01*
G01X432141Y1210420D01*
X432166Y1210487D01*
G37*
G36*
G01X405236D02*
Y1210823D01*
X405211Y1210890D01*
X405187Y1210918D01*
G02X404817Y1211905I1131J987D01*
G02X407821I1502J0D01*
G02X407451Y1210918I-1501J0D01*
G01X407427Y1210890D01*
X407402Y1210823D01*
Y1210487D01*
X407427Y1210420D01*
X407451Y1210392D01*
G02Y1208418I-1131J-987D01*
G01X407427Y1208390D01*
X407402Y1208323D01*
Y1207987D01*
X407427Y1207920D01*
X407451Y1207892D01*
G02Y1205918I-1131J-987D01*
G01X407427Y1205890D01*
X407402Y1205823D01*
Y1205487D01*
X407427Y1205420D01*
X407451Y1205392D01*
G02X407821Y1204405I-1131J-987D01*
G02X404817I-1502J0D01*
G02X405187Y1205392I1501J0D01*
G01X405211Y1205420D01*
X405236Y1205487D01*
Y1205823D01*
X405211Y1205890D01*
X405187Y1205918D01*
G02Y1207892I1131J987D01*
G01X405211Y1207920D01*
X405236Y1207987D01*
Y1208323D01*
X405211Y1208390D01*
X405187Y1208418D01*
G02Y1210392I1131J987D01*
G01X405211Y1210420D01*
X405236Y1210487D01*
G37*
G36*
G01X448781Y1199403D02*
Y1199739D01*
X448756Y1199806D01*
X448732Y1199834D01*
G02X448362Y1200821I1131J987D01*
G02X451366I1502J0D01*
G02X450996Y1199834I-1501J0D01*
G01X450972Y1199806D01*
X450947Y1199739D01*
Y1199403D01*
X450972Y1199336D01*
X450996Y1199308D01*
G02X451366Y1198321I-1131J-987D01*
G02X448362I-1502J0D01*
G02X448732Y1199308I1501J0D01*
G01X448756Y1199336D01*
X448781Y1199403D01*
G37*
G36*
G01X429851D02*
Y1199739D01*
X429826Y1199806D01*
X429802Y1199834D01*
G02X429432Y1200821I1131J987D01*
G02X432436I1502J0D01*
G02X432066Y1199834I-1501J0D01*
G01X432042Y1199806D01*
X432017Y1199739D01*
Y1199403D01*
X432042Y1199336D01*
X432066Y1199308D01*
G02X432436Y1198321I-1131J-987D01*
G02X429432I-1502J0D01*
G02X429802Y1199308I1501J0D01*
G01X429826Y1199336D01*
X429851Y1199403D01*
G37*
G36*
G01X421851D02*
Y1199739D01*
X421826Y1199806D01*
X421802Y1199834D01*
G02X421432Y1200821I1131J987D01*
G02X424436I1502J0D01*
G02X424066Y1199834I-1501J0D01*
G01X424042Y1199806D01*
X424017Y1199739D01*
Y1199403D01*
X424042Y1199336D01*
X424066Y1199308D01*
G02X424436Y1198321I-1131J-987D01*
G02X421432I-1502J0D01*
G02X421802Y1199308I1501J0D01*
G01X421826Y1199336D01*
X421851Y1199403D01*
G37*
G36*
G01X416386D02*
Y1199739D01*
X416361Y1199806D01*
X416337Y1199834D01*
G02X415967Y1200821I1131J987D01*
G02X418971I1502J0D01*
G02X418601Y1199834I-1501J0D01*
G01X418577Y1199806D01*
X418552Y1199739D01*
Y1199403D01*
X418577Y1199336D01*
X418601Y1199308D01*
G02X418971Y1198321I-1131J-987D01*
G02X415967I-1502J0D01*
G02X416337Y1199308I1501J0D01*
G01X416361Y1199336D01*
X416386Y1199403D01*
G37*
G36*
G01X402921D02*
Y1199739D01*
X402896Y1199806D01*
X402872Y1199834D01*
G02X402502Y1200821I1131J987D01*
G02X405506I1502J0D01*
G02X405136Y1199834I-1501J0D01*
G01X405112Y1199806D01*
X405087Y1199739D01*
Y1199403D01*
X405112Y1199336D01*
X405136Y1199308D01*
G02X405506Y1198321I-1131J-987D01*
G02X402502I-1502J0D01*
G02X402872Y1199308I1501J0D01*
G01X402896Y1199336D01*
X402921Y1199403D01*
G37*
G36*
G01X338582Y1195694D02*
X338224Y1195628D01*
X338159Y1195586D01*
X338136Y1195552D01*
G02X336901Y1194905I-1235J855D01*
G02Y1197909I0J1502D01*
G02X337750Y1197646I0J-1502D01*
G01X337783Y1197623D01*
X337859Y1197607D01*
X338217Y1197673D01*
X338282Y1197715D01*
X338305Y1197749D01*
G02X339540Y1198396I1235J-855D01*
G02Y1195392I0J-1502D01*
G02X338691Y1195655I0J1502D01*
G01X338658Y1195678D01*
X338582Y1195694D01*
G37*
G36*
G01X356538Y1186651D02*
X356635Y1187039D01*
X356617Y1187126D01*
X356590Y1187162D01*
G02X356294Y1188058I1206J895D01*
G02X359298I1502J0D01*
G02X358439Y1186700I-1503J0D01*
G01X358398Y1186681D01*
X358341Y1186612D01*
X358244Y1186224D01*
X358262Y1186137D01*
X358289Y1186101D01*
G02X358585Y1185205I-1206J-895D01*
G02X355581I-1502J0D01*
G02X356440Y1186563I1503J0D01*
G01X356481Y1186582D01*
X356538Y1186651D01*
G37*
G36*
G01X213069Y1110728D02*
G02X215473I1202J0D01*
G02X215452Y1110507I-1202J3D01*
G01X215443Y1110458D01*
X215472Y1110364D01*
X215777Y1110059D01*
X215871Y1110030D01*
X215920Y1110039D01*
G02X216141Y1110060I224J-1181D01*
G02X214939Y1108858I0J-1202D01*
G02X214960Y1109079I1202J-3D01*
G01X214969Y1109128D01*
X214940Y1109222D01*
X214635Y1109527D01*
X214541Y1109556D01*
X214492Y1109547D01*
G02X214271Y1109526I-224J1181D01*
G02X214050Y1109547I3J1202D01*
G01X214001Y1109556D01*
X213907Y1109527D01*
X213602Y1109222D01*
X213573Y1109128D01*
X213582Y1109079D01*
G02X213603Y1108858I-1181J-224D01*
G02X212401Y1110060I-1202J0D01*
G02X212622Y1110039I-3J-1202D01*
G01X212671Y1110030D01*
X212765Y1110059D01*
X213070Y1110364D01*
X213099Y1110458D01*
X213090Y1110507D01*
G02X213069Y1110728I1181J224D01*
G37*
G36*
G01X352246Y1134728D02*
Y1134729D01*
G02X353748Y1133227I1502J0D01*
G02X353483Y1133251I2J1502D01*
G01X353433Y1133260D01*
X353337Y1133229D01*
X353072Y1132947D01*
G03X353023Y1132763I145J-137D01*
G02X353065Y1132411I-1460J-353D01*
G01Y1132410D01*
G02X350061I-1502J0D01*
G02X350098Y1132739I1502J-2D01*
G01X350108Y1132784D01*
X350089Y1132870D01*
X349870Y1133150D01*
G03X349717Y1133227I-158J-123D01*
G01X349716D01*
G02X348413Y1134041I32J1502D01*
G01X348387Y1134091D01*
X348291Y1134150D01*
X347823D01*
X347727Y1134091D01*
X347701Y1134041D01*
G02X346366Y1133227I-1335J688D01*
G02Y1136231I0J1502D01*
G02X347701Y1135417I0J-1502D01*
G01X347727Y1135367D01*
X347823Y1135308D01*
X348291D01*
X348387Y1135367D01*
X348413Y1135417D01*
G02X349748Y1136231I1335J-688D01*
G02X351250Y1134729I0J-1502D01*
G02X351213Y1134400I-1502J2D01*
G01X351203Y1134355D01*
X351222Y1134269D01*
X351441Y1133989D01*
G03X351594Y1133912I158J123D01*
G01X351595D01*
G02X351828Y1133888I-37J-1502D01*
G01X351878Y1133879D01*
X351973Y1133910D01*
X352239Y1134192D01*
G03X352288Y1134376I-145J137D01*
G02X352246Y1134728I1460J353D01*
G37*
G36*
G01X356381Y1134107D02*
G02X356246Y1134729I1367J622D01*
G02X359250I1502J0D01*
G02X357749Y1133227I-1502J0D01*
G01X357748D01*
G02X357680Y1133229I10J1502D01*
G01X357678D01*
G03X357296Y1132664I-18J-400D01*
G02X357431Y1132042I-1367J-622D01*
G02X354427I-1502J0D01*
G02X355928Y1133544I1502J0D01*
G01X355929D01*
G02X355997Y1133542I-10J-1502D01*
G01X355999D01*
G03X356381Y1134107I18J400D01*
G37*
G36*
G01X325274Y1136909D02*
G02X326476Y1135707I1202J0D01*
G02X326255Y1135728I3J1202D01*
G01X326206Y1135737D01*
X326112Y1135708D01*
X325807Y1135403D01*
X325778Y1135309D01*
X325787Y1135260D01*
G02X325808Y1135039I-1181J-224D01*
G02X323404I-1202J0D01*
G02X323425Y1135260I1202J-3D01*
G01X323434Y1135309D01*
X323405Y1135403D01*
X323100Y1135708D01*
X323006Y1135737D01*
X322957Y1135728D01*
G02X322736Y1135707I-224J1181D01*
G02X322515Y1135728I3J1202D01*
G01X322466Y1135737D01*
X322372Y1135708D01*
X322067Y1135403D01*
X322038Y1135309D01*
X322047Y1135260D01*
G02X322068Y1135039I-1181J-224D01*
G02X319664I-1202J0D01*
G02X319685Y1135260I1202J-3D01*
G01X319694Y1135309D01*
X319665Y1135403D01*
X319360Y1135708D01*
X319266Y1135737D01*
X319217Y1135728D01*
G02X318996Y1135707I-224J1181D01*
G01X318995D01*
G02X318841Y1135717I1J1202D01*
G01X318840D01*
G03X318671Y1135657I-25J-198D01*
G01X318414Y1135391D01*
X318386Y1135301D01*
X318394Y1135254D01*
G02X318412Y1135040I-1269J-214D01*
G01Y1135039D01*
G02X315838I-1287J0D01*
G01Y1135040D01*
G02X315856Y1135252I1287J-3D01*
G01Y1135254D01*
X315863Y1135301D01*
X315850Y1135345D01*
G03X315802Y1135426I-191J-59D01*
G01X315546Y1135692D01*
X315457Y1135723D01*
X315410Y1135717D01*
G02X315255Y1135707I-155J1192D01*
G02X315100Y1135717I0J1202D01*
G01X315053Y1135723D01*
X314964Y1135692D01*
X314708Y1135426D01*
G03X314660Y1135345I143J-140D01*
G01X314647Y1135301D01*
X314654Y1135254D01*
Y1135252D01*
G02X314672Y1135040I-1269J-215D01*
G01Y1135039D01*
G02X312098I-1287J0D01*
G01Y1135040D01*
G02X312116Y1135252I1287J-3D01*
G01Y1135254D01*
X312123Y1135301D01*
X312110Y1135345D01*
G03X312062Y1135426I-191J-59D01*
G01X311806Y1135692D01*
X311717Y1135723D01*
X311670Y1135717D01*
G02X311516Y1135707I-155J1192D01*
G01X311515D01*
G02X311294Y1135728I3J1202D01*
G01X311245Y1135737D01*
X311151Y1135708D01*
X310846Y1135403D01*
X310817Y1135309D01*
X310826Y1135260D01*
G02X310847Y1135039I-1181J-224D01*
G02X309645Y1136241I-1202J0D01*
G02X309866Y1136220I-3J-1202D01*
G01X309915Y1136211D01*
X310009Y1136240D01*
X310314Y1136545D01*
X310343Y1136639D01*
X310334Y1136688D01*
G02X310313Y1136909I1181J224D01*
G02X312717I1202J0D01*
G01Y1136908D01*
G02X312707Y1136754I-1202J1D01*
G01X312701Y1136707D01*
X312732Y1136618D01*
X312998Y1136362D01*
G03X313079Y1136314I140J143D01*
G01X313123Y1136301D01*
X313170Y1136308D01*
X313172D01*
G02X313384Y1136326I214J-1269D01*
G01X313386D01*
G02X313598Y1136308I-2J-1287D01*
G01X313600D01*
X313647Y1136301D01*
X313691Y1136314D01*
G03X313772Y1136362I-59J191D01*
G01X314038Y1136618D01*
X314069Y1136707D01*
X314063Y1136754D01*
G02X314053Y1136908I1192J155D01*
G01Y1136909D01*
G02X316457I1202J0D01*
G01Y1136908D01*
G02X316447Y1136754I-1202J1D01*
G01X316441Y1136707D01*
X316472Y1136618D01*
X316738Y1136362D01*
G03X316819Y1136314I140J143D01*
G01X316863Y1136301D01*
X316910Y1136308D01*
X316912D01*
G02X317124Y1136326I214J-1269D01*
G01X317126D01*
G02X317340Y1136308I0J-1287D01*
G01X317341D01*
G03X317512Y1136361I33J197D01*
G01X317744Y1136584D01*
G03X317806Y1136727I-138J145D01*
G01Y1136741D01*
X317804Y1136754D01*
G02X317794Y1136908I1192J155D01*
G01Y1136909D01*
G02X320198I1202J0D01*
G02X320177Y1136688I-1202J3D01*
G01X320168Y1136639D01*
X320197Y1136545D01*
X320502Y1136240D01*
X320596Y1136211D01*
X320645Y1136220D01*
G02X320866Y1136241I224J-1181D01*
G02X321087Y1136220I-3J-1202D01*
G01X321136Y1136211D01*
X321230Y1136240D01*
X321535Y1136545D01*
X321564Y1136639D01*
X321555Y1136688D01*
G02X321534Y1136909I1181J224D01*
G02X323938I1202J0D01*
G02X323917Y1136688I-1202J3D01*
G01X323908Y1136639D01*
X323937Y1136545D01*
X324242Y1136240D01*
X324336Y1136211D01*
X324385Y1136220D01*
G02X324606Y1136241I224J-1181D01*
G02X324827Y1136220I-3J-1202D01*
G01X324876Y1136211D01*
X324970Y1136240D01*
X325275Y1136545D01*
X325304Y1136639D01*
X325295Y1136688D01*
G02X325274Y1136909I1181J224D01*
G37*
G36*
G01X291613Y1140649D02*
G02X292815Y1139447I1202J0D01*
G02X292593Y1139468I2J1202D01*
G03X292497Y1139463I-38J-197D01*
G03X292414Y1139413I59J-191D01*
G01X292180Y1139179D01*
G03X292125Y1139001I142J-141D01*
G02X292146Y1138779I-1181J-224D01*
G02X289742I-1202J0D01*
G02X289763Y1139000I1202J-3D01*
G01X289772Y1139049D01*
X289743Y1139143D01*
X289438Y1139448D01*
X289344Y1139477D01*
X289295Y1139468D01*
G02X289074Y1139447I-224J1181D01*
G02X290276Y1140649I0J1202D01*
G02X290255Y1140428I-1202J3D01*
G01X290246Y1140379D01*
X290275Y1140285D01*
X290580Y1139980D01*
X290674Y1139951D01*
X290723Y1139960D01*
G02X290944Y1139981I224J-1181D01*
G02X291166Y1139960I-2J-1202D01*
G03X291262Y1139965I38J197D01*
G03X291345Y1140015I-59J191D01*
G01X291579Y1140249D01*
G03X291634Y1140427I-142J141D01*
G02X291613Y1140649I1181J224D01*
G37*
G36*
G01X367815Y1148843D02*
G02X367155Y1150087I842J1244D01*
G02X370159I1502J0D01*
G02X369499Y1148843I-1502J0D01*
G03Y1148181I224J-331D01*
G02X370159Y1146937I-842J-1244D01*
G02X367155I-1502J0D01*
G02X367815Y1148181I1502J0D01*
G03Y1148843I-224J331D01*
G37*
G36*
G01X352536Y1158666D02*
G02X354038Y1160168I0J1502D01*
G02X353924Y1159594I-1502J0D01*
G03X354320Y1159043I370J-152D01*
G02X354420Y1159046I95J-1499D01*
G02X352918Y1157544I0J-1502D01*
G02X353032Y1158118I1502J0D01*
G03X352636Y1158669I-370J152D01*
G02X352536Y1158666I-95J1499D01*
G37*
G36*
G01X507410Y794066D02*
G03X508072I331J224D01*
G02X509316Y794726I1244J-842D01*
G02Y791722I0J-1502D01*
G02X508072Y792382I0J1502D01*
G03X507410I-331J-224D01*
G02X506166Y791722I-1244J842D01*
G02Y794726I0J1502D01*
G02X507410Y794066I0J-1502D01*
G37*
G36*
G01X530268Y793807D02*
G02X529758Y794934I992J1128D01*
G02X532762I1502J0D01*
G02X532442Y794007I-1503J0D01*
G01X532441Y794005D01*
G03X532400Y793864I158J-122D01*
G01X532425Y793590D01*
G03X532446Y793520I199J22D01*
G01X532463Y793484D01*
X532493Y793458D01*
G02X533003Y792331I-992J-1128D01*
G02X529999I-1502J0D01*
G02X530319Y793258I1503J0D01*
G01X530320Y793260D01*
G03X530361Y793401I-158J122D01*
G01X530336Y793675D01*
G03X530315Y793745I-199J-22D01*
G01X530298Y793781D01*
X530268Y793807D01*
G37*
G36*
G01X556861Y795796D02*
G02X556739Y796389I1380J593D01*
G02X558241Y794887I1502J0D01*
G02X558109Y794893I2J1502D01*
G03X557706Y794336I-36J-398D01*
G02X557828Y793743I-1380J-593D01*
G02X556326Y795245I-1502J0D01*
G02X556458Y795239I-2J-1502D01*
G03X556861Y795796I36J398D01*
G37*
G36*
G01X520774Y797122D02*
X521159Y797294D01*
X521218Y797368D01*
X521228Y797415D01*
G02X522697Y798604I1469J-313D01*
G02Y795600I0J-1502D01*
G02X521950Y795799I0J1502D01*
G01X521908Y795823D01*
X521814Y795828D01*
X521429Y795656D01*
X521370Y795582D01*
X521360Y795535D01*
G02X521348Y795483I-1469J312D01*
G01Y795482D01*
G03X521350Y795379I194J-48D01*
G01Y795378D01*
G03X521406Y795287I192J55D01*
G01X521660Y795049D01*
G03X521753Y795000I136J146D01*
G01X521781Y794994D01*
X521833Y794996D01*
X521859Y795004D01*
G02X522316Y795076I459J-1430D01*
G02X520814Y793574I0J-1502D01*
G02X520859Y793939I1503J0D01*
G01Y793940D01*
G03X520857Y794043I-194J48D01*
G01Y794044D01*
G03X520801Y794135I-192J-55D01*
G01X520547Y794373D01*
G03X520454Y794422I-136J-146D01*
G01X520426Y794428D01*
X520374Y794426D01*
X520348Y794418D01*
G02X519891Y794346I-459J1430D01*
G02Y797350I0J1502D01*
G02X520638Y797151I0J-1502D01*
G01X520680Y797127D01*
X520774Y797122D01*
G37*
G36*
G01X519294Y805553D02*
X519307Y805595D01*
G02X520741Y806651I1434J-446D01*
G02Y803647I0J-1502D01*
G02X520136Y803774I-1J1502D01*
G01X520135Y803775D01*
X520133Y803776D01*
G03X519971Y803774I-79J-184D01*
G01X519659Y803632D01*
X519604Y803569D01*
X519591Y803527D01*
G02X518157Y802471I-1434J446D01*
G02Y805475I0J1502D01*
G02X518762Y805348I1J-1502D01*
G01X518763Y805347D01*
X518765Y805346D01*
G03X518927Y805348I79J184D01*
G01X519239Y805490D01*
X519294Y805553D01*
G37*
G36*
G01X566618Y804894D02*
G02X565814Y806224I698J1330D01*
G02X568818I1502J0D01*
G02X568206Y805014I-1502J0D01*
G03X568257Y804338I237J-322D01*
G02X569061Y803008I-698J-1330D01*
G02X566057I-1502J0D01*
G02X566669Y804218I1502J0D01*
G03X566618Y804894I-237J322D01*
G37*
G36*
G01X560267Y805579D02*
G02X559499Y806889I733J1310D01*
G02X562503I1502J0D01*
G02X561783Y805607I-1501J0D01*
G03X561795Y804916I208J-342D01*
G02X562563Y803606I-733J-1310D01*
G02X559559I-1502J0D01*
G02X560279Y804888I1501J0D01*
G03X560267Y805579I-208J342D01*
G37*
G36*
G01X519691Y813786D02*
G02X519676Y814001I1487J212D01*
G02X521178Y812499I1502J0D01*
G01X521177D01*
G02X520601Y812614I0J1502D01*
G03X520052Y812188I-153J-369D01*
G02X520067Y811973I-1487J-212D01*
G02X518565Y813475I-1502J0D01*
G01X518566D01*
G02X519142Y813360I0J-1502D01*
G03X519691Y813786I153J369D01*
G37*
G36*
G01X580159Y812879D02*
G02X579499Y814123I842J1244D01*
G02X582503I1502J0D01*
G02X581843Y812879I-1502J0D01*
G03Y812217I224J-331D01*
G02X582503Y810973I-842J-1244D01*
G02X579499I-1502J0D01*
G02X580159Y812217I1502J0D01*
G03Y812879I-224J331D01*
G37*
G36*
G01X530589Y814676D02*
X530560Y814708D01*
G02X530164Y815724I1105J1016D01*
G02X533168I1502J0D01*
G02X532493Y814470I-1502J0D01*
G01X532456Y814445D01*
X532410Y814371D01*
X532363Y813981D01*
X532390Y813898D01*
X532419Y813866D01*
G02X532815Y812850I-1105J-1016D01*
G02X529811I-1502J0D01*
G02X530486Y814104I1502J0D01*
G01X530523Y814129D01*
X530569Y814203D01*
X530616Y814593D01*
X530589Y814676D01*
G37*
G36*
G01X566529Y826445D02*
G02X565814Y827724I786J1279D01*
G02X568818I1502J0D01*
G02X568295Y826585I-1502J0D01*
G03X568346Y825940I260J-304D01*
G02X569061Y824661I-786J-1279D01*
G02X566057I-1502J0D01*
G02X566580Y825800I1502J0D01*
G03X566529Y826445I-260J304D01*
G37*
G36*
G01X546855Y828447D02*
G02Y831451I0J1502D01*
G02X548159Y830695I0J-1503D01*
G03X548838Y830671I347J199D01*
G02X550087Y831338I1249J-836D01*
G02Y828334I0J-1502D01*
G02X548783Y829090I0J1503D01*
G03X548104Y829114I-347J-199D01*
G02X546855Y828447I-1249J836D01*
G37*
G36*
G01X560263Y828487D02*
G02Y831491I0J1502D01*
G02X561399Y830971I-1J-1502D01*
G01X561428Y830939D01*
X561504Y830903D01*
X561888Y830897D01*
X561966Y830930D01*
X561995Y830962D01*
G02X563099Y831445I1104J-1020D01*
G02Y828441I0J-1502D01*
G02X561963Y828961I1J1502D01*
G01X561934Y828993D01*
X561858Y829029D01*
X561474Y829035D01*
X561396Y829002D01*
X561367Y828970D01*
G02X560263Y828487I-1104J1020D01*
G37*
G36*
G01X534000Y841498D02*
G02Y844502I0J1502D01*
G02X535326Y843706I0J-1502D01*
G03X536020Y843685I353J188D01*
G02X537300Y844402I1280J-784D01*
G02Y841398I0J-1502D01*
G02X535974Y842194I0J1502D01*
G03X535280Y842215I-353J-188D01*
G02X534000Y841498I-1280J784D01*
G37*
G36*
G01X571549Y844353D02*
G02X570974Y845535I927J1182D01*
G02X573978I1502J0D01*
G02X573162Y844199I-1502J0D01*
G03X573098Y843528I182J-356D01*
G02X573673Y842346I-927J-1182D01*
G02X570669I-1502J0D01*
G02X571485Y843682I1502J0D01*
G03X571549Y844353I-182J356D01*
G37*
G36*
G01X525718Y872319D02*
G02Y875323I0J1502D01*
G02X526999Y874606I0J-1503D01*
G03X527661Y874577I341J209D01*
G02X528868Y875185I1207J-894D01*
G02Y872181I0J-1502D01*
G02X527587Y872898I0J1503D01*
G03X526925Y872927I-341J-209D01*
G02X525718Y872319I-1207J894D01*
G37*
G36*
G01X547598Y876674D02*
G02X547019Y877859I923J1185D01*
G02X550023I1502J0D01*
G02X549444Y876674I-1502J0D01*
G03X549369Y876546I123J-158D01*
G03X549367Y876516I198J-28D01*
G01Y876202D01*
G03X549369Y876172I200J-2D01*
G03X549444Y876044I198J30D01*
G02X550023Y874859I-923J-1185D01*
G02X547019I-1502J0D01*
G02X547598Y876044I1502J0D01*
G03X547673Y876172I-123J158D01*
G03X547675Y876202I-198J28D01*
G01Y876516D01*
G03X547673Y876546I-200J2D01*
G03X547598Y876674I-198J-30D01*
G37*
G36*
G01X568075Y886911D02*
Y886913D01*
G02X569577Y885411I1502J0D01*
G02X569465Y885415I-2J1502D01*
G03X569097Y884803I-30J-399D01*
G02X569329Y884002I-1270J-802D01*
G01Y884000D01*
G02X567827Y885502I-1502J0D01*
G02X567939Y885498I2J-1502D01*
G03X568307Y886110I30J399D01*
G02X568075Y886911I1270J802D01*
G37*
G36*
G01X525159Y912316D02*
G02X526661Y913818I0J1502D01*
G02X526610Y913431I-1502J1D01*
G03X527070Y912934I387J-104D01*
G02X527346Y912960I278J-1476D01*
G02X525844Y911458I0J-1502D01*
G02X525895Y911845I1502J-1D01*
G03X525435Y912342I-387J104D01*
G02X525159Y912316I-278J1476D01*
G37*
G36*
G01X520146Y937739D02*
G02Y940743I0J1502D01*
G02X521399Y940069I0J-1502D01*
G03X522060Y940059I334J220D01*
G02X523289Y940697I1229J-865D01*
G02Y937693I0J-1502D01*
G02X522036Y938367I0J1502D01*
G03X521375Y938377I-334J-220D01*
G02X520146Y937739I-1229J865D01*
G37*
G36*
G01X568017Y952593D02*
G03X568173Y952669I-1J200D01*
G03X568179Y952677I-157J124D01*
G02X569403Y953309I1224J-869D01*
G02Y950305I0J-1502D01*
G02X568179Y950937I0J1501D01*
G03X568173Y950945I-163J-116D01*
G03X568017Y951021I-157J-124D01*
G01X567690D01*
X567689D01*
G03X567533Y950945I1J-200D01*
G03X567527Y950937I157J-124D01*
G02X566303Y950305I-1224J869D01*
G02X565039Y950995I0J1503D01*
G03X564871Y951087I-168J-108D01*
G01X564535D01*
G03X564367Y950995I0J-200D01*
G02X563103Y950305I-1264J813D01*
G02Y953309I0J1502D01*
G02X564367Y952619I0J-1503D01*
G03X564535Y952527I168J108D01*
G01X564871D01*
G03X565039Y952619I0J200D01*
G02X566303Y953309I1264J-813D01*
G02X567527Y952677I0J-1501D01*
G03X567533Y952669I163J116D01*
G03X567689Y952593I157J124D01*
G01X568016D01*
X568017D01*
G37*
G36*
G01X522579Y953134D02*
G03X523236Y953139I327J231D01*
G02X524475Y953792I1239J-849D01*
G02Y950788I0J-1502D01*
G02X523249Y951422I0J1502D01*
G03X522592Y951417I-327J-231D01*
G02X521353Y950764I-1239J849D01*
G02Y953768I0J1502D01*
G02X522579Y953134I0J-1502D01*
G37*
G36*
G01X575193Y966075D02*
G03X575898Y966102I345J202D01*
G02X577249Y966947I1351J-658D01*
G02Y963943I0J-1502D01*
G02X575951Y964689I0J1502D01*
G03X575246Y964662I-345J-202D01*
G02X573895Y963817I-1351J658D01*
G02Y966821I0J1502D01*
G02X575193Y966075I0J-1502D01*
G37*
G36*
G01X456224Y975298D02*
X456680Y975309D01*
X456771Y975365D01*
X456797Y975413D01*
G02X458120Y976203I1323J-713D01*
G02Y973199I0J-1502D01*
G02X456833Y973927I0J1502D01*
G01X456805Y973973D01*
X456711Y974025D01*
X456255Y974014D01*
X456164Y973958D01*
X456138Y973910D01*
G02X454815Y973120I-1323J713D01*
G02X453475Y973944I0J1502D01*
G01X453450Y973994D01*
X453357Y974052D01*
X452948Y974061D01*
G03X452770Y973960I-4J-200D01*
G01X452769Y973959D01*
Y973958D01*
G02X451460Y973193I-1309J737D01*
G02Y976197I0J1502D01*
G02X452800Y975373I0J-1502D01*
G01X452825Y975323D01*
X452918Y975265D01*
X453327Y975256D01*
G03X453505Y975357I4J200D01*
G01X453506Y975358D01*
Y975359D01*
G02X454815Y976124I1309J-737D01*
G02X456102Y975396I0J-1502D01*
G01X456130Y975350D01*
X456224Y975298D01*
G37*
G36*
G01X549486Y1007361D02*
G03X550173Y1007380I338J214D01*
G02X551485Y1008150I1312J-733D01*
G02Y1005146I0J-1502D01*
G02X550214Y1005847I0J1503D01*
G03X549527Y1005828I-338J-214D01*
G02X548215Y1005058I-1312J733D01*
G02Y1008062I0J1502D01*
G02X549486Y1007361I0J-1503D01*
G37*
G36*
G01X559806Y1010672D02*
G02X560911Y1011157I1105J-1017D01*
G01X560912D01*
G02Y1008153I0J-1502D01*
G01X560911D01*
G02X559806Y1008638I0J1502D01*
G03X559658Y1008703I-148J-135D01*
G01X559366D01*
G03X559218Y1008638I0J-200D01*
G02X558113Y1008153I-1105J1017D01*
G01X558112D01*
G02Y1011157I0J1502D01*
G01X558113D01*
G02X559218Y1010672I0J-1502D01*
G03X559366Y1010607I148J135D01*
G01X559658D01*
G03X559806Y1010672I0J200D01*
G37*
G36*
G01X592707Y1011157D02*
G02X592111Y1012354I906J1198D01*
G02X595115I1502J0D01*
G02X594554Y1011183I-1503J0D01*
G01X594518Y1011154D01*
X594479Y1011071D01*
X594484Y1010708D01*
G03X594506Y1010621I200J4D01*
G01X594526Y1010581D01*
X594563Y1010552D01*
X594564Y1010551D01*
G02X595160Y1009354I-906J-1198D01*
G02X592156I-1502J0D01*
G02X592717Y1010525I1503J0D01*
G01X592753Y1010554D01*
X592792Y1010637D01*
X592787Y1011000D01*
G03X592765Y1011087I-200J-4D01*
G01X592745Y1011127D01*
X592708Y1011156D01*
X592707Y1011157D01*
G37*
G36*
G01X445626Y1112565D02*
X445290D01*
X445223Y1112540D01*
X445195Y1112516D01*
G02X444208Y1112146I-987J1131D01*
G02Y1115150I0J1502D01*
G02X445195Y1114780I0J-1501D01*
G01X445223Y1114756D01*
X445290Y1114731D01*
X445626D01*
X445693Y1114756D01*
X445721Y1114780D01*
G02X446708Y1115150I987J-1131D01*
G02Y1112146I0J-1502D01*
G02X445721Y1112516I0J1501D01*
G01X445693Y1112540D01*
X445626Y1112565D01*
G37*
G36*
G01X642105Y1221062D02*
G02X643307Y1219860I1202J0D01*
G02X643085Y1219881I2J1202D01*
G01X643036Y1219890D01*
X642943Y1219861D01*
X642638Y1219556D01*
X642609Y1219463D01*
X642618Y1219414D01*
G02X642639Y1219192I-1181J-224D01*
G02X640235I-1202J0D01*
G02X640256Y1219414I1202J-2D01*
G01X640265Y1219463D01*
X640236Y1219556D01*
X639931Y1219861D01*
X639838Y1219890D01*
X639789Y1219881D01*
G02X639567Y1219860I-224J1181D01*
G02X640769Y1221062I0J1202D01*
G02X640748Y1220840I-1202J2D01*
G01X640739Y1220791D01*
X640768Y1220698D01*
X641073Y1220393D01*
X641166Y1220364D01*
X641215Y1220373D01*
G02X641437Y1220394I224J-1181D01*
G02X641659Y1220373I-2J-1202D01*
G01X641708Y1220364D01*
X641801Y1220393D01*
X642106Y1220698D01*
X642135Y1220791D01*
X642126Y1220840D01*
G02X642105Y1221062I1181J224D01*
G37*
G36*
G01X635827Y1193679D02*
G02X637029Y1194881I0J1202D01*
G02X637008Y1194659I-1202J2D01*
G01X636999Y1194610D01*
X637028Y1194517D01*
X637333Y1194212D01*
X637426Y1194183D01*
X637475Y1194192D01*
G02X637697Y1194213I224J-1181D01*
G02Y1191809I0J-1202D01*
G02X637475Y1191830I2J1202D01*
G01X637426Y1191839D01*
X637333Y1191810D01*
X637028Y1191505D01*
X636999Y1191412D01*
X637008Y1191363D01*
G02X637029Y1191141I-1181J-224D01*
G02X637008Y1190919I-1202J2D01*
G01X636999Y1190870D01*
X637028Y1190777D01*
X637333Y1190472D01*
X637426Y1190443D01*
X637475Y1190452D01*
G02X637697Y1190473I224J-1181D01*
G02Y1188069I0J-1202D01*
G02X637475Y1188090I2J1202D01*
G01X637426Y1188099D01*
X637333Y1188070D01*
X637028Y1187765D01*
X636999Y1187672D01*
X637008Y1187623D01*
G02X637029Y1187401I-1181J-224D01*
G02X637008Y1187179I-1202J2D01*
G01X636999Y1187130D01*
X637028Y1187037D01*
X637333Y1186732D01*
X637426Y1186703D01*
X637475Y1186712D01*
G02X637697Y1186733I224J-1181D01*
G02X636495Y1185531I0J-1202D01*
G02X636516Y1185753I1202J-2D01*
G01X636525Y1185802D01*
X636496Y1185895D01*
X636191Y1186200D01*
X636098Y1186229D01*
X636049Y1186220D01*
G02X635827Y1186199I-224J1181D01*
G02X635605Y1186220I2J1202D01*
G01X635556Y1186229D01*
X635463Y1186200D01*
X635158Y1185895D01*
X635129Y1185802D01*
X635138Y1185753D01*
G02X635159Y1185531I-1181J-224D01*
G02X632755I-1202J0D01*
G02X632776Y1185752I1202J-3D01*
G01Y1185754D01*
G03X632721Y1185931I-197J36D01*
G01X632451Y1186200D01*
X632358Y1186229D01*
X632309Y1186220D01*
G02X632086Y1186199I-224J1181D01*
G02X633288Y1187401I0J1202D01*
G02X633267Y1187180I-1202J3D01*
G01Y1187178D01*
G03X633322Y1187001I197J-36D01*
G01X633592Y1186732D01*
X633685Y1186703D01*
X633734Y1186712D01*
G02X633957Y1186733I224J-1181D01*
G02X634179Y1186712I-2J-1202D01*
G01X634228Y1186703D01*
X634321Y1186732D01*
X634626Y1187037D01*
X634655Y1187130D01*
X634646Y1187179D01*
G02X634625Y1187401I1181J224D01*
G02X635827Y1188603I1202J0D01*
G02X636049Y1188582I-2J-1202D01*
G01X636098Y1188573D01*
X636191Y1188602D01*
X636496Y1188907D01*
X636525Y1189000D01*
X636516Y1189049D01*
G02X636495Y1189271I1181J224D01*
G02X636516Y1189493I1202J-2D01*
G01X636525Y1189542D01*
X636496Y1189635D01*
X636191Y1189940D01*
X636098Y1189969D01*
X636049Y1189960D01*
G02X635827Y1189939I-224J1181D01*
G02Y1192343I0J1202D01*
G02X636049Y1192322I-2J-1202D01*
G01X636098Y1192313D01*
X636191Y1192342D01*
X636496Y1192647D01*
X636525Y1192740D01*
X636516Y1192789D01*
G02X636495Y1193011I1181J224D01*
G02X636516Y1193233I1202J-2D01*
G01X636525Y1193282D01*
X636496Y1193375D01*
X636191Y1193680D01*
X636098Y1193709D01*
X636049Y1193700D01*
G02X635827Y1193679I-224J1181D01*
G37*
G36*
G01X628568Y1182480D02*
G02X628346Y1182459I-224J1181D01*
G02X629548Y1183661I0J1202D01*
G02X629527Y1183439I-1202J2D01*
G03X629994Y1182972I393J-74D01*
G02X630216Y1182993I224J-1181D01*
G02X629014Y1181791I0J-1202D01*
G02X629035Y1182013I1202J-2D01*
G03X628568Y1182480I-393J74D01*
G37*
G36*
G01X519249Y1212117D02*
G02X522253I1502J0D01*
G02X521883Y1211130I-1501J0D01*
G01Y1211129D01*
X521882D01*
G03X521834Y1210999I152J-130D01*
G01Y1210735D01*
G03X521882Y1210605I200J0D01*
G01X521883Y1210604D01*
G02Y1208630I-1131J-987D01*
G01Y1208629D01*
X521882D01*
G03X521834Y1208499I152J-130D01*
G01Y1208235D01*
G03X521882Y1208105I200J0D01*
G01X521883Y1208104D01*
G02Y1206130I-1131J-987D01*
G01Y1206129D01*
X521882D01*
G03X521834Y1205999I152J-130D01*
G01Y1205735D01*
G03X521882Y1205605I200J0D01*
G01X521883Y1205604D01*
G02X522253Y1204617I-1131J-987D01*
G02X519249I-1502J0D01*
G02X519619Y1205604I1501J0D01*
G01Y1205605D01*
X519620D01*
G03X519668Y1205735I-152J130D01*
G01Y1205999D01*
G03X519620Y1206129I-200J0D01*
G01X519619Y1206130D01*
G02Y1208104I1131J987D01*
G01Y1208105D01*
X519620D01*
G03X519668Y1208235I-152J130D01*
G01Y1208499D01*
G03X519620Y1208629I-200J0D01*
G01X519619Y1208630D01*
G02Y1210604I1131J987D01*
G01Y1210605D01*
X519620D01*
G03X519668Y1210735I-152J130D01*
G01Y1210999D01*
G03X519620Y1211129I-200J0D01*
G01X519619Y1211130D01*
G02X519249Y1212117I1131J987D01*
G37*
G36*
G01X492319D02*
G02X495323I1502J0D01*
G02X494953Y1211130I-1501J0D01*
G01Y1211129D01*
X494952D01*
G03X494904Y1210999I152J-130D01*
G01Y1210735D01*
G03X494952Y1210605I200J0D01*
G01X494953Y1210604D01*
G02Y1208630I-1131J-987D01*
G01Y1208629D01*
X494952D01*
G03X494904Y1208499I152J-130D01*
G01Y1208235D01*
G03X494952Y1208105I200J0D01*
G01X494953Y1208104D01*
G02Y1206130I-1131J-987D01*
G01Y1206129D01*
X494952D01*
G03X494904Y1205999I152J-130D01*
G01Y1205735D01*
G03X494952Y1205605I200J0D01*
G01X494953Y1205604D01*
G02X495323Y1204617I-1131J-987D01*
G02X492319I-1502J0D01*
G02X492689Y1205604I1501J0D01*
G01Y1205605D01*
X492690D01*
G03X492738Y1205735I-152J130D01*
G01Y1205999D01*
G03X492690Y1206129I-200J0D01*
G01X492689Y1206130D01*
G02Y1208104I1131J987D01*
G01Y1208105D01*
X492690D01*
G03X492738Y1208235I-152J130D01*
G01Y1208499D01*
G03X492690Y1208629I-200J0D01*
G01X492689Y1208630D01*
G02Y1210604I1131J987D01*
G01Y1210605D01*
X492690D01*
G03X492738Y1210735I-152J130D01*
G01Y1210999D01*
G03X492690Y1211129I-200J0D01*
G01X492689Y1211130D01*
G02X492319Y1212117I1131J987D01*
G37*
G36*
G01X504949Y1211905D02*
G02X507953I1502J0D01*
G02X507583Y1210918I-1501J0D01*
G01Y1210917D01*
X507582D01*
G03X507534Y1210787I152J-130D01*
G01Y1210523D01*
G03X507582Y1210393I200J0D01*
G01X507583Y1210392D01*
G02Y1208418I-1131J-987D01*
G01Y1208417D01*
X507582D01*
G03X507534Y1208287I152J-130D01*
G01Y1208023D01*
G03X507582Y1207893I200J0D01*
G01X507583Y1207892D01*
G02Y1205918I-1131J-987D01*
G01Y1205917D01*
X507582D01*
G03X507534Y1205787I152J-130D01*
G01Y1205523D01*
G03X507582Y1205393I200J0D01*
G01X507583Y1205392D01*
G02X507953Y1204405I-1131J-987D01*
G02X504949I-1502J0D01*
G02X505319Y1205392I1501J0D01*
G01Y1205393D01*
X505320D01*
G03X505368Y1205523I-152J130D01*
G01Y1205787D01*
G03X505320Y1205917I-200J0D01*
G01X505319Y1205918D01*
G02Y1207892I1131J987D01*
G01Y1207893D01*
X505320D01*
G03X505368Y1208023I-152J130D01*
G01Y1208287D01*
G03X505320Y1208417I-200J0D01*
G01X505319Y1208418D01*
G02Y1210392I1131J987D01*
G01Y1210393D01*
X505320D01*
G03X505368Y1210523I-152J130D01*
G01Y1210787D01*
G03X505320Y1210917I-200J0D01*
G01X505319Y1210918D01*
G02X504949Y1211905I1131J987D01*
G37*
G36*
G01X478019D02*
G02X481023I1502J0D01*
G02X480653Y1210918I-1501J0D01*
G01Y1210917D01*
X480652D01*
G03X480604Y1210787I152J-130D01*
G01Y1210523D01*
G03X480652Y1210393I200J0D01*
G01X480653Y1210392D01*
G02Y1208418I-1131J-987D01*
G01Y1208417D01*
X480652D01*
G03X480604Y1208287I152J-130D01*
G01Y1208023D01*
G03X480652Y1207893I200J0D01*
G01X480653Y1207892D01*
G02Y1205918I-1131J-987D01*
G01Y1205917D01*
X480652D01*
G03X480604Y1205787I152J-130D01*
G01Y1205523D01*
G03X480652Y1205393I200J0D01*
G01X480653Y1205392D01*
G02X481023Y1204405I-1131J-987D01*
G02X478019I-1502J0D01*
G02X478389Y1205392I1501J0D01*
G01Y1205393D01*
X478390D01*
G03X478438Y1205523I-152J130D01*
G01Y1205787D01*
G03X478390Y1205917I-200J0D01*
G01X478389Y1205918D01*
G02Y1207892I1131J987D01*
G01Y1207893D01*
X478390D01*
G03X478438Y1208023I-152J130D01*
G01Y1208287D01*
G03X478390Y1208417I-200J0D01*
G01X478389Y1208418D01*
G02Y1210392I1131J987D01*
G01Y1210393D01*
X478390D01*
G03X478438Y1210523I-152J130D01*
G01Y1210787D01*
G03X478390Y1210917I-200J0D01*
G01X478389Y1210918D01*
G02X478019Y1211905I1131J987D01*
G37*
G36*
G01X566502Y1200601D02*
G02X568004Y1202103I0J1502D01*
G02X567995Y1201941I-1502J2D01*
G01X567990Y1201897D01*
X568019Y1201813D01*
X568295Y1201527D01*
X568378Y1201496D01*
X568422Y1201499D01*
G02X568531Y1201503I110J-1498D01*
G01X568532D01*
G02X567030Y1200001I0J-1502D01*
G02X567039Y1200163I1502J-2D01*
G01X567044Y1200207D01*
X567015Y1200291D01*
X566739Y1200577D01*
X566656Y1200608D01*
X566612Y1200605D01*
G02X566503Y1200601I-110J1498D01*
G01X566502D01*
G37*
G36*
G01X521564Y1200821D02*
G02X524568I1502J0D01*
G02X524198Y1199834I-1501J0D01*
G01Y1199833D01*
X524197D01*
G03X524149Y1199703I152J-130D01*
G01Y1199439D01*
G03X524197Y1199309I200J0D01*
G01X524198Y1199308D01*
G02X524568Y1198321I-1131J-987D01*
G02X521564I-1502J0D01*
G02X521934Y1199308I1501J0D01*
G01Y1199309D01*
X521935D01*
G03X521983Y1199439I-152J130D01*
G01Y1199703D01*
G03X521935Y1199833I-200J0D01*
G01X521934Y1199834D01*
G02X521564Y1200821I1131J987D01*
G37*
G36*
G01X502634D02*
G02X505638I1502J0D01*
G02X505268Y1199834I-1501J0D01*
G01Y1199833D01*
X505267D01*
G03X505219Y1199703I152J-130D01*
G01Y1199439D01*
G03X505267Y1199309I200J0D01*
G01X505268Y1199308D01*
G02X505638Y1198321I-1131J-987D01*
G02X502634I-1502J0D01*
G02X503004Y1199308I1501J0D01*
G01Y1199309D01*
X503005D01*
G03X503053Y1199439I-152J130D01*
G01Y1199703D01*
G03X503005Y1199833I-200J0D01*
G01X503004Y1199834D01*
G02X502634Y1200821I1131J987D01*
G37*
G36*
G01X494634D02*
G02X497638I1502J0D01*
G02X497268Y1199834I-1501J0D01*
G01Y1199833D01*
X497267D01*
G03X497219Y1199703I152J-130D01*
G01Y1199439D01*
G03X497267Y1199309I200J0D01*
G01X497268Y1199308D01*
G02X497638Y1198321I-1131J-987D01*
G02X494634I-1502J0D01*
G02X495004Y1199308I1501J0D01*
G01Y1199309D01*
X495005D01*
G03X495053Y1199439I-152J130D01*
G01Y1199703D01*
G03X495005Y1199833I-200J0D01*
G01X495004Y1199834D01*
G02X494634Y1200821I1131J987D01*
G37*
G36*
G01X489169D02*
G02X492173I1502J0D01*
G02X491803Y1199834I-1501J0D01*
G01Y1199833D01*
X491802D01*
G03X491754Y1199703I152J-130D01*
G01Y1199439D01*
G03X491802Y1199309I200J0D01*
G01X491803Y1199308D01*
G02X492173Y1198321I-1131J-987D01*
G02X489169I-1502J0D01*
G02X489539Y1199308I1501J0D01*
G01Y1199309D01*
X489540D01*
G03X489588Y1199439I-152J130D01*
G01Y1199703D01*
G03X489540Y1199833I-200J0D01*
G01X489539Y1199834D01*
G02X489169Y1200821I1131J987D01*
G37*
G36*
G01X475704D02*
G02X478708I1502J0D01*
G02X478338Y1199834I-1501J0D01*
G01Y1199833D01*
X478337D01*
G03X478289Y1199703I152J-130D01*
G01Y1199439D01*
G03X478337Y1199309I200J0D01*
G01X478338Y1199308D01*
G02X478708Y1198321I-1131J-987D01*
G02X475704I-1502J0D01*
G02X476074Y1199308I1501J0D01*
G01Y1199309D01*
X476075D01*
G03X476123Y1199439I-152J130D01*
G01Y1199703D01*
G03X476075Y1199833I-200J0D01*
G01X476074Y1199834D01*
G02X475704Y1200821I1131J987D01*
G37*
G36*
G01X580465Y1180691D02*
G02X583469I1502J0D01*
G02X582908Y1179520I-1503J0D01*
G01X582872Y1179491D01*
X582833Y1179408D01*
X582838Y1179046D01*
G03X582917Y1178889I200J2D01*
G02X583514Y1177691I-905J-1199D01*
G02X580510I-1502J0D01*
G02X581071Y1178862I1503J0D01*
G01X581107Y1178891D01*
X581146Y1178974D01*
X581141Y1179336D01*
G03X581062Y1179493I-200J-2D01*
G02X580465Y1180691I905J1199D01*
G37*
G36*
G01X612184Y1179921D02*
G02X614588I1202J0D01*
G02X614581Y1179796I-1202J5D01*
G01Y1179794D01*
X614577Y1179753D01*
X614603Y1179673D01*
X614830Y1179420D01*
G03X614979Y1179354I149J134D01*
G01X615256D01*
G02Y1176748I0J-1303D01*
G01X611516D01*
G02Y1179354I0J1303D01*
G01X611793D01*
G03X611942Y1179420I0J200D01*
G01X612169Y1179673D01*
X612195Y1179753D01*
X612191Y1179795D01*
G02X612184Y1179921I1195J130D01*
G37*
G36*
G01X600294Y1179354D02*
X604034D01*
G02Y1176748I0J-1303D01*
G01X600294D01*
G02X599288Y1177224I1J1303D01*
G01X599260Y1177258D01*
X599182Y1177296D01*
X598835Y1177305D01*
G03X598684Y1177241I-4J-200D01*
G01X598683Y1177240D01*
G02X597795Y1176848I-888J810D01*
G02Y1179252I0J1202D01*
G02X598682Y1178861I0J-1202D01*
G03X598835Y1178795I149J134D01*
G01X599137Y1178804D01*
G03X599287Y1178877I-4J200D01*
G02X600294Y1179354I1008J-826D01*
G37*
G36*
G01Y1171872D02*
X604034D01*
G02Y1169268I0J-1302D01*
G01X600294D01*
G02X599287Y1169744I0J1303D01*
G01X599259Y1169778D01*
X599182Y1169815D01*
X598791Y1169826D01*
X598712Y1169792D01*
X598683Y1169760D01*
G02X597795Y1169368I-888J810D01*
G02Y1171772I0J1202D01*
G02X598683Y1171380I0J-1202D01*
G01X598712Y1171348D01*
X598791Y1171314D01*
X599138Y1171324D01*
G03X599287Y1171396I-5J200D01*
G02X600294Y1171872I1007J-827D01*
G37*
G36*
G01X580465Y1168091D02*
G02X583469I1502J0D01*
G02X582908Y1166920I-1503J0D01*
G01X582872Y1166891D01*
X582833Y1166808D01*
X582838Y1166446D01*
G03X582917Y1166289I200J2D01*
G02X583514Y1165091I-905J-1199D01*
G02X580510I-1502J0D01*
G02X581071Y1166262I1503J0D01*
G01X581107Y1166291D01*
X581146Y1166374D01*
X581141Y1166736D01*
G03X581062Y1166893I-200J-2D01*
G02X580465Y1168091I905J1199D01*
G37*
G36*
G01Y1142891D02*
G02X583469I1502J0D01*
G02X582908Y1141720I-1503J0D01*
G01X582872Y1141691D01*
X582833Y1141608D01*
X582838Y1141246D01*
G03X582917Y1141089I200J2D01*
G02X583514Y1139891I-905J-1199D01*
G02X580510I-1502J0D01*
G02X581071Y1141062I1503J0D01*
G01X581107Y1141091D01*
X581146Y1141174D01*
X581141Y1141536D01*
G03X581062Y1141693I-200J-2D01*
G02X580465Y1142891I905J1199D01*
G37*
G36*
G01Y1155491D02*
G02X583469I1502J0D01*
G02X582908Y1154320I-1503J0D01*
G01X582872Y1154291D01*
X582833Y1154208D01*
X582838Y1153846D01*
G03X582917Y1153689I200J2D01*
G02X583514Y1152491I-905J-1199D01*
G02X580510I-1502J0D01*
G02X581071Y1153662I1503J0D01*
G01X581107Y1153691D01*
X581146Y1153774D01*
X581141Y1154136D01*
G03X581062Y1154293I-200J-2D01*
G02X580465Y1155491I905J1199D01*
G37*
G36*
G01Y1105091D02*
G02X583469I1502J0D01*
G02X582908Y1103920I-1503J0D01*
G01X582872Y1103891D01*
X582833Y1103808D01*
X582838Y1103446D01*
G03X582917Y1103289I200J2D01*
G02X583514Y1102091I-905J-1199D01*
G02X580510I-1502J0D01*
G02X581071Y1103262I1503J0D01*
G01X581107Y1103291D01*
X581146Y1103374D01*
X581141Y1103736D01*
G03X581062Y1103893I-200J-2D01*
G02X580465Y1105091I905J1199D01*
G37*
G36*
G01Y1117691D02*
G02X583469I1502J0D01*
G02X582908Y1116520I-1503J0D01*
G01X582872Y1116491D01*
X582833Y1116408D01*
X582838Y1116046D01*
G03X582917Y1115889I200J2D01*
G02X583514Y1114691I-905J-1199D01*
G02X580510I-1502J0D01*
G02X581071Y1115862I1503J0D01*
G01X581107Y1115891D01*
X581146Y1115974D01*
X581141Y1116336D01*
G03X581062Y1116493I-200J-2D01*
G02X580465Y1117691I905J1199D01*
G37*
G36*
G01X592792Y1023237D02*
X592786Y1023646D01*
X592745Y1023727D01*
X592708Y1023756D01*
G02X592111Y1024954I905J1199D01*
G02X595115I1502J0D01*
G02X594554Y1023783I-1503J0D01*
G01X594518Y1023754D01*
X594479Y1023671D01*
X594485Y1023262D01*
X594526Y1023181D01*
X594563Y1023152D01*
G02X595160Y1021954I-905J-1199D01*
G02X592156I-1502J0D01*
G02X592717Y1023125I1503J0D01*
G01X592753Y1023154D01*
X592792Y1023237D01*
G37*
G36*
G01X566715Y1029826D02*
X566399D01*
G03X566242Y1029749I1J-200D01*
G02X565057Y1029170I-1185J923D01*
G02Y1032174I0J1502D01*
G02X566242Y1031595I0J-1502D01*
G03X566399Y1031518I158J123D01*
G01X566715D01*
G03X566872Y1031595I-1J200D01*
G02X568057Y1032174I1185J-923D01*
G02Y1029170I0J-1502D01*
G02X566872Y1029749I0J1502D01*
G03X566715Y1029826I-158J-123D01*
G37*
G36*
G01X636525Y1110457D02*
X636516Y1110506D01*
G02X636495Y1110728I1181J224D01*
G02X638899I1202J0D01*
G02X638878Y1110506I-1202J2D01*
G01X638869Y1110457D01*
X638898Y1110364D01*
X639203Y1110059D01*
X639296Y1110030D01*
X639345Y1110039D01*
G02X639567Y1110060I224J-1181D01*
G02X638365Y1108858I0J-1202D01*
G02X638386Y1109080I1202J-2D01*
G01X638395Y1109129D01*
X638366Y1109222D01*
X638061Y1109527D01*
X637968Y1109556D01*
X637919Y1109547D01*
G02X637697Y1109526I-224J1181D01*
G02X637475Y1109547I2J1202D01*
G01X637426Y1109556D01*
X637333Y1109527D01*
X637028Y1109222D01*
X636999Y1109129D01*
X637008Y1109080D01*
G02X637029Y1108858I-1181J-224D01*
G02X634625I-1202J0D01*
G02X634646Y1109080I1202J-2D01*
G01X634655Y1109129D01*
X634626Y1109222D01*
X634321Y1109527D01*
X634228Y1109556D01*
X634179Y1109547D01*
G02X633957Y1109526I-224J1181D01*
G02X633734Y1109547I1J1202D01*
G01X633686Y1109556D01*
X633591Y1109527D01*
X633287Y1109223D01*
X633258Y1109129D01*
X633267Y1109080D01*
G02X633288Y1108858I-1181J-224D01*
G02X630884I-1202J0D01*
G02X630905Y1109080I1202J-2D01*
G01X630914Y1109129D01*
X630885Y1109222D01*
X630580Y1109527D01*
X630487Y1109556D01*
X630438Y1109547D01*
G02X630216Y1109526I-224J1181D01*
G02X631418Y1110728I0J1202D01*
G02X631397Y1110506I-1202J2D01*
G01X631388Y1110457D01*
X631417Y1110364D01*
X631722Y1110059D01*
X631815Y1110030D01*
X631864Y1110039D01*
G02X632086Y1110060I224J-1181D01*
G02X632309Y1110039I-1J-1202D01*
G01X632357Y1110030D01*
X632452Y1110059D01*
X632756Y1110363D01*
X632785Y1110457D01*
X632776Y1110506D01*
G02X632755Y1110728I1181J224D01*
G02X635159I1202J0D01*
G02X635138Y1110506I-1202J2D01*
G01X635129Y1110457D01*
X635158Y1110364D01*
X635463Y1110059D01*
X635556Y1110030D01*
X635605Y1110039D01*
G02X635827Y1110060I224J-1181D01*
G02X636049Y1110039I-2J-1202D01*
G01X636098Y1110030D01*
X636191Y1110059D01*
X636496Y1110364D01*
X636525Y1110457D01*
G37*
G36*
G01X850653Y1008472D02*
X850866Y1008828D01*
X850873Y1008920D01*
X850855Y1008965D01*
G02X850745Y1009529I1391J564D01*
G02X853749I1502J0D01*
G02X853653Y1009001I-1502J0D01*
G01X853638Y1008961D01*
X853642Y1008881D01*
X853805Y1008545D01*
X853866Y1008492D01*
X853906Y1008479D01*
G02X854951Y1007048I-457J-1431D01*
G02X853449Y1005546I-1502J0D01*
G02X852405Y1005969I1J1502D01*
G01X852374Y1005998D01*
X852299Y1006026D01*
X851924Y1006010D01*
X851851Y1005974D01*
X851824Y1005942D01*
G02X850686Y1005421I-1138J982D01*
G02X849184Y1006923I0J1502D01*
G02X850527Y1008417I1502J0D01*
G01X850574Y1008422D01*
X850653Y1008472D01*
G37*
G36*
G01X847144Y1020562D02*
X847147Y1020954D01*
X847112Y1021032D01*
X847079Y1021061D01*
G02X846568Y1022190I992J1129D01*
G02X849572I1502J0D01*
G02X849041Y1021044I-1502J0D01*
G01X849007Y1021015D01*
X848971Y1020938D01*
X848968Y1020546D01*
X849003Y1020468D01*
X849036Y1020439D01*
G02X849547Y1019310I-992J-1129D01*
G02X849344Y1018556I-1502J0D01*
G01X849325Y1018524D01*
X849313Y1018454D01*
X849377Y1018123D01*
X849415Y1018062D01*
X849444Y1018039D01*
G02X850022Y1016855I-924J-1184D01*
G02X847018I-1502J0D01*
G02X847221Y1017609I1502J0D01*
G01X847240Y1017641D01*
X847252Y1017711D01*
X847188Y1018042D01*
X847150Y1018103D01*
X847121Y1018126D01*
G02X846543Y1019310I924J1184D01*
G02X847074Y1020456I1502J0D01*
G01X847108Y1020485D01*
X847144Y1020562D01*
G37*
G36*
G01X790290Y1024796D02*
X789934Y1024892D01*
X789854Y1024880D01*
X789819Y1024860D01*
G02X789050Y1024648I-769J1289D01*
G02Y1027652I0J1502D01*
G02X790363Y1026880I0J-1503D01*
G01X790383Y1026844D01*
X790446Y1026794D01*
X790802Y1026698D01*
X790882Y1026710D01*
X790917Y1026730D01*
G02X791686Y1026942I769J-1289D01*
G02Y1023938I0J-1502D01*
G02X790373Y1024710I0J1503D01*
G01X790353Y1024746D01*
X790290Y1024796D01*
G37*
G36*
G01X872348Y1075146D02*
X872700D01*
X872769Y1075174D01*
X872797Y1075200D01*
G02X874851I1027J-1096D01*
G01X874879Y1075174D01*
X874948Y1075146D01*
X875300D01*
X875369Y1075174D01*
X875397Y1075200D01*
G02X876424Y1075606I1027J-1096D01*
G02X877926Y1074104I0J-1502D01*
G02X877556Y1073117I-1501J0D01*
G01X877532Y1073089D01*
X877507Y1073022D01*
Y1072686D01*
X877532Y1072619D01*
X877556Y1072591D01*
G02X877926Y1071604I-1131J-987D01*
G02X876424Y1070102I-1502J0D01*
G02X875397Y1070508I0J1502D01*
G01X875369Y1070534D01*
X875300Y1070562D01*
X874948D01*
X874879Y1070534D01*
X874851Y1070508D01*
G02X872797I-1027J1096D01*
G01X872769Y1070534D01*
X872700Y1070562D01*
X872348D01*
X872279Y1070534D01*
X872251Y1070508D01*
G02X870197I-1027J1096D01*
G01X870169Y1070534D01*
X870100Y1070562D01*
X869748D01*
X869679Y1070534D01*
X869651Y1070508D01*
G02X868624Y1070102I-1027J1096D01*
G02X867122Y1071604I0J1502D01*
G02X867492Y1072591I1501J0D01*
G01X867516Y1072619D01*
X867541Y1072686D01*
Y1073022D01*
X867516Y1073089D01*
X867492Y1073117D01*
G02X867122Y1074104I1131J987D01*
G02X868624Y1075606I1502J0D01*
G02X869651Y1075200I0J-1502D01*
G01X869679Y1075174D01*
X869748Y1075146D01*
X870100D01*
X870169Y1075174D01*
X870197Y1075200D01*
G02X872251I1027J-1096D01*
G01X872279Y1075174D01*
X872348Y1075146D01*
G37*
G36*
G01X886503D02*
X886855D01*
X886924Y1075174D01*
X886952Y1075200D01*
G02X889006I1027J-1096D01*
G01X889034Y1075174D01*
X889103Y1075146D01*
X889455D01*
X889524Y1075174D01*
X889552Y1075200D01*
G02X890579Y1075606I1027J-1096D01*
G02X892081Y1074104I0J-1502D01*
G02X891711Y1073117I-1501J0D01*
G01X891687Y1073089D01*
X891662Y1073022D01*
Y1072686D01*
X891687Y1072619D01*
X891711Y1072591D01*
G02X892081Y1071604I-1131J-987D01*
G02X890579Y1070102I-1502J0D01*
G02X889552Y1070508I0J1502D01*
G01X889524Y1070534D01*
X889455Y1070562D01*
X889103D01*
X889034Y1070534D01*
X889006Y1070508D01*
G02X886952I-1027J1096D01*
G01X886924Y1070534D01*
X886855Y1070562D01*
X886503D01*
X886434Y1070534D01*
X886406Y1070508D01*
G02X884352I-1027J1096D01*
G01X884324Y1070534D01*
X884255Y1070562D01*
X883903D01*
X883834Y1070534D01*
X883806Y1070508D01*
G02X882779Y1070102I-1027J1096D01*
G02X881277Y1071604I0J1502D01*
G02X881647Y1072591I1501J0D01*
G01X881671Y1072619D01*
X881696Y1072686D01*
Y1073022D01*
X881671Y1073089D01*
X881647Y1073117D01*
G02X881277Y1074104I1131J987D01*
G02X882779Y1075606I1502J0D01*
G02X883806Y1075200I0J-1502D01*
G01X883834Y1075174D01*
X883903Y1075146D01*
X884255D01*
X884324Y1075174D01*
X884352Y1075200D01*
G02X886406I1027J-1096D01*
G01X886434Y1075174D01*
X886503Y1075146D01*
G37*
G36*
G01X881533Y1083583D02*
X881197D01*
X881130Y1083558D01*
X881102Y1083534D01*
G02X880115Y1083164I-987J1131D01*
G02Y1086168I0J1502D01*
G02X881102Y1085798I0J-1501D01*
G01X881130Y1085774D01*
X881197Y1085749D01*
X881533D01*
X881600Y1085774D01*
X881628Y1085798D01*
G02X882615Y1086168I987J-1131D01*
G02Y1083164I0J-1502D01*
G02X881628Y1083534I0J1501D01*
G01X881600Y1083558D01*
X881533Y1083583D01*
G37*
G36*
G01X871181Y1092646D02*
X871533D01*
X871602Y1092674D01*
X871630Y1092700D01*
G02X873684I1027J-1096D01*
G01X873712Y1092674D01*
X873781Y1092646D01*
X874133D01*
X874202Y1092674D01*
X874230Y1092700D01*
G02X875257Y1093106I1027J-1096D01*
G02X876759Y1091604I0J-1502D01*
G02X876389Y1090617I-1501J0D01*
G01X876365Y1090589D01*
X876340Y1090522D01*
Y1090186D01*
X876365Y1090119D01*
X876389Y1090091D01*
G02X876759Y1089104I-1131J-987D01*
G02X875257Y1087602I-1502J0D01*
G02X874230Y1088008I0J1502D01*
G01X874202Y1088034D01*
X874133Y1088062D01*
X873781D01*
X873712Y1088034D01*
X873684Y1088008D01*
G02X871630I-1027J1096D01*
G01X871602Y1088034D01*
X871533Y1088062D01*
X871181D01*
X871112Y1088034D01*
X871084Y1088008D01*
G02X869030I-1027J1096D01*
G01X869002Y1088034D01*
X868933Y1088062D01*
X868581D01*
X868512Y1088034D01*
X868484Y1088008D01*
G02X867457Y1087602I-1027J1096D01*
G02X865955Y1089104I0J1502D01*
G02X866325Y1090091I1501J0D01*
G01X866349Y1090119D01*
X866374Y1090186D01*
Y1090522D01*
X866349Y1090589D01*
X866325Y1090617D01*
G02X865955Y1091604I1131J987D01*
G02X867457Y1093106I1502J0D01*
G02X868484Y1092700I0J-1502D01*
G01X868512Y1092674D01*
X868581Y1092646D01*
X868933D01*
X869002Y1092674D01*
X869030Y1092700D01*
G02X871084I1027J-1096D01*
G01X871112Y1092674D01*
X871181Y1092646D01*
G37*
G36*
G01X907953Y1095001D02*
Y1095317D01*
G03X907876Y1095474I-200J-1D01*
G02X907297Y1096659I923J1185D01*
G02X910301I1502J0D01*
G02X909722Y1095474I-1502J0D01*
G03X909645Y1095317I123J-158D01*
G01Y1095001D01*
G03X909722Y1094844I200J1D01*
G02X910301Y1093659I-923J-1185D01*
G02X907297I-1502J0D01*
G02X907876Y1094844I1502J0D01*
G03X907953Y1095001I-123J158D01*
G37*
G36*
G01X871200Y1111217D02*
X871552D01*
X871621Y1111245D01*
X871649Y1111271D01*
G02X872676Y1111677I1027J-1096D01*
G02X873742Y1111233I0J-1502D01*
G01X873770Y1111204D01*
X873844Y1111174D01*
X874208D01*
X874282Y1111204D01*
X874310Y1111233D01*
G02X875376Y1111677I1066J-1058D01*
G02X876878Y1110175I0J-1502D01*
G02X876498Y1109176I-1503J0D01*
G01X876473Y1109149D01*
X876447Y1109081D01*
Y1108741D01*
X876473Y1108672D01*
X876498Y1108645D01*
G02X876877Y1107647I-1123J-998D01*
G02X875375Y1106145I-1502J0D01*
G02X874309Y1106589I0J1502D01*
G01X874281Y1106618D01*
X874207Y1106648D01*
X873843D01*
X873769Y1106618D01*
X873741Y1106589D01*
G02X872675Y1106145I-1066J1058D01*
G02X871648Y1106551I0J1502D01*
G01X871620Y1106577D01*
X871551Y1106605D01*
X871199D01*
X871130Y1106577D01*
X871102Y1106551D01*
G02X869048I-1027J1096D01*
G01X869020Y1106577D01*
X868951Y1106605D01*
X868599D01*
X868530Y1106577D01*
X868502Y1106551D01*
G02X867475Y1106145I-1027J1096D01*
G02X865973Y1107647I0J1502D01*
G02X866353Y1108646I1503J0D01*
G01X866378Y1108673D01*
X866404Y1108741D01*
Y1109081D01*
X866378Y1109150D01*
X866353Y1109177D01*
G02X865974Y1110175I1123J998D01*
G02X867476Y1111677I1502J0D01*
G02X868503Y1111271I0J-1502D01*
G01X868531Y1111245D01*
X868600Y1111217D01*
X868952D01*
X869021Y1111245D01*
X869049Y1111271D01*
G02X871103I1027J-1096D01*
G01X871131Y1111245D01*
X871200Y1111217D01*
G37*
G36*
G01X890073Y1115145D02*
X890425D01*
X890494Y1115173D01*
X890522Y1115199D01*
G02X891549Y1115605I1027J-1096D01*
G02X892615Y1115161I0J-1502D01*
G01X892643Y1115132D01*
X892717Y1115102D01*
X893081D01*
X893155Y1115132D01*
X893183Y1115161D01*
G02X894249Y1115605I1066J-1058D01*
G02Y1112601I0J-1502D01*
G02X893183Y1113045I0J1502D01*
G01X893155Y1113074D01*
X893081Y1113104D01*
X892717D01*
X892643Y1113074D01*
X892615Y1113045D01*
G02X891549Y1112601I-1066J1058D01*
G02X890522Y1113007I0J1502D01*
G01X890494Y1113033D01*
X890425Y1113061D01*
X890073D01*
X890004Y1113033D01*
X889976Y1113007D01*
G02X887922I-1027J1096D01*
G01X887894Y1113033D01*
X887825Y1113061D01*
X887473D01*
X887404Y1113033D01*
X887376Y1113007D01*
G02X886349Y1112601I-1027J1096D01*
G02Y1115605I0J1502D01*
G02X887376Y1115199I0J-1502D01*
G01X887404Y1115173D01*
X887473Y1115145D01*
X887825D01*
X887894Y1115173D01*
X887922Y1115199D01*
G02X889976I1027J-1096D01*
G01X890004Y1115173D01*
X890073Y1115145D01*
G37*
G36*
G01X906795D02*
X907147D01*
X907216Y1115173D01*
X907244Y1115199D01*
G02X908271Y1115605I1027J-1096D01*
G02X909337Y1115161I0J-1502D01*
G01X909365Y1115132D01*
X909439Y1115102D01*
X909803D01*
X909877Y1115132D01*
X909905Y1115161D01*
G02X910971Y1115605I1066J-1058D01*
G02Y1112601I0J-1502D01*
G02X909905Y1113045I0J1502D01*
G01X909877Y1113074D01*
X909803Y1113104D01*
X909439D01*
X909365Y1113074D01*
X909337Y1113045D01*
G02X908271Y1112601I-1066J1058D01*
G02X907244Y1113007I0J1502D01*
G01X907216Y1113033D01*
X907147Y1113061D01*
X906795D01*
X906726Y1113033D01*
X906698Y1113007D01*
G02X904644I-1027J1096D01*
G01X904616Y1113033D01*
X904547Y1113061D01*
X904195D01*
X904126Y1113033D01*
X904098Y1113007D01*
G02X903071Y1112601I-1027J1096D01*
G02Y1115605I0J1502D01*
G02X904098Y1115199I0J-1502D01*
G01X904126Y1115173D01*
X904195Y1115145D01*
X904547D01*
X904616Y1115173D01*
X904644Y1115199D01*
G02X906698I1027J-1096D01*
G01X906726Y1115173D01*
X906795Y1115145D01*
G37*
G36*
G01X829274Y1115168D02*
X828938D01*
X828871Y1115143D01*
X828843Y1115119D01*
G02X827856Y1114749I-987J1131D01*
G02Y1117753I0J1502D01*
G02X828843Y1117383I0J-1501D01*
G01X828871Y1117359D01*
X828938Y1117334D01*
X829274D01*
X829341Y1117359D01*
X829369Y1117383D01*
G02X830356Y1117753I987J-1131D01*
G02Y1114749I0J-1502D01*
G02X829369Y1115119I0J1501D01*
G01X829341Y1115143D01*
X829274Y1115168D01*
G37*
G36*
G01X859310Y1121635D02*
X859674D01*
X859748Y1121665D01*
X859776Y1121694D01*
G02X860842Y1122138I1066J-1058D01*
G02X861829Y1121768I0J-1501D01*
G01X861857Y1121744D01*
X861924Y1121719D01*
X862260D01*
X862327Y1121744D01*
X862355Y1121768D01*
G02X863342Y1122138I987J-1131D01*
G02Y1119134I0J-1502D01*
G02X862355Y1119504I0J1501D01*
G01X862327Y1119528D01*
X862260Y1119553D01*
X861924D01*
X861857Y1119528D01*
X861829Y1119504D01*
G02X860842Y1119134I-987J1131D01*
G02X859776Y1119578I0J1502D01*
G01X859748Y1119607D01*
X859674Y1119637D01*
X859310D01*
X859236Y1119607D01*
X859208Y1119578D01*
G02X858142Y1119134I-1066J1058D01*
G02X857115Y1119540I0J1502D01*
G01X857087Y1119566D01*
X857018Y1119594D01*
X856666D01*
X856597Y1119566D01*
X856569Y1119540D01*
G02X855542Y1119134I-1027J1096D01*
G02Y1122138I0J1502D01*
G02X856569Y1121732I0J-1502D01*
G01X856597Y1121706D01*
X856666Y1121678D01*
X857018D01*
X857087Y1121706D01*
X857115Y1121732D01*
G02X858142Y1122138I1027J-1096D01*
G02X859208Y1121694I0J-1502D01*
G01X859236Y1121665D01*
X859310Y1121635D01*
G37*
G36*
G01X875088Y1121678D02*
X875440D01*
X875509Y1121706D01*
X875537Y1121732D01*
G02X876564Y1122138I1027J-1096D01*
G02X877630Y1121694I0J-1502D01*
G01X877658Y1121665D01*
X877732Y1121635D01*
X878096D01*
X878170Y1121665D01*
X878198Y1121694D01*
G02X879264Y1122138I1066J-1058D01*
G02Y1119134I0J-1502D01*
G02X878198Y1119578I0J1502D01*
G01X878170Y1119607D01*
X878096Y1119637D01*
X877732D01*
X877658Y1119607D01*
X877630Y1119578D01*
G02X876564Y1119134I-1066J1058D01*
G02X875537Y1119540I0J1502D01*
G01X875509Y1119566D01*
X875440Y1119594D01*
X875088D01*
X875019Y1119566D01*
X874991Y1119540D01*
G02X872937I-1027J1096D01*
G01X872909Y1119566D01*
X872840Y1119594D01*
X872488D01*
X872419Y1119566D01*
X872391Y1119540D01*
G02X871364Y1119134I-1027J1096D01*
G02Y1122138I0J1502D01*
G02X872391Y1121732I0J-1502D01*
G01X872419Y1121706D01*
X872488Y1121678D01*
X872840D01*
X872909Y1121706D01*
X872937Y1121732D01*
G02X874991I1027J-1096D01*
G01X875019Y1121706D01*
X875088Y1121678D01*
G37*
G36*
G01X890073Y1124845D02*
X890425D01*
X890494Y1124873D01*
X890522Y1124899D01*
G02X891549Y1125305I1027J-1096D01*
G02X892615Y1124861I0J-1502D01*
G01X892643Y1124832D01*
X892717Y1124802D01*
X893081D01*
X893155Y1124832D01*
X893183Y1124861D01*
G02X894249Y1125305I1066J-1058D01*
G02Y1122301I0J-1502D01*
G02X893183Y1122745I0J1502D01*
G01X893155Y1122774D01*
X893081Y1122804D01*
X892717D01*
X892643Y1122774D01*
X892615Y1122745D01*
G02X891549Y1122301I-1066J1058D01*
G02X890522Y1122707I0J1502D01*
G01X890494Y1122733D01*
X890425Y1122761D01*
X890073D01*
X890004Y1122733D01*
X889976Y1122707D01*
G02X887922I-1027J1096D01*
G01X887894Y1122733D01*
X887825Y1122761D01*
X887473D01*
X887404Y1122733D01*
X887376Y1122707D01*
G02X886349Y1122301I-1027J1096D01*
G02Y1125305I0J1502D01*
G02X887376Y1124899I0J-1502D01*
G01X887404Y1124873D01*
X887473Y1124845D01*
X887825D01*
X887894Y1124873D01*
X887922Y1124899D01*
G02X889976I1027J-1096D01*
G01X890004Y1124873D01*
X890073Y1124845D01*
G37*
G36*
G01X859410Y1131335D02*
X859774D01*
X859848Y1131365D01*
X859876Y1131394D01*
G02X860942Y1131838I1066J-1058D01*
G02X861929Y1131468I0J-1501D01*
G01X861957Y1131444D01*
X862024Y1131419D01*
X862360D01*
X862427Y1131444D01*
X862455Y1131468D01*
G02X863442Y1131838I987J-1131D01*
G02Y1128834I0J-1502D01*
G02X862455Y1129204I0J1501D01*
G01X862427Y1129228D01*
X862360Y1129253D01*
X862024D01*
X861957Y1129228D01*
X861929Y1129204D01*
G02X860942Y1128834I-987J1131D01*
G02X859876Y1129278I0J1502D01*
G01X859848Y1129307D01*
X859774Y1129337D01*
X859410D01*
X859336Y1129307D01*
X859308Y1129278D01*
G02X858242Y1128834I-1066J1058D01*
G02X857215Y1129240I0J1502D01*
G01X857187Y1129266D01*
X857118Y1129294D01*
X856766D01*
X856697Y1129266D01*
X856669Y1129240D01*
G02X855642Y1128834I-1027J1096D01*
G02Y1131838I0J1502D01*
G02X856669Y1131432I0J-1502D01*
G01X856697Y1131406D01*
X856766Y1131378D01*
X857118D01*
X857187Y1131406D01*
X857215Y1131432D01*
G02X858242Y1131838I1027J-1096D01*
G02X859308Y1131394I0J-1502D01*
G01X859336Y1131365D01*
X859410Y1131335D01*
G37*
G36*
G01X875088Y1131378D02*
X875440D01*
X875509Y1131406D01*
X875537Y1131432D01*
G02X876564Y1131838I1027J-1096D01*
G02X877630Y1131394I0J-1502D01*
G01X877658Y1131365D01*
X877732Y1131335D01*
X878096D01*
X878170Y1131365D01*
X878198Y1131394D01*
G02X879264Y1131838I1066J-1058D01*
G02Y1128834I0J-1502D01*
G02X878198Y1129278I0J1502D01*
G01X878170Y1129307D01*
X878096Y1129337D01*
X877732D01*
X877658Y1129307D01*
X877630Y1129278D01*
G02X876564Y1128834I-1066J1058D01*
G02X875537Y1129240I0J1502D01*
G01X875509Y1129266D01*
X875440Y1129294D01*
X875088D01*
X875019Y1129266D01*
X874991Y1129240D01*
G02X872937I-1027J1096D01*
G01X872909Y1129266D01*
X872840Y1129294D01*
X872488D01*
X872419Y1129266D01*
X872391Y1129240D01*
G02X871364Y1128834I-1027J1096D01*
G02Y1131838I0J1502D01*
G02X872391Y1131432I0J-1502D01*
G01X872419Y1131406D01*
X872488Y1131378D01*
X872840D01*
X872909Y1131406D01*
X872937Y1131432D01*
G02X874991I1027J-1096D01*
G01X875019Y1131406D01*
X875088Y1131378D01*
G37*
G36*
G01X894107Y1131871D02*
X893743D01*
X893669Y1131841D01*
X893641Y1131812D01*
G02X892575Y1131368I-1066J1058D01*
G02Y1134372I0J1502D01*
G02X893641Y1133928I0J-1502D01*
G01X893669Y1133899D01*
X893743Y1133869D01*
X894107D01*
X894181Y1133899D01*
X894209Y1133928D01*
G02X895275Y1134372I1066J-1058D01*
G02Y1131368I0J-1502D01*
G02X894209Y1131812I0J1502D01*
G01X894181Y1131841D01*
X894107Y1131871D01*
G37*
G36*
G01X815468Y1132998D02*
X815174Y1133228D01*
X815096Y1133249D01*
X815054Y1133243D01*
G02X814835Y1133227I-219J1486D01*
G02Y1136231I0J1502D01*
G02X816330Y1134871I0J-1502D01*
G01X816334Y1134829D01*
X816373Y1134758D01*
X816667Y1134528D01*
X816745Y1134507D01*
X816787Y1134513D01*
G02X817006Y1134529I219J-1486D01*
G02X817453Y1134461I0J-1503D01*
G01X817495Y1134448D01*
X817580Y1134458D01*
X817912Y1134663D01*
X817960Y1134734D01*
X817967Y1134778D01*
G02X819449Y1136036I1482J-244D01*
G02Y1133032I0J-1502D01*
G02X819002Y1133100I0J1503D01*
G01X818960Y1133113D01*
X818875Y1133103D01*
X818543Y1132898D01*
X818495Y1132827D01*
X818488Y1132783D01*
G02X817006Y1131525I-1482J244D01*
G02X815511Y1132885I0J1502D01*
G01X815507Y1132927D01*
X815468Y1132998D01*
G37*
G36*
G01X862360Y1138253D02*
X862024D01*
X861957Y1138228D01*
X861929Y1138204D01*
G02X860942Y1137834I-987J1131D01*
G02Y1140838I0J1502D01*
G02X861929Y1140468I0J-1501D01*
G01X861957Y1140444D01*
X862024Y1140419D01*
X862360D01*
X862427Y1140444D01*
X862455Y1140468D01*
G02X863442Y1140838I987J-1131D01*
G02Y1137834I0J-1502D01*
G02X862455Y1138204I0J1501D01*
G01X862427Y1138228D01*
X862360Y1138253D01*
G37*
G36*
G01X870196Y1138337D02*
X869832D01*
X869758Y1138307D01*
X869730Y1138278D01*
G02X868664Y1137834I-1066J1058D01*
G02Y1140838I0J1502D01*
G02X869730Y1140394I0J-1502D01*
G01X869758Y1140365D01*
X869832Y1140335D01*
X870196D01*
X870270Y1140365D01*
X870298Y1140394D01*
G02X871364Y1140838I1066J-1058D01*
G02Y1137834I0J-1502D01*
G02X870298Y1138278I0J1502D01*
G01X870270Y1138307D01*
X870196Y1138337D01*
G37*
G36*
G01X896965Y1144086D02*
X896629D01*
X896562Y1144061D01*
X896534Y1144037D01*
G02X895547Y1143667I-987J1131D01*
G02Y1146671I0J1502D01*
G02X896534Y1146301I0J-1501D01*
G01X896562Y1146277D01*
X896629Y1146252D01*
X896965D01*
X897032Y1146277D01*
X897060Y1146301D01*
G02X898047Y1146671I987J-1131D01*
G02Y1143667I0J-1502D01*
G02X897060Y1144037I0J1501D01*
G01X897032Y1144061D01*
X896965Y1144086D01*
G37*
G36*
G01X903815D02*
X903479D01*
X903412Y1144061D01*
X903384Y1144037D01*
G02X902397Y1143667I-987J1131D01*
G02Y1146671I0J1502D01*
G02X903384Y1146301I0J-1501D01*
G01X903412Y1146277D01*
X903479Y1146252D01*
X903815D01*
X903882Y1146277D01*
X903910Y1146301D01*
G02X904897Y1146671I987J-1131D01*
G02Y1143667I0J-1502D01*
G02X903910Y1144037I0J1501D01*
G01X903882Y1144061D01*
X903815Y1144086D01*
G37*
G36*
G01X862537Y1146997D02*
X862201D01*
X862134Y1146972D01*
X862106Y1146948D01*
G02X861119Y1146578I-987J1131D01*
G02Y1149582I0J1502D01*
G02X862106Y1149212I0J-1501D01*
G01X862134Y1149188D01*
X862201Y1149163D01*
X862537D01*
X862604Y1149188D01*
X862632Y1149212D01*
G02X863619Y1149582I987J-1131D01*
G02Y1146578I0J-1502D01*
G02X862632Y1146948I0J1501D01*
G01X862604Y1146972D01*
X862537Y1146997D01*
G37*
G36*
G01X869440D02*
X869104D01*
X869037Y1146972D01*
X869009Y1146948D01*
G02X868022Y1146578I-987J1131D01*
G02Y1149582I0J1502D01*
G02X869009Y1149212I0J-1501D01*
G01X869037Y1149188D01*
X869104Y1149163D01*
X869440D01*
X869507Y1149188D01*
X869535Y1149212D01*
G02X870522Y1149582I987J-1131D01*
G02Y1146578I0J-1502D01*
G02X869535Y1146948I0J1501D01*
G01X869507Y1146972D01*
X869440Y1146997D01*
G37*
G36*
G01X805626Y1192168D02*
G02X804458Y1191610I-1168J943D01*
G02Y1194614I0J1502D01*
G02X805682Y1193983I0J-1503D01*
G03X806319Y1193963I326J232D01*
G02X807487Y1194521I1168J-943D01*
G02Y1191517I0J-1502D01*
G02X806263Y1192148I0J1503D01*
G03X805626Y1192168I-326J-232D01*
G37*
G36*
G01X763214Y1189960D02*
G02X762992Y1189939I-224J1181D01*
G02X764194Y1191141I0J1202D01*
G02X764173Y1190919I-1202J2D01*
G03X764640Y1190452I393J-74D01*
G02X764862Y1190473I224J-1181D01*
G02X763660Y1189271I0J-1202D01*
G02X763681Y1189493I1202J-2D01*
G03X763214Y1189960I-393J74D01*
G37*
G36*
G01X746850Y1190919D02*
G02X746829Y1191141I1181J224D01*
G02X748031Y1189939I1202J0D01*
G02X747809Y1189960I2J1202D01*
G03X747342Y1189493I-74J-393D01*
G02X747363Y1189271I-1181J-224D01*
G02X746161Y1190473I-1202J0D01*
G02X746383Y1190452I-2J-1202D01*
G03X746850Y1190919I74J393D01*
G37*
G36*
G01X753913Y1188099D02*
X753864Y1188090D01*
G02X753642Y1188069I-224J1181D01*
G02X754844Y1189271I0J1202D01*
G02X754823Y1189049I-1202J2D01*
G01X754814Y1189000D01*
X754843Y1188907D01*
X755148Y1188602D01*
X755241Y1188573D01*
X755290Y1188582D01*
G02X755512Y1188603I224J-1181D01*
G02X756714Y1187401I0J-1202D01*
G02X756693Y1187179I-1202J2D01*
G01X756684Y1187130D01*
X756713Y1187037D01*
X757018Y1186732D01*
X757111Y1186703D01*
X757160Y1186712D01*
G02X757382Y1186733I224J-1181D01*
G02X756180Y1185531I0J-1202D01*
G02X756201Y1185753I1202J-2D01*
G01X756210Y1185802D01*
X756181Y1185895D01*
X755876Y1186200D01*
X755783Y1186229D01*
X755734Y1186220D01*
G02X755512Y1186199I-224J1181D01*
G02X754310Y1187401I0J1202D01*
G02X754331Y1187623I1202J-2D01*
G01X754340Y1187672D01*
X754311Y1187765D01*
X754006Y1188070D01*
X753913Y1188099D01*
G37*
G36*
G01X809723Y1158669D02*
G02X809623Y1158666I-95J1499D01*
G02X811125Y1160168I0J1502D01*
G02X811011Y1159594I-1502J0D01*
G03X811407Y1159043I370J-152D01*
G02X811507Y1159046I95J-1499D01*
G02X810005Y1157544I0J-1502D01*
G02X810119Y1158118I1502J0D01*
G03X809723Y1158669I-370J152D01*
G37*
G36*
G01X824902Y1148843D02*
G02X824242Y1150087I842J1244D01*
G02X827246I1502J0D01*
G02X826586Y1148843I-1502J0D01*
G03Y1148181I224J-331D01*
G02X827246Y1146937I-842J-1244D01*
G02X824242I-1502J0D01*
G02X824902Y1148181I1502J0D01*
G03Y1148843I-224J331D01*
G37*
G36*
G01X771170Y1140378D02*
X771161Y1140427D01*
G02X771140Y1140649I1181J224D01*
G02X772342Y1139447I1202J0D01*
G02X772120Y1139468I2J1202D01*
G01X772071Y1139477D01*
X771978Y1139448D01*
X771673Y1139143D01*
X771644Y1139050D01*
X771653Y1139001D01*
G02X771674Y1138779I-1181J-224D01*
G02X769270I-1202J0D01*
G02X769291Y1139001I1202J-2D01*
G01X769300Y1139050D01*
X769271Y1139143D01*
X768966Y1139448D01*
X768873Y1139477D01*
X768824Y1139468D01*
G02X768602Y1139447I-224J1181D01*
G02X769804Y1140649I0J1202D01*
G02X769783Y1140427I-1202J2D01*
G01X769774Y1140378D01*
X769803Y1140285D01*
X770108Y1139980D01*
X770201Y1139951D01*
X770250Y1139960D01*
G02X770472Y1139981I224J-1181D01*
G02X770694Y1139960I-2J-1202D01*
G01X770743Y1139951D01*
X770836Y1139980D01*
X771141Y1140285D01*
X771170Y1140378D01*
G37*
G36*
G01X748730D02*
X748721Y1140427D01*
G02X748700Y1140649I1181J224D01*
G02X749902Y1139447I1202J0D01*
G02X749679Y1139468I1J1202D01*
G01X749631Y1139477D01*
X749536Y1139448D01*
X749232Y1139144D01*
X749203Y1139050D01*
X749212Y1139001D01*
G02X749233Y1138779I-1181J-224D01*
G02X746829I-1202J0D01*
G02X746850Y1139001I1202J-2D01*
G01X746859Y1139050D01*
X746830Y1139143D01*
X746525Y1139448D01*
X746432Y1139477D01*
X746383Y1139468D01*
G02X746161Y1139447I-224J1181D01*
G02X747363Y1140649I0J1202D01*
G02X747342Y1140427I-1202J2D01*
G01X747333Y1140378D01*
X747362Y1140285D01*
X747667Y1139980D01*
X747760Y1139951D01*
X747809Y1139960D01*
G02X748031Y1139981I224J-1181D01*
G02X748254Y1139960I-1J-1202D01*
G01X748302Y1139951D01*
X748397Y1139980D01*
X748701Y1140284D01*
X748730Y1140378D01*
G37*
G36*
G01X899522Y1135584D02*
G02X898278Y1134924I-1244J842D01*
G02Y1137928I0J1502D01*
G02X899522Y1137268I0J-1502D01*
G03X899687Y1137180I166J112D01*
G01X900019D01*
G03X900184Y1137268I-1J200D01*
G02X901428Y1137928I1244J-842D01*
G02X902660Y1137286I0J-1503D01*
G01X902683Y1137253D01*
X902748Y1137211D01*
X903104Y1137146D01*
X903180Y1137162D01*
X903214Y1137185D01*
G02X904063Y1137448I849J-1239D01*
G02X905565Y1135946I0J-1502D01*
G02X904882Y1134687I-1502J0D01*
G01X904841Y1134660D01*
X904794Y1134578D01*
X904773Y1134157D01*
X904811Y1134071D01*
X904850Y1134040D01*
G02X905410Y1132870I-942J-1170D01*
G02X902406I-1502J0D01*
G02X903089Y1134129I1502J0D01*
G01X903130Y1134156D01*
X903177Y1134238D01*
X903198Y1134659D01*
X903160Y1134745D01*
X903121Y1134776D01*
G02X902831Y1135086I941J1171D01*
G01X902808Y1135119D01*
X902743Y1135161D01*
X902387Y1135226D01*
X902311Y1135210D01*
X902277Y1135187D01*
G02X901428Y1134924I-849J1239D01*
G02X900184Y1135584I0J1502D01*
G03X900019Y1135672I-166J-112D01*
G01X899687D01*
G03X899522Y1135584I1J-200D01*
G37*
G36*
G01X804814Y1134092D02*
X804788Y1134041D01*
G02X803453Y1133227I-1335J688D01*
G02Y1136231I0J1502D01*
G02X804788Y1135417I0J-1502D01*
G01X804814Y1135366D01*
X804909Y1135308D01*
X805379D01*
X805474Y1135366D01*
X805500Y1135417D01*
G02X806835Y1136231I1335J-688D01*
G02X808329Y1134887I0J-1502D01*
G01X808334Y1134835D01*
X808391Y1134753D01*
X808783Y1134554D01*
X808883Y1134557D01*
X808927Y1134583D01*
G02X809682Y1134786I754J-1299D01*
G02Y1131782I0J-1502D01*
G02X808188Y1133126I0J1502D01*
G01X808183Y1133178D01*
X808126Y1133260D01*
X807734Y1133459D01*
X807634Y1133456D01*
X807590Y1133430D01*
G02X806835Y1133227I-754J1299D01*
G02X805500Y1134041I0J1502D01*
G01X805474Y1134092D01*
X805379Y1134150D01*
X804909D01*
X804814Y1134092D01*
G37*
G36*
G01X842258Y1010787D02*
X842233Y1010744D01*
G02X840935Y1009997I-1298J754D01*
G02Y1013001I0J1502D01*
G02X842103Y1012443I0J-1501D01*
G01X842135Y1012404D01*
X842224Y1012366D01*
X842652Y1012398D01*
X842735Y1012450D01*
X842760Y1012493D01*
G02X844058Y1013240I1298J-754D01*
G02X845560Y1011738I0J-1502D01*
G02X844859Y1010468I-1501J0D01*
G01X844820Y1010443D01*
X844772Y1010366D01*
X844728Y1009963D01*
X844758Y1009878D01*
X844791Y1009845D01*
G02X845236Y1008778I-1057J-1067D01*
G02X842232I-1502J0D01*
G02X842933Y1010048I1501J0D01*
G01X842972Y1010073D01*
X843020Y1010150D01*
X843064Y1010553D01*
X843034Y1010638D01*
X843001Y1010671D01*
G02X842890Y1010794I1058J1066D01*
G01X842858Y1010833D01*
X842769Y1010871D01*
X842341Y1010839D01*
X842258Y1010787D01*
G37*
G36*
G01X835135Y938520D02*
X834791D01*
X834721Y938493D01*
X834694Y938468D01*
G02X833683Y938077I-1011J1112D01*
G02Y941081I0J1502D01*
G02X834694Y940690I0J-1503D01*
G01X834721Y940665D01*
X834791Y940638D01*
X835135D01*
X835205Y940665D01*
X835232Y940690D01*
G02X836243Y941081I1011J-1112D01*
G02Y938077I0J-1502D01*
G02X835232Y938468I0J1503D01*
G01X835205Y938493D01*
X835135Y938520D01*
G37*
G36*
G01X723845Y941329D02*
X723466Y941387D01*
X723385Y941365D01*
X723351Y941338D01*
G02X722400Y940998I-952J1162D01*
G02Y944002I0J1502D01*
G02X723655Y943325I0J-1502D01*
G01X723679Y943289D01*
X723749Y943244D01*
X724128Y943186D01*
X724209Y943208D01*
X724243Y943235D01*
G02X725194Y943575I952J-1162D01*
G02Y940571I0J-1502D01*
G02X723939Y941248I0J1502D01*
G01X723915Y941284D01*
X723845Y941329D01*
G37*
G36*
G01X835135Y948046D02*
X834791D01*
X834721Y948019D01*
X834694Y947994D01*
G02X833683Y947603I-1011J1112D01*
G02Y950607I0J1502D01*
G02X834694Y950216I0J-1503D01*
G01X834721Y950191D01*
X834791Y950164D01*
X835135D01*
X835205Y950191D01*
X835232Y950216D01*
G02X836243Y950607I1011J-1112D01*
G02Y947603I0J-1502D01*
G02X835232Y947994I0J1503D01*
G01X835205Y948019D01*
X835135Y948046D01*
G37*
G36*
G01X873404Y993105D02*
G02X872183Y992478I-1221J875D01*
G02Y995482I0J1502D01*
G02X873496Y994710I0J-1503D01*
G03X874170Y994671I349J194D01*
G02X875391Y995298I1221J-875D01*
G02Y992294I0J-1502D01*
G02X874078Y993066I0J1503D01*
G03X873404Y993105I-349J-194D01*
G37*
G36*
G01X784189Y625606D02*
X779628D01*
X779581Y625594D01*
X779559Y625583D01*
G02X778860Y625410I-700J1329D01*
G02Y628414I0J1502D01*
G02X779559Y628241I-1J-1502D01*
G01X779581Y628230D01*
X779628Y628218D01*
X784813D01*
G02X785737Y627836I1J-1306D01*
G01X797059Y616514D01*
G02X797442Y615590I-923J-924D01*
G01Y553524D01*
X797449Y553498D01*
G02X797502Y553101I-1449J-396D01*
G02X794498I-1502J0D01*
G02X794790Y553990I1502J-1D01*
G03X794828Y554109I-162J117D01*
G01Y614966D01*
G03X794770Y615107I-200J0D01*
G01X784330Y625547D01*
G03X784189Y625606I-142J-141D01*
G37*
G36*
G01X784105Y427380D02*
G02X783400Y428653I797J1273D01*
G02X786404I1502J0D01*
G02X785621Y427334I-1502J0D01*
G03X785601Y426644I192J-351D01*
G02X786306Y425371I-797J-1273D01*
G02X783302I-1502J0D01*
G02X784085Y426690I1502J0D01*
G03X784105Y427380I-192J351D01*
G37*
G36*
G01X922848Y1324419D02*
Y1327819D01*
G02X924650Y1329622I1802J1D01*
G02X925542Y1329385I-1J-1803D01*
G03X925685Y1329364I99J174D01*
G01X925804Y1329391D01*
G03X925923Y1329470I-44J195D01*
G02X927146Y1330099I1222J-873D01*
G02Y1327095I0J-1502D01*
G02X926914Y1327113I0J1502D01*
G01X926871Y1327120D01*
X926787Y1327096D01*
X926522Y1326870D01*
G03X926452Y1326718I130J-152D01*
G01Y1325520D01*
G03X926522Y1325368I200J0D01*
G01X926787Y1325142D01*
X926871Y1325118D01*
X926914Y1325125D01*
G02X927146Y1325143I232J-1484D01*
G02Y1322139I0J-1502D01*
G02X925923Y1322768I-1J1502D01*
G03X925804Y1322847I-163J-116D01*
G01X925685Y1322874D01*
G03X925542Y1322853I-44J-195D01*
G02X924650Y1322616I-893J1566D01*
G02X922848Y1324419I1J1803D01*
G37*
G36*
G01X912797Y1344688D02*
X912404Y1344681D01*
X912325Y1344643D01*
X912297Y1344608D01*
G02X911135Y1344058I-1162J952D01*
G02Y1347062I0J1502D01*
G02X912262Y1346553I0J-1502D01*
G01X912291Y1346520D01*
X912371Y1346485D01*
X912764Y1346492D01*
X912843Y1346530D01*
X912871Y1346565D01*
G02X914033Y1347115I1162J-952D01*
G02Y1344111I0J-1502D01*
G02X912906Y1344620I0J1502D01*
G01X912877Y1344653D01*
X912797Y1344688D01*
G37*
G36*
G01X980515Y1360099D02*
X980199D01*
G03X980042Y1360022I1J-200D01*
G02X978857Y1359443I-1185J923D01*
G02Y1362447I0J1502D01*
G02X980042Y1361868I0J-1502D01*
G03X980199Y1361791I158J123D01*
G01X980515D01*
G03X980672Y1361868I-1J200D01*
G02X981857Y1362447I1185J-923D01*
G02Y1359443I0J-1502D01*
G02X980672Y1360022I0J1502D01*
G03X980515Y1360099I-158J-123D01*
G37*
G36*
G01X950728Y1366871D02*
X950412D01*
G03X950255Y1366794I1J-200D01*
G02X949070Y1366215I-1185J923D01*
G02Y1369219I0J1502D01*
G02X950255Y1368640I0J-1502D01*
G03X950412Y1368563I158J123D01*
G01X950728D01*
G03X950885Y1368640I-1J200D01*
G02X952070Y1369219I1185J-923D01*
G02Y1366215I0J-1502D01*
G02X950885Y1366794I0J1502D01*
G03X950728Y1366871I-158J-123D01*
G37*
G36*
G01X982159Y1368839D02*
X981843D01*
G03X981686Y1368762I1J-200D01*
G02X980501Y1368183I-1185J923D01*
G02Y1371187I0J1502D01*
G02X981686Y1370608I0J-1502D01*
G03X981843Y1370531I158J123D01*
G01X982159D01*
G03X982316Y1370608I-1J200D01*
G02X983501Y1371187I1185J-923D01*
G02Y1368183I0J-1502D01*
G02X982316Y1368762I0J1502D01*
G03X982159Y1368839I-158J-123D01*
G37*
G36*
G01X950490Y1370808D02*
X950174D01*
G03X950017Y1370731I1J-200D01*
G02X948832Y1370152I-1185J923D01*
G02Y1373156I0J1502D01*
G02X950017Y1372577I0J-1502D01*
G03X950174Y1372500I158J123D01*
G01X950490D01*
G03X950647Y1372577I-1J200D01*
G02X951832Y1373156I1185J-923D01*
G02Y1370152I0J-1502D01*
G02X950647Y1370731I0J1502D01*
G03X950490Y1370808I-158J-123D01*
G37*
G36*
G01X951043Y1374745D02*
X950727D01*
G03X950570Y1374668I1J-200D01*
G02X949385Y1374089I-1185J923D01*
G02Y1377093I0J1502D01*
G02X950570Y1376514I0J-1502D01*
G03X950727Y1376437I158J123D01*
G01X951043D01*
G03X951200Y1376514I-1J200D01*
G02X952385Y1377093I1185J-923D01*
G02Y1374089I0J-1502D01*
G02X951200Y1374668I0J1502D01*
G03X951043Y1374745I-158J-123D01*
G37*
G36*
G01X951098Y1378652D02*
X950788D01*
G03X950633Y1378579I-1J-200D01*
G02X949469Y1378026I-1164J949D01*
G02Y1381030I0J1502D01*
G02X950633Y1380477I0J-1502D01*
G03X950788Y1380404I154J127D01*
G01X951098D01*
G03X951253Y1380477I1J200D01*
G02X952417Y1381030I1164J-949D01*
G02Y1378026I0J-1502D01*
G02X951253Y1378579I0J1502D01*
G03X951098Y1378652I-154J-127D01*
G37*
G36*
G01X979288Y1388101D02*
G02X978590Y1389370I805J1269D01*
G02X981594I1502J0D01*
G02X980820Y1388056I-1502J0D01*
G03X980800Y1387369I194J-349D01*
G02X981498Y1386100I-805J-1269D01*
G02X978494I-1502J0D01*
G02X979268Y1387414I1502J0D01*
G03X979288Y1388101I-194J349D01*
G37*
G36*
G01X871911Y300777D02*
X871747Y301131D01*
X871681Y301187D01*
X871639Y301199D01*
G02X870548Y302644I411J1445D01*
G02X873552I1502J0D01*
G02X873418Y302024I-1501J0D01*
G01X873400Y301985D01*
X873401Y301897D01*
X873565Y301543D01*
X873631Y301487D01*
X873673Y301475D01*
G02X874764Y300030I-411J-1445D01*
G02X871760I-1502J0D01*
G02X871894Y300650I1501J0D01*
G01X871912Y300689D01*
X871911Y300777D01*
G37*
G36*
G01X877669Y303898D02*
G02X876475Y305368I308J1470D01*
G02X879479I1502J0D01*
G02X879181Y304470I-1502J0D01*
G03X879420Y303839I320J-239D01*
G02X880614Y302369I-308J-1470D01*
G02X877610I-1502J0D01*
G02X877908Y303267I1502J0D01*
G03X877669Y303898I-320J239D01*
G37*
G36*
G01X900245Y403492D02*
G02X903249I1502J0D01*
G02X902879Y402505I-1501J0D01*
G01Y402504D01*
X902878D01*
G03X902830Y402374I152J-130D01*
G01Y402110D01*
G03X902878Y401980I200J0D01*
G01X902879Y401979D01*
G02Y400005I-1131J-987D01*
G01Y400004D01*
X902878D01*
G03X902830Y399874I152J-130D01*
G01Y399610D01*
G03X902878Y399480I200J0D01*
G01X902879Y399479D01*
G02X903249Y398492I-1131J-987D01*
G02X900245I-1502J0D01*
G02X900615Y399479I1501J0D01*
G01Y399480D01*
X900616D01*
G03X900664Y399610I-152J130D01*
G01Y399874D01*
G03X900616Y400004I-200J0D01*
G01X900615Y400005D01*
G02Y401979I1131J987D01*
G01Y401980D01*
X900616D01*
G03X900664Y402110I-152J130D01*
G01Y402374D01*
G03X900616Y402504I-200J0D01*
G01X900615Y402505D01*
G02X900245Y403492I1131J987D01*
G37*
G36*
G01X912821Y403551D02*
G02X915825I1502J0D01*
G02X915455Y402564I-1501J0D01*
G01Y402563D01*
X915454D01*
G03X915406Y402433I152J-130D01*
G01Y402169D01*
G03X915454Y402039I200J0D01*
G01X915455Y402038D01*
G02Y400064I-1131J-987D01*
G01Y400063D01*
X915454D01*
G03X915406Y399933I152J-130D01*
G01Y399669D01*
G03X915454Y399539I200J0D01*
G01X915455Y399538D01*
G02X915825Y398551I-1131J-987D01*
G02X912821I-1502J0D01*
G02X913191Y399538I1501J0D01*
G01Y399539D01*
X913192D01*
G03X913240Y399669I-152J130D01*
G01Y399933D01*
G03X913192Y400063I-200J0D01*
G01X913191Y400064D01*
G02Y402038I1131J987D01*
G01Y402039D01*
X913192D01*
G03X913240Y402169I-152J130D01*
G01Y402433D01*
G03X913192Y402563I-200J0D01*
G01X913191Y402564D01*
G02X912821Y403551I1131J987D01*
G37*
G36*
G01X895326Y403091D02*
X895032D01*
G03X894885Y403026I1J-200D01*
G02X893779Y402541I-1106J1019D01*
G02Y405545I0J1502D01*
G02X894885Y405060I0J-1504D01*
G03X895032Y404995I148J135D01*
G01X895326D01*
G03X895473Y405060I-1J200D01*
G02X896579Y405545I1106J-1019D01*
G02Y402541I0J-1502D01*
G02X895473Y403026I0J1504D01*
G03X895326Y403091I-148J-135D01*
G37*
G36*
G01X885764Y405158D02*
G02X887266Y406660I1502J0D01*
G02X888121Y406393I0J-1502D01*
G01X888155Y406370D01*
X888236Y406353D01*
X888603Y406433D01*
X888670Y406481D01*
X888691Y406516D01*
G02X889979Y407245I1288J-773D01*
G02Y404241I0J-1502D01*
G02X889124Y404508I0J1502D01*
G01X889090Y404531D01*
X889009Y404548D01*
X888642Y404468D01*
X888575Y404420D01*
X888554Y404385D01*
G02X888398Y404172I-1285J777D01*
G03X888397Y404170I173J-88D01*
G03X888349Y404040I152J-130D01*
G01Y403776D01*
G03X888397Y403646I200J0D01*
G01X888398Y403645D01*
G02Y401671I-1131J-987D01*
G01Y401670D01*
X888397D01*
G03X888349Y401540I152J-130D01*
G01Y401276D01*
G03X888397Y401146I200J0D01*
G01X888398Y401145D01*
G02X888768Y400158I-1131J-987D01*
G02X885764I-1502J0D01*
G02X886134Y401145I1501J0D01*
G01Y401146D01*
X886135D01*
G03X886183Y401276I-152J130D01*
G01Y401540D01*
G03X886135Y401670I-200J0D01*
G01X886134Y401671D01*
G02Y403645I1131J987D01*
G01Y403646D01*
X886135D01*
G03X886183Y403776I-152J130D01*
G01Y404040D01*
G03X886135Y404170I-200J0D01*
G01X886134Y404171D01*
G02X885764Y405158I1131J987D01*
G37*
G36*
G01X878690Y410117D02*
G02Y413121I0J1502D01*
G02X879677Y412751I0J-1501D01*
G01X879678D01*
Y412750D01*
G03X879808Y412702I130J152D01*
G01X880072D01*
G03X880202Y412750I0J200D01*
G01X880203Y412751D01*
G02X881190Y413121I987J-1131D01*
G02Y410117I0J-1502D01*
G02X880203Y410487I0J1501D01*
G01X880202D01*
Y410488D01*
G03X880072Y410536I-130J-152D01*
G01X879808D01*
G03X879678Y410488I0J-200D01*
G01X879677Y410487D01*
G02X878690Y410117I-987J1131D01*
G37*
G36*
G01X876917Y413820D02*
G02Y416824I0J1502D01*
G02X877904Y416454I0J-1501D01*
G01X877905D01*
Y416453D01*
G03X878035Y416405I130J152D01*
G01X878299D01*
G03X878429Y416453I0J200D01*
G01X878430Y416454D01*
G02X879417Y416824I987J-1131D01*
G02Y413820I0J-1502D01*
G02X878430Y414190I0J1501D01*
G01X878429D01*
Y414191D01*
G03X878299Y414239I-130J-152D01*
G01X878035D01*
G03X877905Y414191I0J-200D01*
G01X877904Y414190D01*
G02X876917Y413820I-987J1131D01*
G37*
G36*
G01X923216Y425397D02*
X923510D01*
G03X923657Y425462I-1J200D01*
G02X925869I1106J-1017D01*
G03X926016Y425397I148J135D01*
G01X926310D01*
G03X926457Y425462I-1J200D01*
G02X927563Y425947I1106J-1019D01*
G02Y422943I0J-1502D01*
G02X926457Y423428I0J1504D01*
G03X926310Y423493I-148J-135D01*
G01X926016D01*
G03X925869Y423428I1J-200D01*
G02X923657I-1106J1017D01*
G03X923510Y423493I-148J-135D01*
G01X923216D01*
G03X923069Y423428I1J-200D01*
G02X921963Y422943I-1106J1019D01*
G02Y425947I0J1502D01*
G02X923069Y425462I0J-1504D01*
G03X923216Y425397I148J135D01*
G37*
G36*
G01X879758Y428084D02*
X879759Y428083D01*
G03X879889Y428035I130J152D01*
G01X880153D01*
G03X880283Y428083I0J200D01*
G01X880284Y428084D01*
G02X881271Y428454I987J-1131D01*
G02Y425450I0J-1502D01*
G02X880284Y425820I0J1501D01*
G01X880283D01*
Y425821D01*
G03X880153Y425869I-130J-152D01*
G01X879889D01*
G03X879759Y425821I0J-200D01*
G01X879758Y425820D01*
G02X877784I-987J1131D01*
G01X877783D01*
Y425821D01*
G03X877653Y425869I-130J-152D01*
G01X877389D01*
G03X877259Y425821I0J-200D01*
G01X877258Y425820D01*
G02X875284I-987J1131D01*
G01X875283D01*
Y425821D01*
G03X875153Y425869I-130J-152D01*
G01X874889D01*
G03X874759Y425821I0J-200D01*
G01X874758Y425820D01*
G02X873771Y425450I-987J1131D01*
G02Y428454I0J1502D01*
G02X874758Y428084I0J-1501D01*
G01X874759D01*
Y428083D01*
G03X874889Y428035I130J152D01*
G01X875153D01*
G03X875283Y428083I0J200D01*
G01X875284Y428084D01*
G02X877258I987J-1131D01*
G01X877259D01*
Y428083D01*
G03X877389Y428035I130J152D01*
G01X877653D01*
G03X877783Y428083I0J200D01*
G01X877784Y428084D01*
G02X879758I987J-1131D01*
G37*
G36*
G01X922933Y437668D02*
X923227D01*
G03X923374Y437733I-1J200D01*
G02X925586I1106J-1017D01*
G03X925733Y437668I148J135D01*
G01X926027D01*
G03X926174Y437733I-1J200D01*
G02X927280Y438218I1106J-1019D01*
G02Y435214I0J-1502D01*
G02X926174Y435699I0J1504D01*
G03X926027Y435764I-148J-135D01*
G01X925733D01*
G03X925586Y435699I1J-200D01*
G02X923374I-1106J1017D01*
G03X923227Y435764I-148J-135D01*
G01X922933D01*
G03X922786Y435699I1J-200D01*
G02X921680Y435214I-1106J1019D01*
G02Y438218I0J1502D01*
G02X922786Y437733I0J-1504D01*
G03X922933Y437668I148J135D01*
G37*
G36*
G01X879523Y438540D02*
X879524Y438539D01*
G03X879654Y438491I130J152D01*
G01X879918D01*
G03X880048Y438539I0J200D01*
G01X880049Y438540D01*
G02X881036Y438910I987J-1131D01*
G02Y435906I0J-1502D01*
G02X880049Y436276I0J1501D01*
G01X880048D01*
Y436277D01*
G03X879918Y436325I-130J-152D01*
G01X879654D01*
G03X879524Y436277I0J-200D01*
G01X879523Y436276D01*
G02X877549I-987J1131D01*
G01X877548D01*
Y436277D01*
G03X877418Y436325I-130J-152D01*
G01X877154D01*
G03X877024Y436277I0J-200D01*
G01X877023Y436276D01*
G02X875049I-987J1131D01*
G01X875048D01*
Y436277D01*
G03X874918Y436325I-130J-152D01*
G01X874654D01*
G03X874524Y436277I0J-200D01*
G01X874523Y436276D01*
G02X873536Y435906I-987J1131D01*
G02Y438910I0J1502D01*
G02X874523Y438540I0J-1501D01*
G01X874524D01*
Y438539D01*
G03X874654Y438491I130J152D01*
G01X874918D01*
G03X875048Y438539I0J200D01*
G01X875049Y438540D01*
G02X877023I987J-1131D01*
G01X877024D01*
Y438539D01*
G03X877154Y438491I130J152D01*
G01X877418D01*
G03X877548Y438539I0J200D01*
G01X877549Y438540D01*
G02X879523I987J-1131D01*
G37*
G36*
G01X916039Y443780D02*
G02X919043I1502J0D01*
G02X918673Y442793I-1501J0D01*
G01Y442792D01*
X918672D01*
G03X918624Y442662I152J-130D01*
G01Y442398D01*
G03X918672Y442268I200J0D01*
G01X918673Y442267D01*
G02X919043Y441280I-1131J-987D01*
G02X916039I-1502J0D01*
G02X916409Y442267I1501J0D01*
G01Y442268D01*
X916410D01*
G03X916458Y442398I-152J130D01*
G01Y442662D01*
G03X916410Y442792I-200J0D01*
G01X916409Y442793D01*
G02X916039Y443780I1131J987D01*
G37*
G36*
G01X906498Y458515D02*
Y458809D01*
G03X906433Y458956I-200J-1D01*
G02X905948Y460062I1019J1106D01*
G02X907450Y461564I1502J0D01*
G02X908556Y461079I0J-1504D01*
G03X908703Y461014I148J135D01*
G01X908997D01*
G03X909144Y461079I-1J200D01*
G02X910250Y461564I1106J-1019D01*
G02X911752Y460062I0J-1502D01*
G02X911267Y458956I-1504J0D01*
G03X911202Y458809I135J-148D01*
G01Y458515D01*
G03X911267Y458368I200J1D01*
G02Y456156I-1017J-1106D01*
G03X911202Y456009I135J-148D01*
G01Y455715D01*
G03X911267Y455568I200J1D01*
G02Y453356I-1017J-1106D01*
G03X911202Y453209I135J-148D01*
G01Y452915D01*
G03X911267Y452768I200J1D01*
G02X911752Y451662I-1019J-1106D01*
G02X910250Y450160I-1502J0D01*
G02X909144Y450645I0J1504D01*
G03X908997Y450710I-148J-135D01*
G01X908703D01*
G03X908556Y450645I1J-200D01*
G02X907450Y450160I-1106J1019D01*
G02X905948Y451662I0J1502D01*
G02X906433Y452768I1504J0D01*
G03X906498Y452915I-135J148D01*
G01Y453209D01*
G03X906433Y453356I-200J-1D01*
G02Y455568I1017J1106D01*
G03X906498Y455715I-135J148D01*
G01Y456009D01*
G03X906433Y456156I-200J-1D01*
G02Y458368I1017J1106D01*
G03X906498Y458515I-135J148D01*
G37*
G36*
G01X879958Y458687D02*
Y458981D01*
G03X879893Y459128I-200J-1D01*
G02X879408Y460234I1019J1106D01*
G02X882412I1502J0D01*
G02X881927Y459128I-1504J0D01*
G03X881862Y458981I135J-148D01*
G01Y458687D01*
G03X881927Y458540I200J1D01*
G02Y456328I-1017J-1106D01*
G03X881862Y456181I135J-148D01*
G01Y455887D01*
G03X881927Y455740I200J1D01*
G02X882412Y454634I-1019J-1106D01*
G02X879408I-1502J0D01*
G02X879893Y455740I1504J0D01*
G03X879958Y455887I-135J148D01*
G01Y456181D01*
G03X879893Y456328I-200J-1D01*
G02Y458540I1017J1106D01*
G03X879958Y458687I-135J148D01*
G37*
G36*
G01X889951D02*
Y458981D01*
G03X889886Y459128I-200J-1D01*
G02X889401Y460234I1019J1106D01*
G02X892405I1502J0D01*
G02X891920Y459128I-1504J0D01*
G03X891855Y458981I135J-148D01*
G01Y458687D01*
G03X891920Y458540I200J1D01*
G02Y456328I-1017J-1106D01*
G03X891855Y456181I135J-148D01*
G01Y455887D01*
G03X891920Y455740I200J1D01*
G02X892405Y454634I-1019J-1106D01*
G02X889401I-1502J0D01*
G02X889886Y455740I1504J0D01*
G03X889951Y455887I-135J148D01*
G01Y456181D01*
G03X889886Y456328I-200J-1D01*
G02Y458540I1017J1106D01*
G03X889951Y458687I-135J148D01*
G37*
G36*
G01X853930Y460244D02*
Y460538D01*
G03X853865Y460685I-200J-1D01*
G02X853380Y461791I1019J1106D01*
G02X856384I1502J0D01*
G02X855899Y460685I-1504J0D01*
G03X855834Y460538I135J-148D01*
G01Y460244D01*
G03X855899Y460097I200J1D01*
G02X856384Y458991I-1019J-1106D01*
G02X853380I-1502J0D01*
G02X853865Y460097I1504J0D01*
G03X853930Y460244I-135J148D01*
G37*
G36*
G01X861930D02*
Y460538D01*
G03X861865Y460685I-200J-1D01*
G02X861380Y461791I1019J1106D01*
G02X864384I1502J0D01*
G02X863899Y460685I-1504J0D01*
G03X863834Y460538I135J-148D01*
G01Y460244D01*
G03X863899Y460097I200J1D01*
G02X864384Y458991I-1019J-1106D01*
G02X861380I-1502J0D01*
G02X861865Y460097I1504J0D01*
G03X861930Y460244I-135J148D01*
G37*
G36*
G01X869930D02*
Y460538D01*
G03X869865Y460685I-200J-1D01*
G02X869380Y461791I1019J1106D01*
G02X872384I1502J0D01*
G02X871899Y460685I-1504J0D01*
G03X871834Y460538I135J-148D01*
G01Y460244D01*
G03X871899Y460097I200J1D01*
G02X872384Y458991I-1019J-1106D01*
G02X869380I-1502J0D01*
G02X869865Y460097I1504J0D01*
G03X869930Y460244I-135J148D01*
G37*
G36*
G01X857325Y419896D02*
G02X858827Y421398I1502J0D01*
G02X860006Y420827I0J-1503D01*
G01X860032Y420794D01*
X860106Y420755D01*
X860485Y420726D01*
X860563Y420754D01*
X860594Y420783D01*
G02X861622Y421190I1028J-1095D01*
G02X863124Y419688I0J-1502D01*
G02X862623Y418568I-1502J0D01*
G01X862594Y418543D01*
X862560Y418473D01*
X862535Y418159D01*
G03X862579Y418018I199J-15D01*
G02X862915Y417071I-1167J-947D01*
G02X861413Y415569I-1502J0D01*
G02X860522Y415862I0J1501D01*
G01X860521D01*
X860490Y415885D01*
X860414Y415904D01*
X860058Y415852D01*
X859989Y415811D01*
X859966Y415780D01*
G02X859627Y415454I-1198J906D01*
G03X859543Y415315I114J-164D01*
G01X859500Y414979D01*
X859524Y414898D01*
X859552Y414866D01*
G02X859912Y413890I-1143J-976D01*
G02X856908I-1502J0D01*
G02X857550Y415121I1501J0D01*
G03X857634Y415260I-114J164D01*
G01X857677Y415596D01*
X857653Y415677D01*
X857625Y415709D01*
G02X857265Y416685I1143J976D01*
G02X857986Y417968I1502J0D01*
G01X858030Y417995D01*
X858081Y418083D01*
X858089Y418525D01*
X858042Y418615D01*
X857999Y418643D01*
G02X857325Y419896I828J1253D01*
G37*
G36*
G01X875596Y423726D02*
X875910D01*
G03X876068Y423803I0J200D01*
G02X877253Y424382I1185J-923D01*
G02X878755Y422880I0J-1502D01*
G02X878385Y421893I-1501J0D01*
G01Y421892D01*
X878384D01*
G03X878336Y421762I152J-130D01*
G01Y421498D01*
G03X878384Y421368I200J0D01*
G01X878385Y421367D01*
G02X878755Y420380I-1131J-987D01*
G02X877253Y418878I-1502J0D01*
G02X876160Y419350I0J1502D01*
G01X876159Y419351D01*
G03X875994Y419412I-145J-138D01*
G01X875679Y419381D01*
G03X875529Y419287I20J-199D01*
G02X874253Y418578I-1276J794D01*
G02X872751Y420080I0J1502D01*
G02X873236Y421186I1504J0D01*
G03X873301Y421333I-135J148D01*
G01Y421627D01*
G03X873236Y421774I-200J-1D01*
G02X872751Y422880I1019J1106D01*
G02X874253Y424382I1502J0D01*
G02X875438Y423803I0J-1502D01*
G03X875596Y423726I158J123D01*
G37*
G36*
G01X918620Y449600D02*
G02X917549Y449038I-1071J739D01*
G02Y451642I0J1302D01*
G02X918620Y451080I0J-1301D01*
G03X919278I329J228D01*
G02X920349Y451642I1071J-739D01*
G02Y449038I0J-1302D01*
G02X919278Y449600I0J1301D01*
G03X918620I-329J-228D01*
G37*
G36*
G01Y453144D02*
G02X917549Y452582I-1071J739D01*
G02Y455186I0J1302D01*
G02X918620Y454624I0J-1301D01*
G03X919278I329J228D01*
G02X920349Y455186I1071J-739D01*
G02Y452582I0J-1302D01*
G02X919278Y453144I0J1301D01*
G03X918620I-329J-228D01*
G37*
G36*
G01Y456687D02*
G02X917549Y456125I-1071J739D01*
G02Y458729I0J1302D01*
G02X918620Y458167I0J-1301D01*
G03X919278I329J228D01*
G02X920349Y458729I1071J-739D01*
G02Y456125I0J-1302D01*
G02X919278Y456687I0J1301D01*
G03X918620I-329J-228D01*
G37*
G36*
G01Y460230D02*
G02X917549Y459668I-1071J739D01*
G02Y462272I0J1302D01*
G02X918620Y461710I0J-1301D01*
G03X919278I329J228D01*
G02X920349Y462272I1071J-739D01*
G02Y459668I0J-1302D01*
G02X919278Y460230I0J1301D01*
G03X918620I-329J-228D01*
G37*
G36*
G01X887970Y1264141D02*
X888306D01*
X888373Y1264166D01*
X888401Y1264190D01*
G02X890375I987J-1131D01*
G01X890403Y1264166D01*
X890470Y1264141D01*
X890806D01*
X890873Y1264166D01*
X890901Y1264190D01*
G02X891888Y1264560I987J-1131D01*
G02X893390Y1263058I0J-1502D01*
G02X893020Y1262071I-1501J0D01*
G01X892996Y1262043D01*
X892971Y1261976D01*
Y1261640D01*
X892996Y1261573D01*
X893020Y1261545D01*
G02X893390Y1260558I-1131J-987D01*
G02X891888Y1259056I-1502J0D01*
G02X890901Y1259426I0J1501D01*
G01X890873Y1259450D01*
X890806Y1259475D01*
X890470D01*
X890403Y1259450D01*
X890375Y1259426D01*
G02X888401I-987J1131D01*
G01X888373Y1259450D01*
X888306Y1259475D01*
X887970D01*
X887903Y1259450D01*
X887875Y1259426D01*
G02X886888Y1259056I-987J1131D01*
G02X885386Y1260558I0J1502D01*
G02X885756Y1261545I1501J0D01*
G01X885780Y1261573D01*
X885805Y1261640D01*
Y1261976D01*
X885780Y1262043D01*
X885756Y1262071D01*
G02X885386Y1263058I1131J987D01*
G02X886888Y1264560I1502J0D01*
G02X887875Y1264190I0J-1501D01*
G01X887903Y1264166D01*
X887970Y1264141D01*
G37*
G36*
G01X909508Y623418D02*
X912908D01*
G02Y619814I0J-1802D01*
G01X909508D01*
G02Y623418I0J1802D01*
G37*
G36*
G01X900676Y623338D02*
X904076D01*
G02Y619734I0J-1802D01*
G01X900676D01*
G02Y623338I0J1802D01*
G37*
G36*
G01X891449Y545861D02*
G02Y548865I0J1502D01*
G02X892436Y548495I0J-1501D01*
G01X892437D01*
Y548494D01*
G03X892567Y548446I130J152D01*
G01X892831D01*
G03X892961Y548494I0J200D01*
G01X892962Y548495D01*
G02X893949Y548865I987J-1131D01*
G02Y545861I0J-1502D01*
G02X892962Y546231I0J1501D01*
G01X892961D01*
Y546232D01*
G03X892831Y546280I-130J-152D01*
G01X892567D01*
G03X892437Y546232I0J-200D01*
G01X892436Y546231D01*
G02X891449Y545861I-987J1131D01*
G37*
G36*
G01X919038Y577876D02*
G02Y580880I0J1502D01*
G02X920272Y580235I0J-1503D01*
G01X920292Y580205D01*
X920354Y580163D01*
X920650Y580093D01*
G03X920791Y580111I47J194D01*
G02X921507Y580293I717J-1320D01*
G02Y577289I0J-1502D01*
G02X920273Y577934I0J1503D01*
G01X920253Y577964D01*
X920191Y578006D01*
X919895Y578076D01*
G03X919754Y578058I-47J-194D01*
G02X919038Y577876I-717J1320D01*
G37*
G36*
G01X921217Y590718D02*
G02Y587714I0J-1502D01*
G01X921216D01*
G02X921012Y587728I1J1502D01*
G01X921011D01*
G03X920866Y587691I-27J-198D01*
G01X920609Y587502D01*
X920568Y587436D01*
X920562Y587397D01*
G02X919080Y586138I-1482J243D01*
G02Y589142I0J1502D01*
G01X919081D01*
G02X919285Y589128I-1J-1502D01*
G01X919286D01*
G03X919431Y589165I27J198D01*
G01X919688Y589354D01*
X919729Y589420D01*
X919735Y589459D01*
G02X921217Y590718I1482J-243D01*
G37*
G36*
G01X915800Y628198D02*
G02Y631202I0J1502D01*
G02X916787Y630832I0J-1501D01*
G01X916788D01*
Y630831D01*
G03X916918Y630783I130J152D01*
G01X917182D01*
G03X917312Y630831I0J200D01*
G01X917313Y630832D01*
G02X918300Y631202I987J-1131D01*
G02Y628198I0J-1502D01*
G02X917313Y628568I0J1501D01*
G01X917312D01*
Y628569D01*
G03X917182Y628617I-130J-152D01*
G01X916918D01*
G03X916788Y628569I0J-200D01*
G01X916787Y628568D01*
G02X915800Y628198I-987J1131D01*
G37*
G36*
G01X918761Y666015D02*
G02X918588Y666714I1329J700D01*
G02X921592I1502J0D01*
G02X921419Y666015I-1502J1D01*
G03X921396Y665922I177J-93D01*
G01Y636932D01*
G03X921455Y636790I200J0D01*
G01X922991Y635255D01*
G03X923071Y635206I142J141D01*
G01X923072D01*
G02X924128Y633772I-446J-1434D01*
G02X922626Y632270I-1502J0D01*
G02X921192Y633325I0J1502D01*
G01Y633327D01*
G03X921143Y633407I-190J-62D01*
G01X919166Y635384D01*
G02X918784Y636306I924J923D01*
G01Y665922D01*
G03X918761Y666015I-200J0D01*
G37*
G36*
G01X899076Y532858D02*
G02X898429Y534093I855J1235D01*
G02X901433I1502J0D01*
G02X900469Y532691I-1502J0D01*
G03X900385Y531988I143J-374D01*
G02X901032Y530753I-855J-1235D01*
G02X898028I-1502J0D01*
G02X898992Y532155I1502J0D01*
G03X899076Y532858I-143J374D01*
G37*
G36*
G01X950480Y1075146D02*
X950832D01*
X950901Y1075174D01*
X950929Y1075200D01*
G02X952983I1027J-1096D01*
G01X953011Y1075174D01*
X953080Y1075146D01*
X953432D01*
X953501Y1075174D01*
X953529Y1075200D01*
G02X954556Y1075606I1027J-1096D01*
G02X956058Y1074104I0J-1502D01*
G02X955688Y1073117I-1501J0D01*
G01X955664Y1073089D01*
X955639Y1073022D01*
Y1072686D01*
X955664Y1072619D01*
X955688Y1072591D01*
G02X956058Y1071604I-1131J-987D01*
G02X954556Y1070102I-1502J0D01*
G02X953529Y1070508I0J1502D01*
G01X953501Y1070534D01*
X953432Y1070562D01*
X953080D01*
X953011Y1070534D01*
X952983Y1070508D01*
G02X950929I-1027J1096D01*
G01X950901Y1070534D01*
X950832Y1070562D01*
X950480D01*
X950411Y1070534D01*
X950383Y1070508D01*
G02X948329I-1027J1096D01*
G01X948301Y1070534D01*
X948232Y1070562D01*
X947880D01*
X947811Y1070534D01*
X947783Y1070508D01*
G02X946756Y1070102I-1027J1096D01*
G02X945254Y1071604I0J1502D01*
G02X945624Y1072591I1501J0D01*
G01X945648Y1072619D01*
X945673Y1072686D01*
Y1073022D01*
X945648Y1073089D01*
X945624Y1073117D01*
G02X945254Y1074104I1131J987D01*
G02X946756Y1075606I1502J0D01*
G02X947783Y1075200I0J-1502D01*
G01X947811Y1075174D01*
X947880Y1075146D01*
X948232D01*
X948301Y1075174D01*
X948329Y1075200D01*
G02X950383I1027J-1096D01*
G01X950411Y1075174D01*
X950480Y1075146D01*
G37*
G36*
G01X936013Y1075224D02*
X936365D01*
X936434Y1075252D01*
X936462Y1075278D01*
G02X938516I1027J-1096D01*
G01X938544Y1075252D01*
X938613Y1075224D01*
X938965D01*
X939034Y1075252D01*
X939062Y1075278D01*
G02X940089Y1075684I1027J-1096D01*
G02X941591Y1074182I0J-1502D01*
G02X941221Y1073195I-1501J0D01*
G01X941197Y1073167D01*
X941172Y1073100D01*
Y1072764D01*
X941197Y1072697D01*
X941221Y1072669D01*
G02X941591Y1071682I-1131J-987D01*
G02X940089Y1070180I-1502J0D01*
G02X939062Y1070586I0J1502D01*
G01X939034Y1070612D01*
X938965Y1070640D01*
X938613D01*
X938544Y1070612D01*
X938516Y1070586D01*
G02X936462I-1027J1096D01*
G01X936434Y1070612D01*
X936365Y1070640D01*
X936013D01*
X935944Y1070612D01*
X935916Y1070586D01*
G02X933862I-1027J1096D01*
G01X933834Y1070612D01*
X933765Y1070640D01*
X933413D01*
X933344Y1070612D01*
X933316Y1070586D01*
G02X932289Y1070180I-1027J1096D01*
G02X930787Y1071682I0J1502D01*
G02X931157Y1072669I1501J0D01*
G01X931181Y1072697D01*
X931206Y1072764D01*
Y1073100D01*
X931181Y1073167D01*
X931157Y1073195D01*
G02X930787Y1074182I1131J987D01*
G02X932289Y1075684I1502J0D01*
G02X933316Y1075278I0J-1502D01*
G01X933344Y1075252D01*
X933413Y1075224D01*
X933765D01*
X933834Y1075252D01*
X933862Y1075278D01*
G02X935916I1027J-1096D01*
G01X935944Y1075252D01*
X936013Y1075224D01*
G37*
G36*
G01X945510Y1083583D02*
X945174D01*
X945107Y1083558D01*
X945079Y1083534D01*
G02X944092Y1083164I-987J1131D01*
G02Y1086168I0J1502D01*
G02X945079Y1085798I0J-1501D01*
G01X945107Y1085774D01*
X945174Y1085749D01*
X945510D01*
X945577Y1085774D01*
X945605Y1085798D01*
G02X946592Y1086168I987J-1131D01*
G02Y1083164I0J-1502D01*
G02X945605Y1083534I0J1501D01*
G01X945577Y1083558D01*
X945510Y1083583D01*
G37*
G36*
G01X935352Y1092451D02*
X935704D01*
X935773Y1092479D01*
X935801Y1092505D01*
G02X937855I1027J-1096D01*
G01X937883Y1092479D01*
X937952Y1092451D01*
X938304D01*
X938373Y1092479D01*
X938401Y1092505D01*
G02X939428Y1092911I1027J-1096D01*
G02X940930Y1091409I0J-1502D01*
G02X940560Y1090422I-1501J0D01*
G01X940536Y1090394D01*
X940511Y1090327D01*
Y1089991D01*
X940536Y1089924D01*
X940560Y1089896D01*
G02X940930Y1088909I-1131J-987D01*
G02X939428Y1087407I-1502J0D01*
G02X938401Y1087813I0J1502D01*
G01X938373Y1087839D01*
X938304Y1087867D01*
X937952D01*
X937883Y1087839D01*
X937855Y1087813D01*
G02X935801I-1027J1096D01*
G01X935773Y1087839D01*
X935704Y1087867D01*
X935352D01*
X935283Y1087839D01*
X935255Y1087813D01*
G02X933201I-1027J1096D01*
G01X933173Y1087839D01*
X933104Y1087867D01*
X932752D01*
X932683Y1087839D01*
X932655Y1087813D01*
G02X931628Y1087407I-1027J1096D01*
G02X930126Y1088909I0J1502D01*
G02X930496Y1089896I1501J0D01*
G01X930520Y1089924D01*
X930545Y1089991D01*
Y1090327D01*
X930520Y1090394D01*
X930496Y1090422D01*
G02X930126Y1091409I1131J987D01*
G02X931628Y1092911I1502J0D01*
G02X932655Y1092505I0J-1502D01*
G01X932683Y1092479D01*
X932752Y1092451D01*
X933104D01*
X933173Y1092479D01*
X933201Y1092505D01*
G02X935255I1027J-1096D01*
G01X935283Y1092479D01*
X935352Y1092451D01*
G37*
G36*
G01X971930Y1095001D02*
Y1095317D01*
G03X971853Y1095474I-200J-1D01*
G02X971274Y1096659I923J1185D01*
G02X974278I1502J0D01*
G02X973699Y1095474I-1502J0D01*
G03X973622Y1095317I123J-158D01*
G01Y1095001D01*
G03X973699Y1094844I200J1D01*
G02X974278Y1093659I-923J-1185D01*
G02X971274I-1502J0D01*
G02X971853Y1094844I1502J0D01*
G03X971930Y1095001I-123J158D01*
G37*
G36*
G01X954050Y1115145D02*
X954402D01*
X954471Y1115173D01*
X954499Y1115199D01*
G02X955526Y1115605I1027J-1096D01*
G02X956592Y1115161I0J-1502D01*
G01X956620Y1115132D01*
X956694Y1115102D01*
X957058D01*
X957132Y1115132D01*
X957160Y1115161D01*
G02X958226Y1115605I1066J-1058D01*
G02Y1112601I0J-1502D01*
G02X957160Y1113045I0J1502D01*
G01X957132Y1113074D01*
X957058Y1113104D01*
X956694D01*
X956620Y1113074D01*
X956592Y1113045D01*
G02X955526Y1112601I-1066J1058D01*
G02X954499Y1113007I0J1502D01*
G01X954471Y1113033D01*
X954402Y1113061D01*
X954050D01*
X953981Y1113033D01*
X953953Y1113007D01*
G02X951899I-1027J1096D01*
G01X951871Y1113033D01*
X951802Y1113061D01*
X951450D01*
X951381Y1113033D01*
X951353Y1113007D01*
G02X950326Y1112601I-1027J1096D01*
G02Y1115605I0J1502D01*
G02X951353Y1115199I0J-1502D01*
G01X951381Y1115173D01*
X951450Y1115145D01*
X951802D01*
X951871Y1115173D01*
X951899Y1115199D01*
G02X953953I1027J-1096D01*
G01X953981Y1115173D01*
X954050Y1115145D01*
G37*
G36*
G01X939065Y1121678D02*
X939417D01*
X939486Y1121706D01*
X939514Y1121732D01*
G02X940541Y1122138I1027J-1096D01*
G02X941607Y1121694I0J-1502D01*
G01X941635Y1121665D01*
X941709Y1121635D01*
X942073D01*
X942147Y1121665D01*
X942175Y1121694D01*
G02X943241Y1122138I1066J-1058D01*
G02Y1119134I0J-1502D01*
G02X942175Y1119578I0J1502D01*
G01X942147Y1119607D01*
X942073Y1119637D01*
X941709D01*
X941635Y1119607D01*
X941607Y1119578D01*
G02X940541Y1119134I-1066J1058D01*
G02X939514Y1119540I0J1502D01*
G01X939486Y1119566D01*
X939417Y1119594D01*
X939065D01*
X938996Y1119566D01*
X938968Y1119540D01*
G02X936914I-1027J1096D01*
G01X936886Y1119566D01*
X936817Y1119594D01*
X936465D01*
X936396Y1119566D01*
X936368Y1119540D01*
G02X935341Y1119134I-1027J1096D01*
G02Y1122138I0J1502D01*
G02X936368Y1121732I0J-1502D01*
G01X936396Y1121706D01*
X936465Y1121678D01*
X936817D01*
X936886Y1121706D01*
X936914Y1121732D01*
G02X938968I1027J-1096D01*
G01X938996Y1121706D01*
X939065Y1121678D01*
G37*
G36*
G01X954050Y1124845D02*
X954402D01*
X954471Y1124873D01*
X954499Y1124899D01*
G02X955526Y1125305I1027J-1096D01*
G02X956592Y1124861I0J-1502D01*
G01X956620Y1124832D01*
X956694Y1124802D01*
X957058D01*
X957132Y1124832D01*
X957160Y1124861D01*
G02X958226Y1125305I1066J-1058D01*
G02Y1122301I0J-1502D01*
G02X957160Y1122745I0J1502D01*
G01X957132Y1122774D01*
X957058Y1122804D01*
X956694D01*
X956620Y1122774D01*
X956592Y1122745D01*
G02X955526Y1122301I-1066J1058D01*
G02X954499Y1122707I0J1502D01*
G01X954471Y1122733D01*
X954402Y1122761D01*
X954050D01*
X953981Y1122733D01*
X953953Y1122707D01*
G02X951899I-1027J1096D01*
G01X951871Y1122733D01*
X951802Y1122761D01*
X951450D01*
X951381Y1122733D01*
X951353Y1122707D01*
G02X950326Y1122301I-1027J1096D01*
G02Y1125305I0J1502D01*
G02X951353Y1124899I0J-1502D01*
G01X951381Y1124873D01*
X951450Y1124845D01*
X951802D01*
X951871Y1124873D01*
X951899Y1124899D01*
G02X953953I1027J-1096D01*
G01X953981Y1124873D01*
X954050Y1124845D01*
G37*
G36*
G01X939065Y1131378D02*
X939417D01*
X939486Y1131406D01*
X939514Y1131432D01*
G02X940541Y1131838I1027J-1096D01*
G02X941607Y1131394I0J-1502D01*
G01X941635Y1131365D01*
X941709Y1131335D01*
X942073D01*
X942147Y1131365D01*
X942175Y1131394D01*
G02X943241Y1131838I1066J-1058D01*
G02Y1128834I0J-1502D01*
G02X942175Y1129278I0J1502D01*
G01X942147Y1129307D01*
X942073Y1129337D01*
X941709D01*
X941635Y1129307D01*
X941607Y1129278D01*
G02X940541Y1128834I-1066J1058D01*
G02X939514Y1129240I0J1502D01*
G01X939486Y1129266D01*
X939417Y1129294D01*
X939065D01*
X938996Y1129266D01*
X938968Y1129240D01*
G02X936914I-1027J1096D01*
G01X936886Y1129266D01*
X936817Y1129294D01*
X936465D01*
X936396Y1129266D01*
X936368Y1129240D01*
G02X935341Y1128834I-1027J1096D01*
G02Y1131838I0J1502D01*
G02X936368Y1131432I0J-1502D01*
G01X936396Y1131406D01*
X936465Y1131378D01*
X936817D01*
X936886Y1131406D01*
X936914Y1131432D01*
G02X938968I1027J-1096D01*
G01X938996Y1131406D01*
X939065Y1131378D01*
G37*
G36*
G01X958084Y1131871D02*
X957720D01*
X957646Y1131841D01*
X957618Y1131812D01*
G02X956552Y1131368I-1066J1058D01*
G02Y1134372I0J1502D01*
G02X957618Y1133928I0J-1502D01*
G01X957646Y1133899D01*
X957720Y1133869D01*
X958084D01*
X958158Y1133899D01*
X958186Y1133928D01*
G02X959252Y1134372I1066J-1058D01*
G02Y1131368I0J-1502D01*
G02X958186Y1131812I0J1502D01*
G01X958158Y1131841D01*
X958084Y1131871D01*
G37*
G36*
G01X934173Y1138337D02*
X933809D01*
X933735Y1138307D01*
X933707Y1138278D01*
G02X932641Y1137834I-1066J1058D01*
G02Y1140838I0J1502D01*
G02X933707Y1140394I0J-1502D01*
G01X933735Y1140365D01*
X933809Y1140335D01*
X934173D01*
X934247Y1140365D01*
X934275Y1140394D01*
G02X935341Y1140838I1066J-1058D01*
G02Y1137834I0J-1502D01*
G02X934275Y1138278I0J1502D01*
G01X934247Y1138307D01*
X934173Y1138337D01*
G37*
G36*
G01X960942Y1144086D02*
X960606D01*
X960539Y1144061D01*
X960511Y1144037D01*
G02X959524Y1143667I-987J1131D01*
G02Y1146671I0J1502D01*
G02X960511Y1146301I0J-1501D01*
G01X960539Y1146277D01*
X960606Y1146252D01*
X960942D01*
X961009Y1146277D01*
X961037Y1146301D01*
G02X962024Y1146671I987J-1131D01*
G02Y1143667I0J-1502D01*
G02X961037Y1144037I0J1501D01*
G01X961009Y1144061D01*
X960942Y1144086D01*
G37*
G36*
G01X933418Y1146625D02*
X933082D01*
X933015Y1146600D01*
X932987Y1146576D01*
G02X932000Y1146206I-987J1131D01*
G02Y1149210I0J1502D01*
G02X932987Y1148840I0J-1501D01*
G01X933015Y1148816D01*
X933082Y1148791D01*
X933418D01*
X933485Y1148816D01*
X933513Y1148840D01*
G02X934500Y1149210I987J-1131D01*
G02Y1146206I0J-1502D01*
G02X933513Y1146576I0J1501D01*
G01X933485Y1146600D01*
X933418Y1146625D01*
G37*
G36*
G01X951947Y1264141D02*
X952283D01*
X952350Y1264166D01*
X952378Y1264190D01*
G02X954352I987J-1131D01*
G01X954380Y1264166D01*
X954447Y1264141D01*
X954783D01*
X954850Y1264166D01*
X954878Y1264190D01*
G02X955865Y1264560I987J-1131D01*
G02X957367Y1263058I0J-1502D01*
G02X956997Y1262071I-1501J0D01*
G01X956973Y1262043D01*
X956948Y1261976D01*
Y1261640D01*
X956973Y1261573D01*
X956997Y1261545D01*
G02X957367Y1260558I-1131J-987D01*
G02X955865Y1259056I-1502J0D01*
G02X954878Y1259426I0J1501D01*
G01X954850Y1259450D01*
X954783Y1259475D01*
X954447D01*
X954380Y1259450D01*
X954352Y1259426D01*
G02X952378I-987J1131D01*
G01X952350Y1259450D01*
X952283Y1259475D01*
X951947D01*
X951880Y1259450D01*
X951852Y1259426D01*
G02X950865Y1259056I-987J1131D01*
G02X949363Y1260558I0J1502D01*
G02X949733Y1261545I1501J0D01*
G01X949757Y1261573D01*
X949782Y1261640D01*
Y1261976D01*
X949757Y1262043D01*
X949733Y1262071D01*
G02X949363Y1263058I1131J987D01*
G02X950865Y1264560I1502J0D01*
G02X951852Y1264190I0J-1501D01*
G01X951880Y1264166D01*
X951947Y1264141D01*
G37*
G36*
G01X975553Y978992D02*
X964326Y990219D01*
G02X963770Y991564I1346J1344D01*
G02X965671Y993466I1901J1D01*
G02X967016Y992909I0J-1902D01*
G01X977627Y982297D01*
G03X977768Y982238I142J141D01*
G01X1006222D01*
G02Y978436I0J-1901D01*
G01X976898D01*
G02X975553Y978992I-1J1902D01*
G37*
G36*
G01X1068190Y933538D02*
G02X1069685Y934893I1495J-147D01*
G02Y931889I0J-1502D01*
G02X1068963Y932074I0J1501D01*
G03X1068373Y931762I-192J-351D01*
G02X1066878Y930407I-1495J147D01*
G02Y933411I0J1502D01*
G02X1067600Y933226I0J-1501D01*
G03X1068190Y933538I192J351D01*
G37*
G36*
G01X1027216Y287938D02*
G02Y290942I0J1502D01*
G02X1028602Y290019I0J-1502D01*
G03X1029226Y289866I369J155D01*
G02X1030184Y290211I958J-1158D01*
G02Y287207I0J-1502D01*
G02X1028798Y288130I0J1502D01*
G03X1028174Y288283I-369J-155D01*
G02X1027216Y287938I-958J1158D01*
G37*
G36*
G01X1008563Y295147D02*
G02X1010065Y293645I0J-1502D01*
G02X1009580Y292538I-1506J0D01*
G03X1009515Y292391I135J-148D01*
G01Y292099D01*
G03X1009580Y291952I200J1D01*
G02X1010065Y290845I-1021J-1107D01*
G02X1009738Y289910I-1500J0D01*
G01X1009717Y289883D01*
X1009695Y289821D01*
Y289657D01*
X1009646D01*
Y289426D01*
X1009671Y289359D01*
X1009695Y289332D01*
G02X1010065Y288345I-1131J-987D01*
G02X1008563Y286843I-1502J0D01*
G02X1007628Y287170I0J1500D01*
G01X1007601Y287191D01*
X1007539Y287213D01*
X1007375D01*
Y287262D01*
X1007144D01*
X1007077Y287237D01*
X1007050Y287213D01*
G02X1006063Y286843I-987J1131D01*
G02X1004561Y288345I0J1502D01*
G02X1004888Y289280I1500J0D01*
G01X1004909Y289307D01*
X1004931Y289369D01*
Y289533D01*
X1004980D01*
Y289764D01*
X1004955Y289831D01*
X1004931Y289858D01*
G02X1004561Y290845I1131J987D01*
G02X1005046Y291952I1506J0D01*
G03X1005111Y292099I-135J148D01*
G01Y292391D01*
G03X1005046Y292538I-200J-1D01*
G02X1004561Y293645I1021J1107D01*
G02X1006063Y295147I1502J0D01*
G02X1006998Y294820I0J-1500D01*
G01X1007025Y294799D01*
X1007087Y294777D01*
X1007251D01*
Y294728D01*
X1007482D01*
X1007549Y294753D01*
X1007576Y294777D01*
G02X1008563Y295147I987J-1131D01*
G37*
G36*
G01X1036566Y298789D02*
G02X1039570I1502J0D01*
G02X1038941Y297567I-1502J0D01*
G01X1038911Y297546D01*
X1038870Y297485D01*
X1038835Y297330D01*
G03X1038830Y297278I195J-45D01*
G03X1038857Y297186I200J9D01*
G02X1039094Y296293I-1566J-894D01*
G02X1037291Y294490I-1803J0D01*
G01X1033891D01*
G02X1032088Y296293I0J1803D01*
G02X1032325Y297186I1804J-1D01*
G03X1032346Y297329I-174J99D01*
G01X1032311Y297484D01*
X1032270Y297545D01*
X1032240Y297566D01*
G02X1031610Y298789I872J1223D01*
G02X1034614I1502J0D01*
G02X1034596Y298557I-1502J0D01*
G01X1034589Y298513D01*
X1034613Y298430D01*
X1034839Y298166D01*
G03X1034991Y298096I152J130D01*
G01X1036189D01*
G03X1036341Y298166I0J200D01*
G01X1036538Y298396D01*
G03X1036540Y298398I-140J142D01*
G01X1036568Y298431D01*
X1036591Y298513D01*
X1036584Y298557D01*
G02X1036566Y298789I1484J232D01*
G37*
G36*
G01X1020933Y312865D02*
G02X1023937I1502J0D01*
G02X1023292Y311631I-1503J0D01*
G01X1023291D01*
G03X1023211Y311513I115J-164D01*
G01X1023141Y311216D01*
X1023151Y311144D01*
X1023169Y311111D01*
G02X1023350Y310396I-1321J-715D01*
G02X1020346I-1502J0D01*
G02X1020991Y311630I1503J0D01*
G01X1020992D01*
G03X1021072Y311748I-115J164D01*
G01X1021142Y312045D01*
X1021132Y312117D01*
X1021114Y312150D01*
G02X1020933Y312865I1321J715D01*
G37*
G36*
G01X992536Y320000D02*
G02X991741Y321325I707J1325D01*
G02X994745I1502J0D01*
G02X994194Y320163I-1501J0D01*
G03X994259Y319500I253J-310D01*
G02X995054Y318175I-707J-1325D01*
G02X992050I-1502J0D01*
G02X992601Y319337I1501J0D01*
G03X992536Y320000I-253J310D01*
G37*
G36*
G01X1029860Y329268D02*
G02X1032864I1502J0D01*
G02X1032058Y327937I-1502J0D01*
G01X1032009Y327911D01*
X1031952Y327817D01*
X1031950Y327407D01*
G03X1032056Y327229I200J-2D01*
G02X1032856Y325901I-702J-1328D01*
G02X1032280Y324718I-1503J0D01*
G03X1032203Y324561I123J-158D01*
G01Y324245D01*
G03X1032280Y324088I200J1D01*
G02X1032856Y322905I-927J-1183D01*
G02X1029852I-1502J0D01*
G02X1030428Y324088I1503J0D01*
G03X1030505Y324245I-123J158D01*
G01Y324561D01*
G03X1030428Y324718I-200J-1D01*
G02X1029852Y325901I927J1183D01*
G02X1030658Y327232I1502J0D01*
G01X1030707Y327258D01*
X1030764Y327352D01*
X1030766Y327762D01*
G03X1030660Y327940I-200J2D01*
G02X1029860Y329268I702J1328D01*
G37*
G36*
G01X991918Y337954D02*
G02X994922I1502J0D01*
G01Y337953D01*
G02X994711Y337186I-1501J0D01*
G01X994692Y337154D01*
X994679Y337081D01*
X994739Y336781D01*
G03X994816Y336660I196J40D01*
G02X995422Y335454I-897J-1206D01*
G02X992418I-1502J0D01*
G01Y335455D01*
G02X992629Y336222I1501J0D01*
G01X992648Y336254D01*
X992661Y336327D01*
X992601Y336627D01*
G03X992524Y336748I-196J-40D01*
G02X991918Y337954I897J1206D01*
G37*
G36*
G01X1030461Y339760D02*
G02X1029880Y340947I922J1187D01*
G02X1032884I1502J0D01*
G02X1032246Y339718I-1503J0D01*
G03X1032231Y339075I230J-327D01*
G02X1032812Y337888I-922J-1187D01*
G02X1029808I-1502J0D01*
G02X1030446Y339117I1503J0D01*
G03X1030461Y339760I-230J327D01*
G37*
G36*
G01X1061096Y457759D02*
X1060802D01*
G03X1060655Y457694I1J-200D01*
G02X1059549Y457209I-1106J1019D01*
G02Y460213I0J1502D01*
G02X1060655Y459728I0J-1504D01*
G03X1060802Y459663I148J135D01*
G01X1061096D01*
G03X1061243Y459728I-1J200D01*
G02X1062349Y460213I1106J-1019D01*
G02X1063851Y458711I0J-1502D01*
G02X1063591Y457867I-1502J1D01*
G01Y457866D01*
X1063566Y457830D01*
X1063552Y457746D01*
X1063656Y457365D01*
X1063712Y457299D01*
X1063752Y457280D01*
G02X1064615Y455921I-639J-1359D01*
G01Y455918D01*
G02X1064591Y455652I-1502J1D01*
G01X1064583Y455610D01*
X1064604Y455527D01*
X1064843Y455224D01*
X1064919Y455184D01*
X1064962Y455182D01*
G02X1066378Y453682I-86J-1500D01*
G02X1063374I-1502J0D01*
G01Y453685D01*
G02X1063398Y453951I1502J-1D01*
G01X1063406Y453993D01*
X1063385Y454076D01*
X1063146Y454379D01*
X1063070Y454419D01*
X1063027Y454421D01*
G02X1061611Y455921I86J1500D01*
G02X1061871Y456765I1502J-1D01*
G01Y456766D01*
X1061896Y456802D01*
X1061910Y456886D01*
X1061806Y457267D01*
X1061750Y457333D01*
X1061710Y457352D01*
G02X1061243Y457694I637J1360D01*
G03X1061096Y457759I-148J-135D01*
G37*
G36*
G01X1059994Y612786D02*
G02X1062998I1502J0D01*
G01Y612785D01*
G02X1062558Y611723I-1502J0D01*
G01X1062532Y611697D01*
X1062502Y611631D01*
X1062483Y611328D01*
G03X1062524Y611195I200J-11D01*
G01X1062525Y611194D01*
G02X1062844Y610269I-1182J-925D01*
G02X1059840I-1502J0D01*
G01Y610270D01*
G02X1060280Y611332I1502J0D01*
G01X1060306Y611358D01*
X1060336Y611424D01*
X1060355Y611727D01*
G03X1060314Y611860I-200J11D01*
G01X1060313Y611861D01*
G02X1059994Y612786I1182J925D01*
G37*
G36*
G01X1021097Y1034983D02*
G02X1021091Y1035114I1497J134D01*
G02X1024097I1503J0D01*
G02X1024091Y1034983I-1503J3D01*
G02X1022594Y1033600I-1497J119D01*
G02X1021097Y1034983I0J1502D01*
G37*
G36*
G01X1017801Y1031518D02*
G03X1017958Y1031595I-1J200D01*
G02X1020328I1185J-923D01*
G03X1020485Y1031518I158J123D01*
G01X1020801D01*
G03X1020958Y1031595I-1J200D01*
G02X1022143Y1032174I1185J-923D01*
G02Y1029170I0J-1502D01*
G02X1020958Y1029749I0J1502D01*
G03X1020801Y1029826I-158J-123D01*
G01X1020485D01*
G03X1020328Y1029749I1J-200D01*
G02X1017958I-1185J923D01*
G03X1017801Y1029826I-158J-123D01*
G01X1017485D01*
G03X1017328Y1029749I1J-200D01*
G02X1016143Y1029170I-1185J923D01*
G02Y1032174I0J1502D01*
G02X1017328Y1031595I0J-1502D01*
G03X1017485Y1031518I158J123D01*
G01X1017801D01*
G37*
G36*
G01X1037551Y1117691D02*
G02X1040555I1502J0D01*
G02X1039994Y1116520I-1503J0D01*
G01X1039958Y1116491D01*
X1039919Y1116408D01*
X1039924Y1116046D01*
G03X1040003Y1115889I200J2D01*
G02X1040600Y1114691I-905J-1199D01*
G02X1037596I-1502J0D01*
G02X1038157Y1115862I1503J0D01*
G01X1038193Y1115891D01*
X1038232Y1115974D01*
X1038227Y1116336D01*
G03X1038148Y1116493I-200J-2D01*
G02X1037551Y1117691I905J1199D01*
G37*
G36*
G01Y1130291D02*
G02X1040555I1502J0D01*
G02X1039994Y1129120I-1503J0D01*
G01X1039958Y1129091D01*
X1039919Y1129008D01*
X1039924Y1128646D01*
G03X1040003Y1128489I200J2D01*
G02X1040600Y1127291I-905J-1199D01*
G02X1037596I-1502J0D01*
G02X1038157Y1128462I1503J0D01*
G01X1038193Y1128491D01*
X1038232Y1128574D01*
X1038227Y1128936D01*
G03X1038148Y1129093I-200J-2D01*
G02X1037551Y1130291I905J1199D01*
G37*
G36*
G01Y1142891D02*
G02X1040555I1502J0D01*
G02X1039994Y1141720I-1503J0D01*
G01X1039958Y1141691D01*
X1039919Y1141608D01*
X1039924Y1141246D01*
G03X1040003Y1141089I200J2D01*
G02X1040600Y1139891I-905J-1199D01*
G02X1037596I-1502J0D01*
G02X1038157Y1141062I1503J0D01*
G01X1038193Y1141091D01*
X1038232Y1141174D01*
X1038227Y1141536D01*
G03X1038148Y1141693I-200J-2D01*
G02X1037551Y1142891I905J1199D01*
G37*
G36*
G01X1059645Y1052460D02*
G02X1059266Y1053457I1122J997D01*
G02X1062270I1502J0D01*
G02X1061420Y1052104I-1502J0D01*
G03X1061295Y1051478I174J-360D01*
G02X1061674Y1050481I-1122J-997D01*
G02X1058670I-1502J0D01*
G02X1059520Y1051834I1502J0D01*
G03X1059645Y1052460I-174J360D01*
G37*
G36*
G01X1072226Y1056646D02*
G02X1071641Y1056527I-586J1383D01*
G02X1073143Y1058029I0J1502D01*
G02X1073102Y1057681I-1502J1D01*
G03X1073647Y1057219I389J-94D01*
G02X1074232Y1057338I586J-1383D01*
G02X1072730Y1055836I0J-1502D01*
G02X1072771Y1056184I1502J-1D01*
G03X1072226Y1056646I-389J94D01*
G37*
G36*
G01X1254816Y1194603D02*
X1254513Y1194449D01*
X1254465Y1194396D01*
X1254452Y1194362D01*
G02X1253056Y1193415I-1396J555D01*
G02Y1196419I0J1502D01*
G02X1253429Y1196372I0J-1502D01*
G01X1253466Y1196363D01*
X1253536Y1196370D01*
X1253839Y1196524D01*
X1253887Y1196577D01*
X1253900Y1196611D01*
G02X1255296Y1197558I1396J-555D01*
G02Y1194554I0J-1502D01*
G02X1254923Y1194601I0J1502D01*
G01X1254886Y1194610D01*
X1254816Y1194603D01*
G37*
G36*
G01X1317095Y1199403D02*
Y1199739D01*
X1317070Y1199806D01*
X1317046Y1199834D01*
G02X1316676Y1200821I1131J987D01*
G02X1319680I1502J0D01*
G02X1319310Y1199834I-1501J0D01*
G01X1319286Y1199806D01*
X1319261Y1199739D01*
Y1199403D01*
X1319286Y1199336D01*
X1319310Y1199308D01*
G02X1319680Y1198321I-1131J-987D01*
G02X1316676I-1502J0D01*
G02X1317046Y1199308I1501J0D01*
G01X1317070Y1199336D01*
X1317095Y1199403D01*
G37*
G36*
G01X1330560D02*
Y1199739D01*
X1330535Y1199806D01*
X1330511Y1199834D01*
G02X1330141Y1200821I1131J987D01*
G02X1333145I1502J0D01*
G02X1332775Y1199834I-1501J0D01*
G01X1332751Y1199806D01*
X1332726Y1199739D01*
Y1199403D01*
X1332751Y1199336D01*
X1332775Y1199308D01*
G02X1333145Y1198321I-1131J-987D01*
G02X1330141I-1502J0D01*
G02X1330511Y1199308I1501J0D01*
G01X1330535Y1199336D01*
X1330560Y1199403D01*
G37*
G36*
G01X1336025D02*
Y1199739D01*
X1336000Y1199806D01*
X1335976Y1199834D01*
G02X1335606Y1200821I1131J987D01*
G02X1338610I1502J0D01*
G02X1338240Y1199834I-1501J0D01*
G01X1338216Y1199806D01*
X1338191Y1199739D01*
Y1199403D01*
X1338216Y1199336D01*
X1338240Y1199308D01*
G02X1338610Y1198321I-1131J-987D01*
G02X1335606I-1502J0D01*
G02X1335976Y1199308I1501J0D01*
G01X1336000Y1199336D01*
X1336025Y1199403D01*
G37*
G36*
G01X1344025D02*
Y1199739D01*
X1344000Y1199806D01*
X1343976Y1199834D01*
G02X1343606Y1200821I1131J987D01*
G02X1346610I1502J0D01*
G02X1346240Y1199834I-1501J0D01*
G01X1346216Y1199806D01*
X1346191Y1199739D01*
Y1199403D01*
X1346216Y1199336D01*
X1346240Y1199308D01*
G02X1346610Y1198321I-1131J-987D01*
G02X1343606I-1502J0D01*
G02X1343976Y1199308I1501J0D01*
G01X1344000Y1199336D01*
X1344025Y1199403D01*
G37*
G36*
G01X1362955D02*
Y1199739D01*
X1362930Y1199806D01*
X1362906Y1199834D01*
G02X1362536Y1200821I1131J987D01*
G02X1365540I1502J0D01*
G02X1365170Y1199834I-1501J0D01*
G01X1365146Y1199806D01*
X1365121Y1199739D01*
Y1199403D01*
X1365146Y1199336D01*
X1365170Y1199308D01*
G02X1365540Y1198321I-1131J-987D01*
G02X1362536I-1502J0D01*
G02X1362906Y1199308I1501J0D01*
G01X1362930Y1199336D01*
X1362955Y1199403D01*
G37*
G36*
G01X1319410Y1210487D02*
Y1210823D01*
X1319385Y1210890D01*
X1319361Y1210918D01*
G02X1318991Y1211905I1131J987D01*
G02X1321995I1502J0D01*
G02X1321625Y1210918I-1501J0D01*
G01X1321601Y1210890D01*
X1321576Y1210823D01*
Y1210487D01*
X1321601Y1210420D01*
X1321625Y1210392D01*
G02Y1208418I-1131J-987D01*
G01X1321601Y1208390D01*
X1321576Y1208323D01*
Y1207987D01*
X1321601Y1207920D01*
X1321625Y1207892D01*
G02Y1205918I-1131J-987D01*
G01X1321601Y1205890D01*
X1321576Y1205823D01*
Y1205487D01*
X1321601Y1205420D01*
X1321625Y1205392D01*
G02X1321995Y1204405I-1131J-987D01*
G02X1318991I-1502J0D01*
G02X1319361Y1205392I1501J0D01*
G01X1319385Y1205420D01*
X1319410Y1205487D01*
Y1205823D01*
X1319385Y1205890D01*
X1319361Y1205918D01*
G02Y1207892I1131J987D01*
G01X1319385Y1207920D01*
X1319410Y1207987D01*
Y1208323D01*
X1319385Y1208390D01*
X1319361Y1208418D01*
G02Y1210392I1131J987D01*
G01X1319385Y1210420D01*
X1319410Y1210487D01*
G37*
G36*
G01X1346340D02*
Y1210823D01*
X1346315Y1210890D01*
X1346291Y1210918D01*
G02X1345921Y1211905I1131J987D01*
G02X1348925I1502J0D01*
G02X1348555Y1210918I-1501J0D01*
G01X1348531Y1210890D01*
X1348506Y1210823D01*
Y1210487D01*
X1348531Y1210420D01*
X1348555Y1210392D01*
G02Y1208418I-1131J-987D01*
G01X1348531Y1208390D01*
X1348506Y1208323D01*
Y1207987D01*
X1348531Y1207920D01*
X1348555Y1207892D01*
G02Y1205918I-1131J-987D01*
G01X1348531Y1205890D01*
X1348506Y1205823D01*
Y1205487D01*
X1348531Y1205420D01*
X1348555Y1205392D01*
G02X1348925Y1204405I-1131J-987D01*
G02X1345921I-1502J0D01*
G02X1346291Y1205392I1501J0D01*
G01X1346315Y1205420D01*
X1346340Y1205487D01*
Y1205823D01*
X1346315Y1205890D01*
X1346291Y1205918D01*
G02Y1207892I1131J987D01*
G01X1346315Y1207920D01*
X1346340Y1207987D01*
Y1208323D01*
X1346315Y1208390D01*
X1346291Y1208418D01*
G02Y1210392I1131J987D01*
G01X1346315Y1210420D01*
X1346340Y1210487D01*
G37*
G36*
G01X1333710Y1210699D02*
Y1211035D01*
X1333685Y1211102D01*
X1333661Y1211130D01*
G02X1333291Y1212117I1131J987D01*
G02X1336295I1502J0D01*
G02X1335925Y1211130I-1501J0D01*
G01X1335901Y1211102D01*
X1335876Y1211035D01*
Y1210699D01*
X1335901Y1210632D01*
X1335925Y1210604D01*
G02Y1208630I-1131J-987D01*
G01X1335901Y1208602D01*
X1335876Y1208535D01*
Y1208199D01*
X1335901Y1208132D01*
X1335925Y1208104D01*
G02Y1206130I-1131J-987D01*
G01X1335901Y1206102D01*
X1335876Y1206035D01*
Y1205699D01*
X1335901Y1205632D01*
X1335925Y1205604D01*
G02X1336295Y1204617I-1131J-987D01*
G02X1333291I-1502J0D01*
G02X1333661Y1205604I1501J0D01*
G01X1333685Y1205632D01*
X1333710Y1205699D01*
Y1206035D01*
X1333685Y1206102D01*
X1333661Y1206130D01*
G02Y1208104I1131J987D01*
G01X1333685Y1208132D01*
X1333710Y1208199D01*
Y1208535D01*
X1333685Y1208602D01*
X1333661Y1208630D01*
G02Y1210604I1131J987D01*
G01X1333685Y1210632D01*
X1333710Y1210699D01*
G37*
G36*
G01X1360640D02*
Y1211035D01*
X1360615Y1211102D01*
X1360591Y1211130D01*
G02X1360221Y1212117I1131J987D01*
G02X1363225I1502J0D01*
G02X1362855Y1211130I-1501J0D01*
G01X1362831Y1211102D01*
X1362806Y1211035D01*
Y1210699D01*
X1362831Y1210632D01*
X1362855Y1210604D01*
G02Y1208630I-1131J-987D01*
G01X1362831Y1208602D01*
X1362806Y1208535D01*
Y1208199D01*
X1362831Y1208132D01*
X1362855Y1208104D01*
G02Y1206130I-1131J-987D01*
G01X1362831Y1206102D01*
X1362806Y1206035D01*
Y1205699D01*
X1362831Y1205632D01*
X1362855Y1205604D01*
G02X1363225Y1204617I-1131J-987D01*
G02X1360221I-1502J0D01*
G02X1360591Y1205604I1501J0D01*
G01X1360615Y1205632D01*
X1360640Y1205699D01*
Y1206035D01*
X1360615Y1206102D01*
X1360591Y1206130D01*
G02Y1208104I1131J987D01*
G01X1360615Y1208132D01*
X1360640Y1208199D01*
Y1208535D01*
X1360615Y1208602D01*
X1360591Y1208630D01*
G02Y1210604I1131J987D01*
G01X1360615Y1210632D01*
X1360640Y1210699D01*
G37*
G36*
G01X1131012Y1114197D02*
X1131003Y1114246D01*
G02X1130982Y1114468I1181J224D01*
G02X1132184Y1113266I1202J0D01*
G02X1131962Y1113287I2J1202D01*
G01X1131913Y1113296D01*
X1131820Y1113267D01*
X1131515Y1112962D01*
X1131486Y1112869D01*
X1131495Y1112820D01*
G02X1131516Y1112598I-1181J-224D01*
G02X1129112I-1202J0D01*
G02X1129133Y1112820I1202J-2D01*
G01X1129142Y1112869D01*
X1129113Y1112962D01*
X1128808Y1113267D01*
X1128715Y1113296D01*
X1128666Y1113287D01*
G02X1128444Y1113266I-224J1181D01*
G02X1129646Y1114468I0J1202D01*
G02X1129625Y1114246I-1202J2D01*
G01X1129616Y1114197D01*
X1129645Y1114104D01*
X1129950Y1113799D01*
X1130043Y1113770D01*
X1130092Y1113779D01*
G02X1130314Y1113800I224J-1181D01*
G02X1130536Y1113779I-2J-1202D01*
G01X1130585Y1113770D01*
X1130678Y1113799D01*
X1130983Y1114104D01*
X1131012Y1114197D01*
G37*
G36*
G01X1261874Y1134041D02*
G02X1260539Y1133227I-1335J688D01*
G02Y1136231I0J1502D01*
G02X1261874Y1135417I0J-1502D01*
G03X1262586I356J183D01*
G02X1263921Y1136231I1335J-688D01*
G02Y1133227I0J-1502D01*
G02X1262586Y1134041I0J1502D01*
G03X1261874I-356J-183D01*
G37*
G36*
G01X1274323Y1134422D02*
X1274315Y1134468D01*
G02X1274292Y1134729I1479J262D01*
G02X1275794Y1133227I1502J0D01*
G02X1275750Y1133228I12J1502D01*
G01X1275704Y1133229D01*
X1275623Y1133193D01*
X1275360Y1132889D01*
X1275336Y1132804D01*
X1275344Y1132758D01*
G02X1275367Y1132497I-1479J-262D01*
G02X1272363I-1502J0D01*
G02X1272386Y1132759I1502J0D01*
G01X1272394Y1132804D01*
X1272370Y1132890D01*
X1272106Y1133194D01*
X1272023Y1133230D01*
X1271977Y1133228D01*
G02X1271921Y1133227I-55J1501D01*
G02X1271751Y1133237I3J1502D01*
G01X1271700Y1133242D01*
X1271608Y1133206D01*
X1271328Y1132875D01*
X1271307Y1132779D01*
X1271321Y1132730D01*
G02X1271378Y1132319I-1445J-410D01*
G02X1268374I-1502J0D01*
G02X1268429Y1132723I1502J1D01*
G01X1268443Y1132771D01*
X1268423Y1132865D01*
X1268155Y1133195D01*
X1268068Y1133233D01*
X1268018Y1133230D01*
G02X1267921Y1133227I-95J1499D01*
G02X1269423Y1134729I0J1502D01*
G02X1269368Y1134325I-1502J-1D01*
G01X1269354Y1134277D01*
X1269374Y1134183D01*
X1269642Y1133853D01*
X1269729Y1133815D01*
X1269779Y1133818D01*
G02X1269876Y1133821I95J-1499D01*
G02X1270046Y1133811I-3J-1502D01*
G01X1270097Y1133806D01*
X1270189Y1133842D01*
X1270469Y1134173D01*
X1270490Y1134269D01*
X1270476Y1134318D01*
G02X1270419Y1134729I1445J410D01*
G02X1273423I1502J0D01*
G02X1273400Y1134467I-1502J0D01*
G01X1273392Y1134422D01*
X1273416Y1134336D01*
X1273680Y1134032D01*
X1273763Y1133996D01*
X1273809Y1133998D01*
G02X1273865Y1133999I55J-1501D01*
G02X1273909Y1133998I-12J-1502D01*
G01X1273955Y1133997D01*
X1274036Y1134033D01*
X1274299Y1134337D01*
X1274323Y1134422D01*
G37*
G36*
G01X1205815Y1136638D02*
X1205806Y1136687D01*
G02X1205785Y1136909I1181J224D01*
G02X1208189I1202J0D01*
G02X1208168Y1136687I-1202J2D01*
G01X1208159Y1136638D01*
X1208188Y1136544D01*
X1208492Y1136240D01*
X1208587Y1136211D01*
X1208635Y1136220D01*
G02X1208858Y1136241I224J-1181D01*
G02X1207656Y1135039I0J-1202D01*
G02X1207677Y1135261I1202J-2D01*
G01X1207686Y1135310D01*
X1207657Y1135404D01*
X1207353Y1135708D01*
X1207258Y1135737D01*
X1207210Y1135728D01*
G02X1206987Y1135707I-224J1181D01*
G02X1206765Y1135728I2J1202D01*
G01X1206716Y1135737D01*
X1206623Y1135708D01*
X1206318Y1135403D01*
X1206289Y1135310D01*
X1206298Y1135261D01*
G02X1206319Y1135039I-1181J-224D01*
G02X1205117Y1136241I-1202J0D01*
G02X1205339Y1136220I-2J-1202D01*
G01X1205388Y1136211D01*
X1205481Y1136240D01*
X1205786Y1136545D01*
X1205815Y1136638D01*
G37*
G36*
G01X1239477D02*
X1239468Y1136687D01*
G02X1239447Y1136909I1181J224D01*
G02X1240649Y1138111I1202J0D01*
G02X1241587Y1137661I0J-1203D01*
G03X1241743Y1137586I156J125D01*
G01X1242055D01*
G03X1242211Y1137661I0J200D01*
G02X1243149Y1138111I938J-753D01*
G02Y1135707I0J-1202D01*
G02X1242211Y1136157I0J1203D01*
G03X1242055Y1136232I-156J-125D01*
G01X1241743D01*
G03X1241587Y1136157I0J-200D01*
G02X1240649Y1135707I-938J753D01*
G02X1240427Y1135728I2J1202D01*
G01X1240378Y1135737D01*
X1240285Y1135708D01*
X1239980Y1135403D01*
X1239951Y1135310D01*
X1239960Y1135261D01*
G02X1239981Y1135039I-1181J-224D01*
G02X1237577I-1202J0D01*
G02X1237598Y1135261I1202J-2D01*
G01X1237607Y1135310D01*
X1237578Y1135403D01*
X1237273Y1135708D01*
X1237180Y1135737D01*
X1237131Y1135728D01*
G02X1236909Y1135707I-224J1181D01*
G02X1236687Y1135728I2J1202D01*
G01X1236638Y1135737D01*
X1236545Y1135708D01*
X1236240Y1135403D01*
X1236211Y1135310D01*
X1236220Y1135261D01*
G02X1236241Y1135039I-1181J-224D01*
G02X1233837I-1202J0D01*
G02X1233858Y1135261I1202J-2D01*
G01X1233867Y1135310D01*
X1233838Y1135403D01*
X1233533Y1135708D01*
X1233440Y1135737D01*
X1233391Y1135728D01*
G02X1233169Y1135707I-224J1181D01*
G02X1233014Y1135717I0J1202D01*
G01X1232966Y1135723D01*
X1232877Y1135692D01*
X1232587Y1135391D01*
X1232559Y1135301D01*
X1232567Y1135254D01*
G02X1232586Y1135039I-1269J-220D01*
G02X1230010I-1288J0D01*
G02X1230029Y1135254I1288J-5D01*
G01X1230036Y1135301D01*
X1230009Y1135391D01*
X1229719Y1135692D01*
X1229630Y1135723D01*
X1229583Y1135717D01*
G02X1229428Y1135707I-155J1192D01*
G02X1229273Y1135717I0J1202D01*
G01X1229226Y1135723D01*
X1229137Y1135692D01*
X1228847Y1135391D01*
X1228820Y1135301D01*
X1228827Y1135254D01*
G02X1228846Y1135039I-1269J-220D01*
G02X1227558Y1136326I-1288J-1D01*
G02X1227773Y1136308I1J-1287D01*
G01X1227820Y1136301D01*
X1227910Y1136328D01*
X1228211Y1136618D01*
X1228242Y1136707D01*
X1228236Y1136754D01*
G02X1228226Y1136909I1192J155D01*
G02X1230630I1202J0D01*
G02X1230620Y1136754I-1202J0D01*
G01X1230614Y1136707D01*
X1230645Y1136618D01*
X1230946Y1136328D01*
X1231036Y1136301D01*
X1231083Y1136308D01*
G02X1231298Y1136326I214J-1269D01*
G02X1231513Y1136308I1J-1287D01*
G01X1231561Y1136300D01*
X1231651Y1136328D01*
X1231952Y1136617D01*
X1231983Y1136707D01*
X1231977Y1136754D01*
G02X1231967Y1136909I1192J155D01*
G02X1234371I1202J0D01*
G02X1234350Y1136687I-1202J2D01*
G01X1234341Y1136638D01*
X1234370Y1136545D01*
X1234675Y1136240D01*
X1234768Y1136211D01*
X1234817Y1136220D01*
G02X1235039Y1136241I224J-1181D01*
G02X1235261Y1136220I-2J-1202D01*
G01X1235310Y1136211D01*
X1235403Y1136240D01*
X1235708Y1136545D01*
X1235737Y1136638D01*
X1235728Y1136687D01*
G02X1235707Y1136909I1181J224D01*
G02X1238111I1202J0D01*
G02X1238090Y1136687I-1202J2D01*
G01X1238081Y1136638D01*
X1238110Y1136545D01*
X1238415Y1136240D01*
X1238508Y1136211D01*
X1238557Y1136220D01*
G02X1238779Y1136241I224J-1181D01*
G02X1239001Y1136220I-2J-1202D01*
G01X1239050Y1136211D01*
X1239143Y1136240D01*
X1239448Y1136545D01*
X1239477Y1136638D01*
G37*
G36*
G01X1281988Y1148843D02*
G02X1281328Y1150087I842J1244D01*
G02X1284332I1502J0D01*
G02X1283672Y1148843I-1502J0D01*
G03Y1148181I224J-331D01*
G02X1284332Y1146937I-842J-1244D01*
G02X1281328I-1502J0D01*
G02X1281988Y1148181I1502J0D01*
G03Y1148843I-224J331D01*
G37*
G36*
G01X1266809Y1158669D02*
G02X1266709Y1158666I-95J1499D01*
G02X1268211Y1160168I0J1502D01*
G02X1268097Y1159594I-1502J0D01*
G03X1268493Y1159043I370J-152D01*
G02X1268593Y1159046I95J-1499D01*
G02X1267091Y1157544I0J-1502D01*
G02X1267205Y1158118I1502J0D01*
G03X1266809Y1158669I-370J152D01*
G37*
G36*
G01X1256821Y1187433D02*
G02X1255628Y1186843I-1193J911D01*
G02Y1189847I0J1502D01*
G02X1256889Y1189161I0J-1502D01*
G03X1257543Y1189135I336J217D01*
G02X1258736Y1189725I1193J-911D01*
G02Y1186721I0J-1502D01*
G02X1257475Y1187407I0J1502D01*
G03X1256821Y1187433I-336J-217D01*
G37*
G36*
G01X1212820Y1193700D02*
G02X1212598Y1193679I-224J1181D01*
G02X1213800Y1194881I0J1202D01*
G02X1213779Y1194659I-1202J2D01*
G03X1214246Y1194192I393J-74D01*
G02X1214468Y1194213I224J-1181D01*
G02X1213266Y1193011I0J-1202D01*
G02X1213287Y1193233I1202J-2D01*
G03X1212820Y1193700I-393J74D01*
G37*
G36*
G01X1222646Y1194610D02*
X1222637Y1194659D01*
G02X1222616Y1194881I1181J224D01*
G02X1225020I1202J0D01*
G02X1224999Y1194659I-1202J2D01*
G01X1224990Y1194610D01*
X1225019Y1194517D01*
X1225324Y1194212D01*
X1225417Y1194183D01*
X1225466Y1194192D01*
G02X1225688Y1194213I224J-1181D01*
G02X1224486Y1193011I0J-1202D01*
G02X1224507Y1193233I1202J-2D01*
G01X1224516Y1193282D01*
X1224487Y1193375D01*
X1224182Y1193680D01*
X1224089Y1193709D01*
X1224040Y1193700D01*
G02X1223818Y1193679I-224J1181D01*
G02X1223596Y1193700I2J1202D01*
G01X1223547Y1193709D01*
X1223454Y1193680D01*
X1223149Y1193375D01*
X1223120Y1193282D01*
X1223129Y1193233D01*
G02X1223150Y1193011I-1181J-224D01*
G02X1221948Y1194213I-1202J0D01*
G02X1222170Y1194192I-2J-1202D01*
G01X1222219Y1194183D01*
X1222312Y1194212D01*
X1222617Y1194517D01*
X1222646Y1194610D01*
G37*
G36*
G01X1233867Y1198350D02*
X1233858Y1198399D01*
G02X1233837Y1198621I1181J224D01*
G02X1235039Y1197419I1202J0D01*
G02X1234817Y1197440I2J1202D01*
G01X1234768Y1197449D01*
X1234675Y1197420D01*
X1234370Y1197115D01*
X1234341Y1197022D01*
X1234350Y1196973D01*
G02X1234371Y1196751I-1181J-224D01*
G02X1231967I-1202J0D01*
G02X1231988Y1196973I1202J-2D01*
G01X1231997Y1197022D01*
X1231968Y1197116D01*
X1231664Y1197420D01*
X1231569Y1197449D01*
X1231521Y1197440D01*
G02X1231298Y1197419I-224J1181D01*
G02X1231076Y1197440I2J1202D01*
G01X1231027Y1197449D01*
X1230934Y1197420D01*
X1230629Y1197115D01*
X1230600Y1197022D01*
X1230609Y1196973D01*
G02X1230630Y1196751I-1181J-224D01*
G02X1228226I-1202J0D01*
G02X1228247Y1196973I1202J-2D01*
G01X1228256Y1197022D01*
X1228227Y1197115D01*
X1227922Y1197420D01*
X1227829Y1197449D01*
X1227780Y1197440D01*
G02X1227558Y1197419I-224J1181D01*
G02X1228760Y1198621I0J1202D01*
G02X1228739Y1198399I-1202J2D01*
G01X1228730Y1198350D01*
X1228759Y1198257D01*
X1229064Y1197952D01*
X1229157Y1197923D01*
X1229206Y1197932D01*
G02X1229428Y1197953I224J-1181D01*
G02X1229650Y1197932I-2J-1202D01*
G01X1229699Y1197923D01*
X1229792Y1197952D01*
X1230097Y1198257D01*
X1230126Y1198350D01*
X1230117Y1198399D01*
G02X1230096Y1198621I1181J224D01*
G02X1232500I1202J0D01*
G02X1232479Y1198399I-1202J2D01*
G01X1232470Y1198350D01*
X1232499Y1198256D01*
X1232803Y1197952D01*
X1232898Y1197923D01*
X1232946Y1197932D01*
G02X1233169Y1197953I224J-1181D01*
G02X1233391Y1197932I-2J-1202D01*
G01X1233440Y1197923D01*
X1233533Y1197952D01*
X1233838Y1198257D01*
X1233867Y1198350D01*
G37*
G36*
G01X1263090Y1201265D02*
G02X1264575Y1202545I1485J-221D01*
G02Y1199541I0J-1502D01*
G02X1263662Y1199850I0J1503D01*
G03X1263023Y1199592I-243J-317D01*
G02X1261538Y1198312I-1485J221D01*
G02Y1201316I0J1502D01*
G02X1262451Y1201007I0J-1503D01*
G03X1263090Y1201265I243J317D01*
G37*
G36*
G01X1277954Y1213555D02*
X1277942Y1213607D01*
G02X1277900Y1213958I1460J353D01*
G02X1279402Y1212456I1502J0D01*
G02X1279051Y1212498I2J1502D01*
G01X1278999Y1212510D01*
X1278900Y1212482D01*
X1278584Y1212166D01*
X1278556Y1212067D01*
X1278568Y1212015D01*
G02X1278610Y1211664I-1460J-353D01*
G02X1277108Y1210162I-1502J0D01*
G02X1276964Y1210169I1J1502D01*
G01X1276919Y1210173D01*
X1276835Y1210143D01*
X1276553Y1209861D01*
X1276523Y1209778D01*
X1276527Y1209733D01*
G02X1276534Y1209589I-1495J-145D01*
G02X1275032Y1211091I-1502J0D01*
G02X1275176Y1211084I-1J-1502D01*
G01X1275221Y1211080D01*
X1275305Y1211110D01*
X1275587Y1211392D01*
X1275617Y1211475D01*
X1275613Y1211520D01*
G02X1275606Y1211664I1495J145D01*
G02X1277108Y1213166I1502J0D01*
G02X1277459Y1213124I-2J-1502D01*
G01X1277511Y1213112D01*
X1277610Y1213140D01*
X1277926Y1213456D01*
X1277954Y1213555D01*
G37*
G36*
G01X1226386Y1224532D02*
X1226377Y1224580D01*
G02X1226356Y1224803I1181J224D01*
G02X1227558Y1223601I1202J0D01*
G02X1227336Y1223622I2J1202D01*
G01X1227287Y1223631D01*
X1227193Y1223602D01*
X1226889Y1223298D01*
X1226860Y1223203D01*
X1226869Y1223155D01*
G02X1226890Y1222932I-1181J-224D01*
G02X1226869Y1222710I-1202J2D01*
G01X1226860Y1222661D01*
X1226889Y1222568D01*
X1227194Y1222263D01*
X1227287Y1222234D01*
X1227336Y1222243D01*
G02X1227558Y1222264I224J-1181D01*
G02X1226356Y1221062I0J-1202D01*
G02X1226377Y1221284I1202J-2D01*
G01X1226386Y1221333D01*
X1226357Y1221426D01*
X1226052Y1221731D01*
X1225959Y1221760D01*
X1225910Y1221751D01*
G02X1225688Y1221730I-224J1181D01*
G02X1225466Y1221751I2J1202D01*
G01X1225417Y1221760D01*
X1225324Y1221731D01*
X1225019Y1221426D01*
X1224990Y1221333D01*
X1224999Y1221284D01*
G02X1225020Y1221062I-1181J-224D01*
G02X1223818Y1222264I-1202J0D01*
G02X1224040Y1222243I-2J-1202D01*
G01X1224089Y1222234D01*
X1224182Y1222263D01*
X1224487Y1222568D01*
X1224516Y1222661D01*
X1224507Y1222710D01*
G02X1224486Y1222932I1181J224D01*
G02X1224507Y1223155I1202J-1D01*
G01X1224516Y1223203D01*
X1224487Y1223298D01*
X1224183Y1223602D01*
X1224089Y1223631D01*
X1224040Y1223622D01*
G02X1223818Y1223601I-224J1181D01*
G02X1225020Y1224803I0J1202D01*
G02X1224999Y1224580I-1202J1D01*
G01X1224990Y1224532D01*
X1225019Y1224437D01*
X1225323Y1224133D01*
X1225417Y1224104D01*
X1225466Y1224113D01*
G02X1225688Y1224134I224J-1181D01*
G02X1225910Y1224113I-2J-1202D01*
G01X1225959Y1224104D01*
X1226053Y1224133D01*
X1226357Y1224437D01*
X1226386Y1224532D01*
G37*
G36*
G01X1272968Y1227959D02*
G02X1272944Y1228226I1478J267D01*
G02X1274446Y1226724I1502J0D01*
G02X1274178Y1226748I-1J1502D01*
G03X1273713Y1226283I-71J-394D01*
G02X1273737Y1226016I-1478J-267D01*
G02X1272235Y1227518I-1502J0D01*
G02X1272503Y1227494I1J-1502D01*
G03X1272968Y1227959I71J394D01*
G37*
G36*
G01X1130238Y1597895D02*
Y1599021D01*
G02X1130440Y1599224I202J1D01*
G01X1133260D01*
G02X1133462Y1599021I-1J-203D01*
G01Y1597895D01*
G03X1133491Y1597792I200J1D01*
G02Y1595830I-1640J-981D01*
G03X1133462Y1595727I171J-104D01*
G01Y1592777D01*
G03X1133491Y1592674I200J1D01*
G02Y1590712I-1640J-981D01*
G03X1133462Y1590609I171J-104D01*
G01Y1589483D01*
G02X1133260Y1589280I-202J-1D01*
G01X1130440D01*
G02X1130238Y1589483I1J203D01*
G01Y1590609D01*
G03X1130209Y1590712I-200J-1D01*
G02Y1592674I1640J981D01*
G03X1130238Y1592777I-171J104D01*
G01Y1595727D01*
G03X1130209Y1595830I-200J-1D01*
G02Y1597792I1640J981D01*
G03X1130238Y1597895I-171J104D01*
G37*
G36*
G01X1147560D02*
Y1599021D01*
G02X1147763Y1599224I203J0D01*
G01X1150583D01*
G02X1150786Y1599021I0J-203D01*
G01Y1597895D01*
G03X1150814Y1597792I200J-1D01*
G02Y1595830I-1640J-981D01*
G03X1150786Y1595727I172J-102D01*
G01Y1592777D01*
G03X1150814Y1592674I200J-1D01*
G02Y1590712I-1640J-981D01*
G03X1150786Y1590609I172J-102D01*
G01Y1589483D01*
G02X1150583Y1589280I-203J0D01*
G01X1147763D01*
G02X1147560Y1589483I0J203D01*
G01Y1590609D01*
G03X1147532Y1590712I-200J1D01*
G02Y1592674I1640J981D01*
G03X1147560Y1592777I-172J102D01*
G01Y1595727D01*
G03X1147532Y1595830I-200J1D01*
G02Y1597792I1640J981D01*
G03X1147560Y1597895I-172J102D01*
G37*
G36*
G01X1164884D02*
Y1599021D01*
G02X1165086Y1599224I202J1D01*
G01X1167906D01*
G02X1168108Y1599021I-1J-203D01*
G01Y1597895D01*
G03X1168137Y1597792I200J1D01*
G02Y1595830I-1640J-981D01*
G03X1168108Y1595727I171J-104D01*
G01Y1592777D01*
G03X1168137Y1592674I200J1D01*
G02Y1590712I-1640J-981D01*
G03X1168108Y1590609I171J-104D01*
G01Y1589483D01*
G02X1167906Y1589280I-202J-1D01*
G01X1165086D01*
G02X1164884Y1589483I1J203D01*
G01Y1590609D01*
G03X1164855Y1590712I-200J-1D01*
G02Y1592674I1640J981D01*
G03X1164884Y1592777I-171J104D01*
G01Y1595727D01*
G03X1164855Y1595830I-200J-1D01*
G02Y1597792I1640J981D01*
G03X1164884Y1597895I-171J104D01*
G37*
G36*
G01X1182206D02*
Y1599021D01*
G02X1182408Y1599224I202J1D01*
G01X1185228D01*
G02X1185430Y1599021I-1J-203D01*
G01Y1597895D01*
G03X1185459Y1597792I200J1D01*
G02Y1595830I-1640J-981D01*
G03X1185430Y1595727I171J-104D01*
G01Y1592777D01*
G03X1185459Y1592674I200J1D01*
G02Y1590712I-1640J-981D01*
G03X1185430Y1590609I171J-104D01*
G01Y1589483D01*
G02X1185228Y1589280I-202J-1D01*
G01X1182408D01*
G02X1182206Y1589483I1J203D01*
G01Y1590609D01*
G03X1182177Y1590712I-200J-1D01*
G02Y1592674I1640J981D01*
G03X1182206Y1592777I-171J104D01*
G01Y1595727D01*
G03X1182177Y1595830I-200J-1D01*
G02Y1597792I1640J981D01*
G03X1182206Y1597895I-171J104D01*
G37*
G36*
G01X1138898Y1602226D02*
Y1603352D01*
G02X1139101Y1603554I203J-1D01*
G01X1141921D01*
G02X1142124Y1603352I1J-202D01*
G01Y1602226D01*
G03X1142152Y1602123I200J-1D01*
G02Y1600161I-1640J-981D01*
G03X1142124Y1600058I172J-102D01*
G01Y1597108D01*
G03X1142152Y1597005I200J-1D01*
G02Y1595043I-1640J-981D01*
G03X1142124Y1594940I172J-102D01*
G01Y1593814D01*
G02X1141921Y1593612I-203J1D01*
G01X1139101D01*
G02X1138898Y1593814I-1J202D01*
G01Y1594940D01*
G03X1138870Y1595043I-200J1D01*
G02Y1597005I1640J981D01*
G03X1138898Y1597108I-172J102D01*
G01Y1600058D01*
G03X1138870Y1600161I-200J1D01*
G02Y1602123I1640J981D01*
G03X1138898Y1602226I-172J102D01*
G37*
G36*
G01X1156222D02*
Y1603352D01*
G02X1156424Y1603554I202J0D01*
G01X1159244D01*
G02X1159446Y1603352I0J-202D01*
G01Y1602226D01*
G03X1159475Y1602123I200J1D01*
G02Y1600161I-1640J-981D01*
G03X1159446Y1600058I171J-104D01*
G01Y1597108D01*
G03X1159475Y1597005I200J1D01*
G02Y1595043I-1640J-981D01*
G03X1159446Y1594940I171J-104D01*
G01Y1593814D01*
G02X1159244Y1593612I-202J0D01*
G01X1156424D01*
G02X1156222Y1593814I0J202D01*
G01Y1594940D01*
G03X1156193Y1595043I-200J-1D01*
G02Y1597005I1640J981D01*
G03X1156222Y1597108I-171J104D01*
G01Y1600058D01*
G03X1156193Y1600161I-200J-1D01*
G02Y1602123I1640J981D01*
G03X1156222Y1602226I-171J104D01*
G37*
G36*
G01X1173544D02*
Y1603352D01*
G02X1173747Y1603554I203J-1D01*
G01X1176567D01*
G02X1176770Y1603352I1J-202D01*
G01Y1602226D01*
G03X1176798Y1602123I200J-1D01*
G02Y1600161I-1640J-981D01*
G03X1176770Y1600058I172J-102D01*
G01Y1597108D01*
G03X1176798Y1597005I200J-1D01*
G02Y1595043I-1640J-981D01*
G03X1176770Y1594940I172J-102D01*
G01Y1593814D01*
G02X1176567Y1593612I-203J1D01*
G01X1173747D01*
G02X1173544Y1593814I-1J202D01*
G01Y1594940D01*
G03X1173516Y1595043I-200J1D01*
G02Y1597005I1640J981D01*
G03X1173544Y1597108I-172J102D01*
G01Y1600058D01*
G03X1173516Y1600161I-200J1D01*
G02Y1602123I1640J981D01*
G03X1173544Y1602226I-172J102D01*
G37*
G36*
G01X1190868D02*
Y1603352D01*
G02X1191070Y1603554I202J0D01*
G01X1193890D01*
G02X1194092Y1603352I0J-202D01*
G01Y1602226D01*
G03X1194121Y1602123I200J1D01*
G02Y1600161I-1640J-981D01*
G03X1194092Y1600058I171J-104D01*
G01Y1597108D01*
G03X1194121Y1597005I200J1D01*
G02Y1595043I-1640J-981D01*
G03X1194092Y1594940I171J-104D01*
G01Y1593814D01*
G02X1193890Y1593612I-202J0D01*
G01X1191070D01*
G02X1190868Y1593814I0J202D01*
G01Y1594940D01*
G03X1190839Y1595043I-200J-1D01*
G02Y1597005I1640J981D01*
G03X1190868Y1597108I-171J104D01*
G01Y1600058D01*
G03X1190839Y1600161I-200J-1D01*
G02Y1602123I1640J981D01*
G03X1190868Y1602226I-171J104D01*
G37*
G36*
G01X1130238Y1613250D02*
Y1614376D01*
G02X1130440Y1614578I202J0D01*
G01X1133260D01*
G02X1133462Y1614376I0J-202D01*
G01Y1613250D01*
G03X1133491Y1613147I200J1D01*
G02Y1611185I-1640J-981D01*
G03X1133462Y1611082I171J-104D01*
G01Y1608132D01*
G03X1133491Y1608029I200J1D01*
G02Y1606067I-1640J-981D01*
G03X1133462Y1605964I171J-104D01*
G01Y1604838D01*
G02X1133260Y1604636I-202J0D01*
G01X1130440D01*
G02X1130238Y1604838I0J202D01*
G01Y1605964D01*
G03X1130209Y1606067I-200J-1D01*
G02Y1608029I1640J981D01*
G03X1130238Y1608132I-171J104D01*
G01Y1611082D01*
G03X1130209Y1611185I-200J-1D01*
G02Y1613147I1640J981D01*
G03X1130238Y1613250I-171J104D01*
G37*
G36*
G01X1147560D02*
Y1614376D01*
G02X1147763Y1614578I203J-1D01*
G01X1150583D01*
G02X1150786Y1614376I1J-202D01*
G01Y1613250D01*
G03X1150814Y1613147I200J-1D01*
G02Y1611185I-1640J-981D01*
G03X1150786Y1611082I172J-102D01*
G01Y1608132D01*
G03X1150814Y1608029I200J-1D01*
G02Y1606067I-1640J-981D01*
G03X1150786Y1605964I172J-102D01*
G01Y1604838D01*
G02X1150583Y1604636I-203J1D01*
G01X1147763D01*
G02X1147560Y1604838I-1J202D01*
G01Y1605964D01*
G03X1147532Y1606067I-200J1D01*
G02Y1608029I1640J981D01*
G03X1147560Y1608132I-172J102D01*
G01Y1611082D01*
G03X1147532Y1611185I-200J1D01*
G02Y1613147I1640J981D01*
G03X1147560Y1613250I-172J102D01*
G37*
G36*
G01X1164884D02*
Y1614376D01*
G02X1165086Y1614578I202J0D01*
G01X1167906D01*
G02X1168108Y1614376I0J-202D01*
G01Y1613250D01*
G03X1168137Y1613147I200J1D01*
G02Y1611185I-1640J-981D01*
G03X1168108Y1611082I171J-104D01*
G01Y1608132D01*
G03X1168137Y1608029I200J1D01*
G02Y1606067I-1640J-981D01*
G03X1168108Y1605964I171J-104D01*
G01Y1604838D01*
G02X1167906Y1604636I-202J0D01*
G01X1165086D01*
G02X1164884Y1604838I0J202D01*
G01Y1605964D01*
G03X1164855Y1606067I-200J-1D01*
G02Y1608029I1640J981D01*
G03X1164884Y1608132I-171J104D01*
G01Y1611082D01*
G03X1164855Y1611185I-200J-1D01*
G02Y1613147I1640J981D01*
G03X1164884Y1613250I-171J104D01*
G37*
G36*
G01X1182206D02*
Y1614376D01*
G02X1182408Y1614578I202J0D01*
G01X1185228D01*
G02X1185430Y1614376I0J-202D01*
G01Y1613250D01*
G03X1185459Y1613147I200J1D01*
G02Y1611185I-1640J-981D01*
G03X1185430Y1611082I171J-104D01*
G01Y1608132D01*
G03X1185459Y1608029I200J1D01*
G02Y1606067I-1640J-981D01*
G03X1185430Y1605964I171J-104D01*
G01Y1604838D01*
G02X1185228Y1604636I-202J0D01*
G01X1182408D01*
G02X1182206Y1604838I0J202D01*
G01Y1605964D01*
G03X1182177Y1606067I-200J-1D01*
G02Y1608029I1640J981D01*
G03X1182206Y1608132I-171J104D01*
G01Y1611082D01*
G03X1182177Y1611185I-200J-1D01*
G02Y1613147I1640J981D01*
G03X1182206Y1613250I-171J104D01*
G37*
G36*
G01X1138898Y1617580D02*
Y1618706D01*
G02X1139101Y1618908I203J-1D01*
G01X1141921D01*
G02X1142124Y1618706I1J-202D01*
G01Y1617580D01*
G03X1142152Y1617477I200J-1D01*
G02Y1615515I-1640J-981D01*
G03X1142124Y1615412I172J-102D01*
G01Y1612462D01*
G03X1142152Y1612359I200J-1D01*
G02Y1610397I-1640J-981D01*
G03X1142124Y1610294I172J-102D01*
G01Y1609168D01*
G02X1141921Y1608966I-203J1D01*
G01X1139101D01*
G02X1138898Y1609168I-1J202D01*
G01Y1610294D01*
G03X1138870Y1610397I-200J1D01*
G02Y1612359I1640J981D01*
G03X1138898Y1612462I-172J102D01*
G01Y1615412D01*
G03X1138870Y1615515I-200J1D01*
G02Y1617477I1640J981D01*
G03X1138898Y1617580I-172J102D01*
G37*
G36*
G01X1156222D02*
Y1618706D01*
G02X1156424Y1618908I202J0D01*
G01X1159244D01*
G02X1159446Y1618706I0J-202D01*
G01Y1617580D01*
G03X1159475Y1617477I200J1D01*
G02Y1615515I-1640J-981D01*
G03X1159446Y1615412I171J-104D01*
G01Y1612462D01*
G03X1159475Y1612359I200J1D01*
G02Y1610397I-1640J-981D01*
G03X1159446Y1610294I171J-104D01*
G01Y1609168D01*
G02X1159244Y1608966I-202J0D01*
G01X1156424D01*
G02X1156222Y1609168I0J202D01*
G01Y1610294D01*
G03X1156193Y1610397I-200J-1D01*
G02Y1612359I1640J981D01*
G03X1156222Y1612462I-171J104D01*
G01Y1615412D01*
G03X1156193Y1615515I-200J-1D01*
G02Y1617477I1640J981D01*
G03X1156222Y1617580I-171J104D01*
G37*
G36*
G01X1173544D02*
Y1618706D01*
G02X1173747Y1618908I203J-1D01*
G01X1176567D01*
G02X1176770Y1618706I1J-202D01*
G01Y1617580D01*
G03X1176798Y1617477I200J-1D01*
G02Y1615515I-1640J-981D01*
G03X1176770Y1615412I172J-102D01*
G01Y1612462D01*
G03X1176798Y1612359I200J-1D01*
G02Y1610397I-1640J-981D01*
G03X1176770Y1610294I172J-102D01*
G01Y1609168D01*
G02X1176567Y1608966I-203J1D01*
G01X1173747D01*
G02X1173544Y1609168I-1J202D01*
G01Y1610294D01*
G03X1173516Y1610397I-200J1D01*
G02Y1612359I1640J981D01*
G03X1173544Y1612462I-172J102D01*
G01Y1615412D01*
G03X1173516Y1615515I-200J1D01*
G02Y1617477I1640J981D01*
G03X1173544Y1617580I-172J102D01*
G37*
G36*
G01X1190868D02*
Y1618706D01*
G02X1191070Y1618908I202J0D01*
G01X1193890D01*
G02X1194092Y1618706I0J-202D01*
G01Y1617580D01*
G03X1194121Y1617477I200J1D01*
G02Y1615515I-1640J-981D01*
G03X1194092Y1615412I171J-104D01*
G01Y1612462D01*
G03X1194121Y1612359I200J1D01*
G02Y1610397I-1640J-981D01*
G03X1194092Y1610294I171J-104D01*
G01Y1609168D01*
G02X1193890Y1608966I-202J0D01*
G01X1191070D01*
G02X1190868Y1609168I0J202D01*
G01Y1610294D01*
G03X1190839Y1610397I-200J-1D01*
G02Y1612359I1640J981D01*
G03X1190868Y1612462I-171J104D01*
G01Y1615412D01*
G03X1190839Y1615515I-200J-1D01*
G02Y1617477I1640J981D01*
G03X1190868Y1617580I-171J104D01*
G37*
G36*
G01X1240197Y627313D02*
G02X1239026Y625848I-1502J0D01*
G01X1238972Y625836D01*
X1238893Y625761D01*
X1238781Y625372D01*
G03X1238832Y625175I192J-55D01*
G01X1240994Y623013D01*
G03X1241136Y622954I142J141D01*
G01X1247165D01*
G02X1248089Y622571I0J-1306D01*
G01X1254011Y616649D01*
G02X1254394Y615725I-923J-924D01*
G01Y553891D01*
G03X1254415Y553802I200J0D01*
G01X1254416Y553800D01*
G02X1254589Y553101I-1329J-700D01*
G02X1251585I-1502J0D01*
G02X1251757Y553798I1502J-1D01*
G03X1251759Y553802I-178J91D01*
G01X1251770Y553823D01*
X1251780Y553867D01*
Y615101D01*
G03X1251721Y615243I-200J0D01*
G01X1246683Y620281D01*
G03X1246541Y620340I-142J-141D01*
G01X1240512D01*
G02X1239588Y620723I0J1306D01*
G01X1237448Y622863D01*
G03X1237246Y622913I-142J-141D01*
G01X1236908Y622806D01*
G03X1236771Y622650I60J-191D01*
G02X1235292Y621410I-1479J262D01*
G02X1233790Y622912I0J1502D01*
G02X1234866Y624352I1502J0D01*
G01X1234867D01*
X1234920Y624368D01*
X1234994Y624451D01*
X1235072Y624855D01*
G03X1235001Y625049I-196J38D01*
G01X1235000Y625050D01*
G02X1234428Y626229I929J1179D01*
G02X1235930Y627731I1502J0D01*
G02X1236679Y627531I0J-1503D01*
G01X1236719Y627508D01*
X1236809Y627501D01*
X1237143Y627632D01*
G03X1237261Y627758I-73J186D01*
G01Y627759D01*
G02X1237419Y628104I1433J-448D01*
G01Y628106D01*
G03X1237443Y628258I-170J105D01*
G01X1237364Y628577D01*
X1237315Y628642D01*
X1237280Y628662D01*
G02X1236532Y629961I754J1299D01*
G02X1236718Y630684I1502J-1D01*
G01Y630685D01*
G03X1236738Y630823I-175J96D01*
G01X1236674Y631116D01*
X1236634Y631177D01*
X1236605Y631198D01*
G02X1235998Y632404I895J1206D01*
G01Y632405D01*
G02X1239002I1502J0D01*
G02X1238816Y631682I-1502J1D01*
G01Y631681D01*
G03X1238796Y631543I175J-96D01*
G01X1238860Y631250D01*
X1238900Y631189D01*
X1238929Y631168D01*
G02X1239536Y629962I-895J-1206D01*
G01Y629961D01*
G02X1239310Y629170I-1500J1D01*
G01Y629168D01*
G03X1239286Y629016I170J-105D01*
G01X1239365Y628697D01*
X1239414Y628632D01*
X1239449Y628612D01*
G02X1240197Y627313I-754J-1299D01*
G37*
G36*
G01X1248106Y1006202D02*
G02Y1003198I0J-1502D01*
G02X1247377Y1003387I0J1502D01*
G01X1247338Y1003408D01*
X1247253Y1003415D01*
X1246885Y1003280D01*
X1246823Y1003218D01*
X1246808Y1003177D01*
G02X1245400Y1002198I-1408J523D01*
G02Y1005202I0J1502D01*
G02X1246129Y1005013I0J-1502D01*
G01X1246168Y1004992D01*
X1246253Y1004985D01*
X1246621Y1005120D01*
X1246683Y1005182D01*
X1246698Y1005223D01*
G02X1248106Y1006202I1408J-523D01*
G37*
G36*
G01X1198198Y1013661D02*
G02X1201202I1502J0D01*
G01Y1013659D01*
G02X1200939Y1012811I-1502J1D01*
G01X1200918Y1012781D01*
X1200901Y1012710D01*
X1200942Y1012374D01*
X1200975Y1012311D01*
X1201003Y1012286D01*
G02X1201510Y1011161I-995J-1125D01*
G02X1198506I-1502J0D01*
G01Y1011163D01*
G02X1198769Y1012011I1502J-1D01*
G01X1198790Y1012041D01*
X1198807Y1012112D01*
X1198766Y1012448D01*
X1198733Y1012511D01*
X1198705Y1012536D01*
G02X1198198Y1013661I995J1125D01*
G37*
G36*
G01X1443660Y1312500D02*
G02Y1308896I0J-1802D01*
G01X1440260D01*
G02Y1312500I0J1802D01*
G01X1443660D01*
G37*
G36*
G01X1362218Y1261006D02*
X1362534D01*
G03X1362691Y1261083I-1J200D01*
G02X1365061I1185J-923D01*
G03X1365218Y1261006I158J123D01*
G01X1365534D01*
G03X1365691Y1261083I-1J200D01*
G02X1366876Y1261662I1185J-923D01*
G02X1368378Y1260160I0J-1502D01*
G02X1367799Y1258975I-1502J0D01*
G03X1367722Y1258818I123J-158D01*
G01Y1258502D01*
G03X1367799Y1258345I200J1D01*
G02X1368378Y1257160I-923J-1185D01*
G02X1366876Y1255658I-1502J0D01*
G02X1365691Y1256237I0J1502D01*
G03X1365534Y1256314I-158J-123D01*
G01X1365218D01*
G03X1365061Y1256237I1J-200D01*
G02X1362691I-1185J923D01*
G03X1362534Y1256314I-158J-123D01*
G01X1362218D01*
G03X1362061Y1256237I1J-200D01*
G02X1359691I-1185J923D01*
G03X1359534Y1256314I-158J-123D01*
G01X1359218D01*
G03X1359061Y1256237I1J-200D01*
G02X1356691I-1185J923D01*
G03X1356534Y1256314I-158J-123D01*
G01X1356218D01*
G03X1356061Y1256237I1J-200D01*
G02X1353691I-1185J923D01*
G03X1353534Y1256314I-158J-123D01*
G01X1353218D01*
G03X1353061Y1256237I1J-200D01*
G02X1350691I-1185J923D01*
G03X1350534Y1256314I-158J-123D01*
G01X1350218D01*
G03X1350061Y1256237I1J-200D01*
G02X1347691I-1185J923D01*
G03X1347534Y1256314I-158J-123D01*
G01X1347218D01*
G03X1347061Y1256237I1J-200D01*
G02X1344691I-1185J923D01*
G03X1344534Y1256314I-158J-123D01*
G01X1344218D01*
G03X1344061Y1256237I1J-200D01*
G02X1341691I-1185J923D01*
G03X1341534Y1256314I-158J-123D01*
G01X1341218D01*
G03X1341061Y1256237I1J-200D01*
G02X1338691I-1185J923D01*
G03X1338534Y1256314I-158J-123D01*
G01X1338218D01*
G03X1338061Y1256237I1J-200D01*
G02X1335691I-1185J923D01*
G03X1335534Y1256314I-158J-123D01*
G01X1335218D01*
G03X1335061Y1256237I1J-200D01*
G02X1333876Y1255658I-1185J923D01*
G02X1332374Y1257160I0J1502D01*
G02X1332953Y1258345I1502J0D01*
G03X1333030Y1258502I-123J158D01*
G01Y1258818D01*
G03X1332953Y1258975I-200J-1D01*
G02X1332374Y1260160I923J1185D01*
G02X1333876Y1261662I1502J0D01*
G02X1335061Y1261083I0J-1502D01*
G03X1335218Y1261006I158J123D01*
G01X1335534D01*
G03X1335691Y1261083I-1J200D01*
G02X1338061I1185J-923D01*
G03X1338218Y1261006I158J123D01*
G01X1338534D01*
G03X1338691Y1261083I-1J200D01*
G02X1341061I1185J-923D01*
G03X1341218Y1261006I158J123D01*
G01X1341534D01*
G03X1341691Y1261083I-1J200D01*
G02X1344061I1185J-923D01*
G03X1344218Y1261006I158J123D01*
G01X1344534D01*
G03X1344691Y1261083I-1J200D01*
G02X1347061I1185J-923D01*
G03X1347218Y1261006I158J123D01*
G01X1347534D01*
G03X1347691Y1261083I-1J200D01*
G02X1350061I1185J-923D01*
G03X1350218Y1261006I158J123D01*
G01X1350534D01*
G03X1350691Y1261083I-1J200D01*
G02X1353061I1185J-923D01*
G03X1353218Y1261006I158J123D01*
G01X1353534D01*
G03X1353691Y1261083I-1J200D01*
G02X1356061I1185J-923D01*
G03X1356218Y1261006I158J123D01*
G01X1356534D01*
G03X1356691Y1261083I-1J200D01*
G02X1359061I1185J-923D01*
G03X1359218Y1261006I158J123D01*
G01X1359534D01*
G03X1359691Y1261083I-1J200D01*
G02X1362061I1185J-923D01*
G03X1362218Y1261006I158J123D01*
G37*
G36*
G01X1417163D02*
X1417479D01*
G03X1417636Y1261083I-1J200D01*
G02X1420006I1185J-923D01*
G03X1420163Y1261006I158J123D01*
G01X1420479D01*
G03X1420636Y1261083I-1J200D01*
G02X1421821Y1261662I1185J-923D01*
G02X1423323Y1260160I0J-1502D01*
G02X1422744Y1258975I-1502J0D01*
G03X1422667Y1258818I123J-158D01*
G01Y1258502D01*
G03X1422744Y1258345I200J1D01*
G02X1423323Y1257160I-923J-1185D01*
G02X1421821Y1255658I-1502J0D01*
G02X1420636Y1256237I0J1502D01*
G03X1420479Y1256314I-158J-123D01*
G01X1420163D01*
G03X1420006Y1256237I1J-200D01*
G02X1417636I-1185J923D01*
G03X1417479Y1256314I-158J-123D01*
G01X1417163D01*
G03X1417006Y1256237I1J-200D01*
G02X1414636I-1185J923D01*
G03X1414479Y1256314I-158J-123D01*
G01X1414163D01*
G03X1414006Y1256237I1J-200D01*
G02X1411636I-1185J923D01*
G03X1411479Y1256314I-158J-123D01*
G01X1411163D01*
G03X1411006Y1256237I1J-200D01*
G02X1408636I-1185J923D01*
G03X1408479Y1256314I-158J-123D01*
G01X1408163D01*
G03X1408006Y1256237I1J-200D01*
G02X1405636I-1185J923D01*
G03X1405479Y1256314I-158J-123D01*
G01X1405163D01*
G03X1405006Y1256237I1J-200D01*
G02X1402636I-1185J923D01*
G03X1402479Y1256314I-158J-123D01*
G01X1402163D01*
G03X1402006Y1256237I1J-200D01*
G02X1399636I-1185J923D01*
G03X1399479Y1256314I-158J-123D01*
G01X1399163D01*
G03X1399006Y1256237I1J-200D01*
G02X1396636I-1185J923D01*
G03X1396479Y1256314I-158J-123D01*
G01X1396163D01*
G03X1396006Y1256237I1J-200D01*
G02X1393636I-1185J923D01*
G03X1393479Y1256314I-158J-123D01*
G01X1393163D01*
G03X1393006Y1256237I1J-200D01*
G02X1390636I-1185J923D01*
G03X1390479Y1256314I-158J-123D01*
G01X1390163D01*
G03X1390006Y1256237I1J-200D01*
G02X1387636I-1185J923D01*
G03X1387479Y1256314I-158J-123D01*
G01X1387163D01*
G03X1387006Y1256237I1J-200D01*
G02X1385821Y1255658I-1185J923D01*
G02X1384319Y1257160I0J1502D01*
G02X1384898Y1258345I1502J0D01*
G03X1384975Y1258502I-123J158D01*
G01Y1258818D01*
G03X1384898Y1258975I-200J-1D01*
G02X1384319Y1260160I923J1185D01*
G02X1385821Y1261662I1502J0D01*
G02X1387006Y1261083I0J-1502D01*
G03X1387163Y1261006I158J123D01*
G01X1387479D01*
G03X1387636Y1261083I-1J200D01*
G02X1390006I1185J-923D01*
G03X1390163Y1261006I158J123D01*
G01X1390479D01*
G03X1390636Y1261083I-1J200D01*
G02X1393006I1185J-923D01*
G03X1393163Y1261006I158J123D01*
G01X1393479D01*
G03X1393636Y1261083I-1J200D01*
G02X1396006I1185J-923D01*
G03X1396163Y1261006I158J123D01*
G01X1396479D01*
G03X1396636Y1261083I-1J200D01*
G02X1399006I1185J-923D01*
G03X1399163Y1261006I158J123D01*
G01X1399479D01*
G03X1399636Y1261083I-1J200D01*
G02X1402006I1185J-923D01*
G03X1402163Y1261006I158J123D01*
G01X1402479D01*
G03X1402636Y1261083I-1J200D01*
G02X1405006I1185J-923D01*
G03X1405163Y1261006I158J123D01*
G01X1405479D01*
G03X1405636Y1261083I-1J200D01*
G02X1408006I1185J-923D01*
G03X1408163Y1261006I158J123D01*
G01X1408479D01*
G03X1408636Y1261083I-1J200D01*
G02X1411006I1185J-923D01*
G03X1411163Y1261006I158J123D01*
G01X1411479D01*
G03X1411636Y1261083I-1J200D01*
G02X1414006I1185J-923D01*
G03X1414163Y1261006I158J123D01*
G01X1414479D01*
G03X1414636Y1261083I-1J200D01*
G02X1417006I1185J-923D01*
G03X1417163Y1261006I158J123D01*
G37*
G36*
G01X1309299Y1281962D02*
X1308936Y1282096D01*
X1308853Y1282090D01*
X1308814Y1282070D01*
G02X1308107Y1281893I-707J1325D01*
G02Y1284897I0J1502D01*
G02X1309505Y1283943I0J-1501D01*
G01X1309521Y1283902D01*
X1309581Y1283844D01*
X1309944Y1283710D01*
X1310027Y1283716D01*
X1310066Y1283736D01*
G02X1310773Y1283913I707J-1325D01*
G02Y1280909I0J-1502D01*
G02X1309375Y1281863I0J1501D01*
G01X1309359Y1281904D01*
X1309299Y1281962D01*
G37*
G36*
G01X1426087Y1300953D02*
X1426062Y1300906D01*
G02X1424732Y1300101I-1330J696D01*
G02Y1303105I0J1502D01*
G02X1425990Y1302424I0J-1502D01*
G01X1426019Y1302380D01*
X1426113Y1302331D01*
X1426565Y1302353D01*
X1426654Y1302410D01*
X1426679Y1302457D01*
G02X1428009Y1303262I1330J-696D01*
G02X1429238Y1302623I0J-1501D01*
G01X1429266Y1302583D01*
X1429350Y1302539D01*
X1429770Y1302531D01*
X1429855Y1302572D01*
X1429884Y1302611D01*
G02X1431080Y1303204I1196J-910D01*
G02Y1300200I0J-1502D01*
G02X1429851Y1300839I0J1501D01*
G01X1429823Y1300879D01*
X1429739Y1300923D01*
X1429319Y1300931D01*
X1429234Y1300890D01*
X1429205Y1300851D01*
G02X1428009Y1300258I-1196J910D01*
G02X1426751Y1300939I0J1502D01*
G01X1426722Y1300983D01*
X1426628Y1301032D01*
X1426176Y1301010D01*
X1426087Y1300953D01*
G37*
G36*
G01X1358382Y1112146D02*
G02Y1115150I0J1502D01*
G02X1359369Y1114780I0J-1501D01*
G01X1359370D01*
Y1114779D01*
G03X1359500Y1114731I130J152D01*
G01X1359764D01*
G03X1359894Y1114779I0J200D01*
G01X1359895Y1114780D01*
G02X1360882Y1115150I987J-1131D01*
G02Y1112146I0J-1502D01*
G02X1359895Y1112516I0J1501D01*
G01X1359894D01*
Y1112517D01*
G03X1359764Y1112565I-130J-152D01*
G01X1359500D01*
G03X1359370Y1112517I0J-200D01*
G01X1359369Y1112516D01*
G02X1358382Y1112146I-987J1131D01*
G37*
G36*
G01X1494638Y1142891D02*
G02X1497642I1502J0D01*
G02X1497081Y1141720I-1503J0D01*
G01X1497045Y1141691D01*
X1497006Y1141608D01*
X1497011Y1141246D01*
G03X1497090Y1141089I200J2D01*
G02X1497687Y1139891I-905J-1199D01*
G02X1494683I-1502J0D01*
G02X1495244Y1141062I1503J0D01*
G01X1495280Y1141091D01*
X1495319Y1141174D01*
X1495314Y1141536D01*
G03X1495235Y1141693I-200J-2D01*
G02X1494638Y1142891I905J1199D01*
G37*
G36*
G01Y1155491D02*
G02X1497642I1502J0D01*
G02X1497081Y1154320I-1503J0D01*
G01X1497045Y1154291D01*
X1497006Y1154208D01*
X1497011Y1153846D01*
G03X1497090Y1153689I200J2D01*
G02X1497687Y1152491I-905J-1199D01*
G02X1494683I-1502J0D01*
G02X1495244Y1153662I1503J0D01*
G01X1495280Y1153691D01*
X1495319Y1153774D01*
X1495314Y1154136D01*
G03X1495235Y1154293I-200J-2D01*
G02X1494638Y1155491I905J1199D01*
G37*
G36*
G01Y1168091D02*
G02X1497642I1502J0D01*
G02X1497081Y1166920I-1503J0D01*
G01X1497045Y1166891D01*
X1497006Y1166808D01*
X1497011Y1166446D01*
G03X1497090Y1166289I200J2D01*
G02X1497687Y1165091I-905J-1199D01*
G02X1494683I-1502J0D01*
G02X1495244Y1166262I1503J0D01*
G01X1495280Y1166291D01*
X1495319Y1166374D01*
X1495314Y1166736D01*
G03X1495235Y1166893I-200J-2D01*
G02X1494638Y1168091I905J1199D01*
G37*
G36*
G01X1514467Y1171872D02*
X1518207D01*
G02Y1169268I0J-1302D01*
G01X1514467D01*
G02X1513460Y1169744I0J1303D01*
G01X1513432Y1169778D01*
X1513355Y1169815D01*
X1512964Y1169826D01*
X1512885Y1169792D01*
X1512856Y1169760D01*
G02X1511968Y1169368I-888J810D01*
G02Y1171772I0J1202D01*
G02X1512856Y1171380I0J-1202D01*
G01X1512885Y1171348D01*
X1512964Y1171314D01*
X1513311Y1171324D01*
G03X1513460Y1171396I-5J200D01*
G02X1514467Y1171872I1007J-827D01*
G37*
G36*
G01Y1179354D02*
X1518207D01*
G02Y1176748I0J-1303D01*
G01X1514467D01*
G02X1513461Y1177224I1J1303D01*
G01X1513433Y1177258D01*
X1513355Y1177296D01*
X1513008Y1177305D01*
G03X1512857Y1177241I-4J-200D01*
G01X1512856Y1177240D01*
G02X1511968Y1176848I-888J810D01*
G02Y1179252I0J1202D01*
G02X1512855Y1178861I0J-1202D01*
G03X1513008Y1178795I149J134D01*
G01X1513310Y1178804D01*
G03X1513460Y1178877I-4J200D01*
G02X1514467Y1179354I1008J-826D01*
G37*
G36*
G01X1494638Y1180691D02*
G02X1497642I1502J0D01*
G02X1497081Y1179520I-1503J0D01*
G01X1497045Y1179491D01*
X1497006Y1179408D01*
X1497011Y1179046D01*
G03X1497090Y1178889I200J2D01*
G02X1497687Y1177691I-905J-1199D01*
G02X1494683I-1502J0D01*
G02X1495244Y1178862I1503J0D01*
G01X1495280Y1178891D01*
X1495319Y1178974D01*
X1495314Y1179336D01*
G03X1495235Y1179493I-200J-2D01*
G02X1494638Y1180691I905J1199D01*
G37*
G36*
G01X1389878Y1200821D02*
G02X1392882I1502J0D01*
G02X1392512Y1199834I-1501J0D01*
G01Y1199833D01*
X1392511D01*
G03X1392463Y1199703I152J-130D01*
G01Y1199439D01*
G03X1392511Y1199309I200J0D01*
G01X1392512Y1199308D01*
G02X1392882Y1198321I-1131J-987D01*
G02X1389878I-1502J0D01*
G02X1390248Y1199308I1501J0D01*
G01Y1199309D01*
X1390249D01*
G03X1390297Y1199439I-152J130D01*
G01Y1199703D01*
G03X1390249Y1199833I-200J0D01*
G01X1390248Y1199834D01*
G02X1389878Y1200821I1131J987D01*
G37*
G36*
G01X1403343D02*
G02X1406347I1502J0D01*
G02X1405977Y1199834I-1501J0D01*
G01Y1199833D01*
X1405976D01*
G03X1405928Y1199703I152J-130D01*
G01Y1199439D01*
G03X1405976Y1199309I200J0D01*
G01X1405977Y1199308D01*
G02X1406347Y1198321I-1131J-987D01*
G02X1403343I-1502J0D01*
G02X1403713Y1199308I1501J0D01*
G01Y1199309D01*
X1403714D01*
G03X1403762Y1199439I-152J130D01*
G01Y1199703D01*
G03X1403714Y1199833I-200J0D01*
G01X1403713Y1199834D01*
G02X1403343Y1200821I1131J987D01*
G37*
G36*
G01X1408808D02*
G02X1411812I1502J0D01*
G02X1411442Y1199834I-1501J0D01*
G01Y1199833D01*
X1411441D01*
G03X1411393Y1199703I152J-130D01*
G01Y1199439D01*
G03X1411441Y1199309I200J0D01*
G01X1411442Y1199308D01*
G02X1411812Y1198321I-1131J-987D01*
G02X1408808I-1502J0D01*
G02X1409178Y1199308I1501J0D01*
G01Y1199309D01*
X1409179D01*
G03X1409227Y1199439I-152J130D01*
G01Y1199703D01*
G03X1409179Y1199833I-200J0D01*
G01X1409178Y1199834D01*
G02X1408808Y1200821I1131J987D01*
G37*
G36*
G01X1416808D02*
G02X1419812I1502J0D01*
G02X1419442Y1199834I-1501J0D01*
G01Y1199833D01*
X1419441D01*
G03X1419393Y1199703I152J-130D01*
G01Y1199439D01*
G03X1419441Y1199309I200J0D01*
G01X1419442Y1199308D01*
G02X1419812Y1198321I-1131J-987D01*
G02X1416808I-1502J0D01*
G02X1417178Y1199308I1501J0D01*
G01Y1199309D01*
X1417179D01*
G03X1417227Y1199439I-152J130D01*
G01Y1199703D01*
G03X1417179Y1199833I-200J0D01*
G01X1417178Y1199834D01*
G02X1416808Y1200821I1131J987D01*
G37*
G36*
G01X1435738D02*
G02X1438742I1502J0D01*
G02X1438372Y1199834I-1501J0D01*
G01Y1199833D01*
X1438371D01*
G03X1438323Y1199703I152J-130D01*
G01Y1199439D01*
G03X1438371Y1199309I200J0D01*
G01X1438372Y1199308D01*
G02X1438742Y1198321I-1131J-987D01*
G02X1435738I-1502J0D01*
G02X1436108Y1199308I1501J0D01*
G01Y1199309D01*
X1436109D01*
G03X1436157Y1199439I-152J130D01*
G01Y1199703D01*
G03X1436109Y1199833I-200J0D01*
G01X1436108Y1199834D01*
G02X1435738Y1200821I1131J987D01*
G37*
G36*
G01X1480675Y1200601D02*
G02X1482177Y1202103I0J1502D01*
G02X1482168Y1201941I-1502J2D01*
G01X1482163Y1201897D01*
X1482192Y1201813D01*
X1482468Y1201527D01*
X1482551Y1201496D01*
X1482595Y1201499D01*
G02X1482704Y1201503I110J-1498D01*
G01X1482705D01*
G02X1481203Y1200001I0J-1502D01*
G02X1481212Y1200163I1502J-2D01*
G01X1481217Y1200207D01*
X1481188Y1200291D01*
X1480912Y1200577D01*
X1480829Y1200608D01*
X1480785Y1200605D01*
G02X1480676Y1200601I-110J1498D01*
G01X1480675D01*
G37*
G36*
G01X1419123Y1209405D02*
G02X1422127I1502J0D01*
G02X1421757Y1208418I-1501J0D01*
G01Y1208417D01*
X1421756D01*
G03X1421708Y1208287I152J-130D01*
G01Y1208023D01*
G03X1421756Y1207893I200J0D01*
G01X1421757Y1207892D01*
G02Y1205918I-1131J-987D01*
G01Y1205917D01*
X1421756D01*
G03X1421708Y1205787I152J-130D01*
G01Y1205523D01*
G03X1421756Y1205393I200J0D01*
G01X1421757Y1205392D01*
G02X1422127Y1204405I-1131J-987D01*
G02X1419123I-1502J0D01*
G02X1419493Y1205392I1501J0D01*
G01Y1205393D01*
X1419494D01*
G03X1419542Y1205523I-152J130D01*
G01Y1205787D01*
G03X1419494Y1205917I-200J0D01*
G01X1419493Y1205918D01*
G02Y1207892I1131J987D01*
G01Y1207893D01*
X1419494D01*
G03X1419542Y1208023I-152J130D01*
G01Y1208287D01*
G03X1419494Y1208417I-200J0D01*
G01X1419493Y1208418D01*
G02X1419123Y1209405I1131J987D01*
G37*
G36*
G01X1392193Y1211905D02*
G02X1395197I1502J0D01*
G02X1394827Y1210918I-1501J0D01*
G01Y1210917D01*
X1394826D01*
G03X1394778Y1210787I152J-130D01*
G01Y1210523D01*
G03X1394826Y1210393I200J0D01*
G01X1394827Y1210392D01*
G02Y1208418I-1131J-987D01*
G01Y1208417D01*
X1394826D01*
G03X1394778Y1208287I152J-130D01*
G01Y1208023D01*
G03X1394826Y1207893I200J0D01*
G01X1394827Y1207892D01*
G02Y1205918I-1131J-987D01*
G01Y1205917D01*
X1394826D01*
G03X1394778Y1205787I152J-130D01*
G01Y1205523D01*
G03X1394826Y1205393I200J0D01*
G01X1394827Y1205392D01*
G02X1395197Y1204405I-1131J-987D01*
G02X1392193I-1502J0D01*
G02X1392563Y1205392I1501J0D01*
G01Y1205393D01*
X1392564D01*
G03X1392612Y1205523I-152J130D01*
G01Y1205787D01*
G03X1392564Y1205917I-200J0D01*
G01X1392563Y1205918D01*
G02Y1207892I1131J987D01*
G01Y1207893D01*
X1392564D01*
G03X1392612Y1208023I-152J130D01*
G01Y1208287D01*
G03X1392564Y1208417I-200J0D01*
G01X1392563Y1208418D01*
G02Y1210392I1131J987D01*
G01Y1210393D01*
X1392564D01*
G03X1392612Y1210523I-152J130D01*
G01Y1210787D01*
G03X1392564Y1210917I-200J0D01*
G01X1392563Y1210918D01*
G02X1392193Y1211905I1131J987D01*
G37*
G36*
G01X1406493Y1212117D02*
G02X1409497I1502J0D01*
G02X1409127Y1211130I-1501J0D01*
G01Y1211129D01*
X1409126D01*
G03X1409078Y1210999I152J-130D01*
G01Y1210735D01*
G03X1409126Y1210605I200J0D01*
G01X1409127Y1210604D01*
G02Y1208630I-1131J-987D01*
G01Y1208629D01*
X1409126D01*
G03X1409078Y1208499I152J-130D01*
G01Y1208235D01*
G03X1409126Y1208105I200J0D01*
G01X1409127Y1208104D01*
G02Y1206130I-1131J-987D01*
G01Y1206129D01*
X1409126D01*
G03X1409078Y1205999I152J-130D01*
G01Y1205735D01*
G03X1409126Y1205605I200J0D01*
G01X1409127Y1205604D01*
G02X1409497Y1204617I-1131J-987D01*
G02X1406493I-1502J0D01*
G02X1406863Y1205604I1501J0D01*
G01Y1205605D01*
X1406864D01*
G03X1406912Y1205735I-152J130D01*
G01Y1205999D01*
G03X1406864Y1206129I-200J0D01*
G01X1406863Y1206130D01*
G02Y1208104I1131J987D01*
G01Y1208105D01*
X1406864D01*
G03X1406912Y1208235I-152J130D01*
G01Y1208499D01*
G03X1406864Y1208629I-200J0D01*
G01X1406863Y1208630D01*
G02Y1210604I1131J987D01*
G01Y1210605D01*
X1406864D01*
G03X1406912Y1210735I-152J130D01*
G01Y1210999D01*
G03X1406864Y1211129I-200J0D01*
G01X1406863Y1211130D01*
G02X1406493Y1212117I1131J987D01*
G37*
G36*
G01X1433423D02*
G02X1436427I1502J0D01*
G02X1436057Y1211130I-1501J0D01*
G01Y1211129D01*
X1436056D01*
G03X1436008Y1210999I152J-130D01*
G01Y1210735D01*
G03X1436056Y1210605I200J0D01*
G01X1436057Y1210604D01*
G02Y1208630I-1131J-987D01*
G01Y1208629D01*
X1436056D01*
G03X1436008Y1208499I152J-130D01*
G01Y1208235D01*
G03X1436056Y1208105I200J0D01*
G01X1436057Y1208104D01*
G02Y1206130I-1131J-987D01*
G01Y1206129D01*
X1436056D01*
G03X1436008Y1205999I152J-130D01*
G01Y1205735D01*
G03X1436056Y1205605I200J0D01*
G01X1436057Y1205604D01*
G02X1436427Y1204617I-1131J-987D01*
G02X1433423I-1502J0D01*
G02X1433793Y1205604I1501J0D01*
G01Y1205605D01*
X1433794D01*
G03X1433842Y1205735I-152J130D01*
G01Y1205999D01*
G03X1433794Y1206129I-200J0D01*
G01X1433793Y1206130D01*
G02Y1208104I1131J987D01*
G01Y1208105D01*
X1433794D01*
G03X1433842Y1208235I-152J130D01*
G01Y1208499D01*
G03X1433794Y1208629I-200J0D01*
G01X1433793Y1208630D01*
G02Y1210604I1131J987D01*
G01Y1210605D01*
X1433794D01*
G03X1433842Y1210735I-152J130D01*
G01Y1210999D01*
G03X1433794Y1211129I-200J0D01*
G01X1433793Y1211130D01*
G02X1433423Y1212117I1131J987D01*
G37*
G36*
G01X1553962Y1216141D02*
G02X1553740Y1216120I-224J1181D01*
G02X1554942Y1217322I0J1202D01*
G02X1554921Y1217100I-1202J2D01*
G03X1555388Y1216633I393J-74D01*
G02X1555610Y1216654I224J-1181D01*
G02X1554408Y1215452I0J-1202D01*
G02X1554429Y1215674I1202J-2D01*
G03X1553962Y1216141I-393J74D01*
G37*
G36*
G01X1550000Y1193679D02*
G02X1551202Y1194881I0J1202D01*
G02X1551181Y1194659I-1202J2D01*
G01X1551172Y1194610D01*
X1551201Y1194517D01*
X1551506Y1194212D01*
X1551599Y1194183D01*
X1551648Y1194192D01*
G02X1551870Y1194213I224J-1181D01*
G02Y1191809I0J-1202D01*
G02X1551648Y1191830I2J1202D01*
G01X1551599Y1191839D01*
X1551506Y1191810D01*
X1551201Y1191505D01*
X1551172Y1191412D01*
X1551181Y1191363D01*
G02X1551202Y1191141I-1181J-224D01*
G02X1551181Y1190919I-1202J2D01*
G01X1551172Y1190870D01*
X1551201Y1190777D01*
X1551506Y1190472D01*
X1551599Y1190443D01*
X1551648Y1190452D01*
G02X1551870Y1190473I224J-1181D01*
G02Y1188069I0J-1202D01*
G02X1551648Y1188090I2J1202D01*
G01X1551599Y1188099D01*
X1551506Y1188070D01*
X1551201Y1187765D01*
X1551172Y1187672D01*
X1551181Y1187623D01*
G02X1551202Y1187401I-1181J-224D01*
G02X1551181Y1187179I-1202J2D01*
G01X1551172Y1187130D01*
X1551201Y1187037D01*
X1551506Y1186732D01*
X1551599Y1186703D01*
X1551648Y1186712D01*
G02X1551870Y1186733I224J-1181D01*
G02X1550668Y1185531I0J-1202D01*
G02X1550689Y1185753I1202J-2D01*
G01X1550698Y1185802D01*
X1550669Y1185895D01*
X1550364Y1186200D01*
X1550271Y1186229D01*
X1550222Y1186220D01*
G02X1550000Y1186199I-224J1181D01*
G02X1549778Y1186220I2J1202D01*
G01X1549729Y1186229D01*
X1549636Y1186200D01*
X1549331Y1185895D01*
X1549302Y1185802D01*
X1549311Y1185753D01*
G02X1549332Y1185531I-1181J-224D01*
G02X1546928I-1202J0D01*
G02X1546949Y1185752I1202J-3D01*
G01Y1185754D01*
G03X1546894Y1185931I-197J36D01*
G01X1546624Y1186200D01*
X1546531Y1186229D01*
X1546482Y1186220D01*
G02X1546259Y1186199I-224J1181D01*
G02X1547461Y1187401I0J1202D01*
G02X1547440Y1187180I-1202J3D01*
G01Y1187178D01*
G03X1547495Y1187001I197J-36D01*
G01X1547765Y1186732D01*
X1547858Y1186703D01*
X1547907Y1186712D01*
G02X1548130Y1186733I224J-1181D01*
G02X1548352Y1186712I-2J-1202D01*
G01X1548401Y1186703D01*
X1548494Y1186732D01*
X1548799Y1187037D01*
X1548828Y1187130D01*
X1548819Y1187179D01*
G02X1548798Y1187401I1181J224D01*
G02X1550000Y1188603I1202J0D01*
G02X1550222Y1188582I-2J-1202D01*
G01X1550271Y1188573D01*
X1550364Y1188602D01*
X1550669Y1188907D01*
X1550698Y1189000D01*
X1550689Y1189049D01*
G02X1550668Y1189271I1181J224D01*
G02X1550689Y1189493I1202J-2D01*
G01X1550698Y1189542D01*
X1550669Y1189635D01*
X1550364Y1189940D01*
X1550271Y1189969D01*
X1550222Y1189960D01*
G02X1550000Y1189939I-224J1181D01*
G02Y1192343I0J1202D01*
G02X1550222Y1192322I-2J-1202D01*
G01X1550271Y1192313D01*
X1550364Y1192342D01*
X1550669Y1192647D01*
X1550698Y1192740D01*
X1550689Y1192789D01*
G02X1550668Y1193011I1181J224D01*
G02X1550689Y1193233I1202J-2D01*
G01X1550698Y1193282D01*
X1550669Y1193375D01*
X1550364Y1193680D01*
X1550271Y1193709D01*
X1550222Y1193700D01*
G02X1550000Y1193679I-224J1181D01*
G37*
G36*
G01X1541317Y1183661D02*
G02X1543721I1202J0D01*
G02X1543700Y1183439I-1202J2D01*
G01X1543691Y1183390D01*
X1543720Y1183297D01*
X1544025Y1182992D01*
X1544118Y1182963D01*
X1544167Y1182972D01*
G02X1544389Y1182993I224J-1181D01*
G02X1543187Y1181791I0J-1202D01*
G02X1543208Y1182013I1202J-2D01*
G01X1543217Y1182062D01*
X1543188Y1182155D01*
X1542883Y1182460D01*
X1542790Y1182489D01*
X1542741Y1182480D01*
G02X1542519Y1182459I-224J1181D01*
G02X1542297Y1182480I2J1202D01*
G01X1542248Y1182489D01*
X1542155Y1182460D01*
X1541850Y1182155D01*
X1541821Y1182062D01*
X1541830Y1182013D01*
G02X1541851Y1181791I-1181J-224D01*
G02X1540649Y1180589I-1202J0D01*
G02X1540427Y1180610I2J1202D01*
G01X1540378Y1180619D01*
X1540285Y1180590D01*
X1539980Y1180285D01*
X1539951Y1180192D01*
X1539960Y1180143D01*
G02X1539981Y1179921I-1181J-224D01*
G02X1539960Y1179698I-1202J1D01*
G01X1539951Y1179649D01*
X1539980Y1179556D01*
X1540249Y1179286D01*
G03X1540426Y1179231I141J142D01*
G01X1540427D01*
G02X1540649Y1179252I224J-1181D01*
G02X1539447Y1178050I0J-1202D01*
G02X1539468Y1178273I1202J-1D01*
G01X1539477Y1178322D01*
X1539448Y1178415D01*
X1539179Y1178685D01*
G03X1539002Y1178740I-141J-142D01*
G01X1539001D01*
G02X1538779Y1178719I-224J1181D01*
G02Y1181123I0J1202D01*
G02X1539001Y1181102I-2J-1202D01*
G01X1539050Y1181093D01*
X1539143Y1181122D01*
X1539448Y1181427D01*
X1539477Y1181520D01*
X1539468Y1181569D01*
G02X1539447Y1181791I1181J224D01*
G02X1539468Y1182013I1202J-2D01*
G01X1539477Y1182062D01*
X1539448Y1182155D01*
X1539143Y1182460D01*
X1539050Y1182489D01*
X1539001Y1182480D01*
G02X1538779Y1182459I-224J1181D01*
G02X1539981Y1183661I0J1202D01*
G02X1539960Y1183439I-1202J2D01*
G01X1539951Y1183390D01*
X1539980Y1183297D01*
X1540285Y1182992D01*
X1540378Y1182963D01*
X1540427Y1182972D01*
G02X1540649Y1182993I224J-1181D01*
G02X1540871Y1182972I-2J-1202D01*
G01X1540920Y1182963D01*
X1541013Y1182992D01*
X1541318Y1183297D01*
X1541347Y1183390D01*
X1541338Y1183439D01*
G02X1541317Y1183661I1181J224D01*
G37*
G36*
G01X1518876D02*
G02X1520078Y1182459I1202J0D01*
G02X1519855Y1182480I1J1202D01*
G01X1519806Y1182489D01*
X1519713Y1182460D01*
X1519443Y1182191D01*
G03X1519388Y1182014I142J-141D01*
G01Y1182013D01*
G02X1519409Y1181791I-1181J-224D01*
G02X1517005I-1202J0D01*
G02X1517026Y1182013I1202J-2D01*
G01X1517035Y1182062D01*
X1517006Y1182155D01*
X1516703Y1182459D01*
X1516608Y1182488D01*
X1516559Y1182479D01*
G02X1516338Y1182459I-218J1182D01*
G02X1516117Y1182480I3J1202D01*
G01X1516115D01*
G03X1515938Y1182425I-36J-197D01*
G01X1515669Y1182155D01*
X1515640Y1182062D01*
X1515649Y1182013D01*
G02X1515670Y1181790I-1181J-224D01*
G02X1514468Y1182992I-1202J0D01*
G02X1514689Y1182971I-3J-1202D01*
G01X1514691D01*
G03X1514868Y1183026I36J197D01*
G01X1515137Y1183296D01*
X1515166Y1183389D01*
X1515157Y1183438D01*
G02X1515136Y1183661I1181J224D01*
G02X1517540I1202J0D01*
G02X1517519Y1183439I-1202J2D01*
G01X1517510Y1183390D01*
X1517539Y1183297D01*
X1517842Y1182993D01*
X1517937Y1182964D01*
X1517986Y1182973D01*
G02X1518207Y1182993I218J-1182D01*
G02X1518430Y1182972I-1J-1202D01*
G01X1518479Y1182963D01*
X1518572Y1182992D01*
X1518842Y1183261D01*
G03X1518897Y1183438I-142J141D01*
G01Y1183439D01*
G02X1518876Y1183661I1181J224D01*
G37*
G36*
G01X1531299Y1178719D02*
G02X1532501Y1179921I0J1202D01*
G02X1532480Y1179699I-1202J2D01*
G01X1532471Y1179650D01*
X1532500Y1179557D01*
X1532805Y1179252D01*
X1532898Y1179223D01*
X1532947Y1179232D01*
G02X1533169Y1179253I224J-1181D01*
G02X1534371Y1178051I0J-1202D01*
G02X1534350Y1177828I-1202J1D01*
G01X1534341Y1177779D01*
X1534370Y1177686D01*
X1534639Y1177416D01*
G03X1534816Y1177361I141J142D01*
G01X1534817D01*
G02X1535039Y1177382I224J-1181D01*
G02X1536241Y1176180I0J-1202D01*
G02X1536220Y1175958I-1202J2D01*
G01X1536211Y1175909D01*
X1536240Y1175816D01*
X1536545Y1175511D01*
X1536638Y1175482D01*
X1536687Y1175491D01*
G02X1536909Y1175512I224J-1181D01*
G02X1535707Y1174310I0J-1202D01*
G02X1535728Y1174532I1202J-2D01*
G01X1535737Y1174581D01*
X1535708Y1174674D01*
X1535403Y1174979D01*
X1535310Y1175008D01*
X1535261Y1174999D01*
G02X1535039Y1174978I-224J1181D01*
G02X1534817Y1174999I2J1202D01*
G01X1534768Y1175008D01*
X1534675Y1174979D01*
X1534370Y1174674D01*
X1534341Y1174581D01*
X1534350Y1174532D01*
G02X1534371Y1174310I-1181J-224D01*
G02X1531967I-1202J0D01*
G02X1531976Y1174452I1202J-5D01*
G01Y1174454D01*
X1531981Y1174500D01*
X1531949Y1174588D01*
X1531649Y1174875D01*
X1531559Y1174903D01*
X1531513Y1174895D01*
G02X1531299Y1174878I-210J1285D01*
G01X1531022D01*
G03X1530873Y1174812I0J-200D01*
G01X1530646Y1174558D01*
X1530620Y1174478D01*
X1530624Y1174436D01*
G02X1530631Y1174310I-1195J-130D01*
G02X1528227I-1202J0D01*
G02X1528234Y1174435I1202J-5D01*
G01Y1174437D01*
X1528238Y1174478D01*
X1528212Y1174558D01*
X1527985Y1174812D01*
G03X1527836Y1174878I-149J-134D01*
G01X1527559D01*
G02X1527345Y1174895I-4J1302D01*
G01X1527299Y1174903D01*
X1527209Y1174875D01*
X1526942Y1174620D01*
G03X1526882Y1174454I139J-144D01*
G01Y1174453D01*
G02X1526891Y1174310I-1193J-147D01*
G02X1525689Y1175512I-1202J0D01*
G02X1525831Y1175503I-5J-1202D01*
G01X1525833D01*
X1525879Y1175498D01*
X1525967Y1175530D01*
X1526254Y1175830D01*
X1526282Y1175920D01*
X1526274Y1175966D01*
G02X1526256Y1176180I1285J216D01*
G02X1527559Y1177482I1303J-1D01*
G01X1531299D01*
G02X1531513Y1177465I4J-1302D01*
G01X1531560Y1177457D01*
X1531650Y1177485D01*
X1531950Y1177772D01*
X1531982Y1177860D01*
X1531976Y1177907D01*
G02X1531967Y1178051I1193J147D01*
G02X1531988Y1178273I1202J-2D01*
G01X1531997Y1178322D01*
X1531968Y1178415D01*
X1531663Y1178720D01*
X1531570Y1178749D01*
X1531521Y1178740D01*
G02X1531299Y1178719I-224J1181D01*
G37*
G36*
G01X1522638Y1179699D02*
G02X1522617Y1179921I1181J224D01*
G02X1523819Y1178719I1202J0D01*
G02X1523596Y1178740I1J1202D01*
G03X1523129Y1178273I-74J-393D01*
G02X1523150Y1178051I-1181J-224D01*
G02X1521948Y1179253I-1202J0D01*
G02X1522171Y1179232I-1J-1202D01*
G03X1522638Y1179699I74J393D01*
G37*
G36*
G01X1472915Y876224D02*
G02X1472558Y877196I1145J972D01*
G02X1475562I1502J0D01*
G02X1474737Y875855I-1502J0D01*
G01X1474697Y875835D01*
X1474641Y875762D01*
X1474560Y875363D01*
X1474583Y875274D01*
X1474613Y875239D01*
G02X1474970Y874267I-1145J-972D01*
G02X1471966I-1502J0D01*
G02X1472791Y875608I1502J0D01*
G01X1472831Y875628D01*
X1472887Y875701D01*
X1472968Y876100D01*
X1472945Y876189D01*
X1472915Y876224D01*
G37*
G36*
G01X1510526Y907148D02*
G02Y910754I0J1803D01*
G01X1513926D01*
G02Y907148I0J-1803D01*
G01X1510526D01*
G37*
G36*
G01X1416486Y909737D02*
G02X1415782Y911009I797J1272D01*
G02X1418786I1502J0D01*
G02X1418155Y909785I-1503J0D01*
G03X1418071Y909616I116J-163D01*
G01X1418081Y909283D01*
G03X1418174Y909120I200J6D01*
G02X1418878Y907848I-797J-1272D01*
G02X1417376Y906346I-1502J0D01*
G02X1416389Y906716I0J1501D01*
G01X1416388D01*
Y906717D01*
G03X1416258Y906765I-130J-152D01*
G01X1415994D01*
G03X1415864Y906717I0J-200D01*
G01X1415863Y906716D01*
G02X1413889I-987J1131D01*
G01X1413888D01*
Y906717D01*
G03X1413758Y906765I-130J-152D01*
G01X1413494D01*
G03X1413364Y906717I0J-200D01*
G01X1413363Y906716D01*
G02X1411389I-987J1131D01*
G01X1411388D01*
Y906717D01*
G03X1411258Y906765I-130J-152D01*
G01X1410994D01*
G03X1410864Y906717I0J-200D01*
G01X1410863Y906716D01*
G02X1409876Y906346I-987J1131D01*
G02Y909350I0J1502D01*
G02X1410863Y908980I0J-1501D01*
G01X1410864D01*
Y908979D01*
G03X1410994Y908931I130J152D01*
G01X1411258D01*
G03X1411388Y908979I0J200D01*
G01X1411389Y908980D01*
G02X1413363I987J-1131D01*
G01X1413364D01*
Y908979D01*
G03X1413494Y908931I130J152D01*
G01X1413758D01*
G03X1413888Y908979I0J200D01*
G01X1413889Y908980D01*
G02X1415863I987J-1131D01*
G01X1415864D01*
Y908979D01*
G03X1415994Y908931I130J152D01*
G01X1416258D01*
G03X1416388Y908979I0J200D01*
G01X1416389Y908980D01*
G02X1416505Y909072I990J-1129D01*
G03X1416589Y909241I-116J163D01*
G01X1416579Y909574D01*
G03X1416486Y909737I-200J-6D01*
G37*
G36*
G01X1484066Y932946D02*
Y932947D01*
G02X1485500Y934002I1434J-447D01*
G02Y930998I0J-1502D01*
G01X1485498D01*
G02X1484897Y931124I1J1502D01*
G01X1484857Y931142D01*
X1484773Y931141D01*
X1484463Y930999D01*
G03X1484355Y930878I82J-182D01*
G01Y930877D01*
G02X1482921Y929822I-1434J447D01*
G02Y932826I0J1502D01*
G01X1482923D01*
G02X1483524Y932700I-1J-1502D01*
G01X1483564Y932682D01*
X1483648Y932683D01*
X1483958Y932825D01*
G03X1484066Y932946I-82J182D01*
G37*
G36*
G01X1417465Y943159D02*
G03X1418116I326J233D01*
G02X1419337Y943787I1221J-873D01*
G02Y940783I0J-1502D01*
G02X1418116Y941411I0J1501D01*
G03X1417465I-325J-233D01*
G02X1416244Y940783I-1221J873D01*
G02Y943787I0J1502D01*
G02X1417465Y943159I0J-1501D01*
G37*
G36*
G01X1479444Y945551D02*
G02X1478642Y946880I700J1329D01*
G02X1481646I1502J0D01*
G02X1480816Y945537I-1502J0D01*
G03X1480809Y944825I179J-358D01*
G02X1481611Y943496I-700J-1329D01*
G02X1478607I-1502J0D01*
G02X1479437Y944839I1502J0D01*
G03X1479444Y945551I-179J358D01*
G37*
G36*
G01X1399763Y989464D02*
Y989465D01*
G02X1401265Y987963I1502J0D01*
G02X1400835Y988026I0J1502D01*
G03X1400328Y987566I-114J-383D01*
G02X1400356Y987278I-1474J-289D01*
G01Y987277D01*
G02X1398854Y988779I-1502J0D01*
G02X1399284Y988716I0J-1502D01*
G03X1399791Y989176I114J383D01*
G02X1399763Y989464I1474J289D01*
G37*
G36*
G01X1364765Y1003264D02*
G02Y1006268I0J1502D01*
G02X1366170Y1005297I0J-1502D01*
G03X1366287Y1005180I187J70D01*
G01X1366568Y1005075D01*
G03X1366733Y1005086I70J187D01*
G02X1367444Y1005265I711J-1323D01*
G02Y1002261I0J-1502D01*
G02X1366039Y1003232I0J1502D01*
G03X1365922Y1003349I-187J-70D01*
G01X1365641Y1003454D01*
G03X1365476Y1003443I-70J-187D01*
G02X1364765Y1003264I-711J1323D01*
G37*
G36*
G01X1506881Y1011156D02*
G02X1506284Y1012354I905J1199D01*
G02X1509288I1502J0D01*
G02X1508727Y1011183I-1503J0D01*
G01X1508691Y1011154D01*
X1508652Y1011071D01*
X1508657Y1010709D01*
G03X1508736Y1010552I200J2D01*
G02X1509333Y1009354I-905J-1199D01*
G02X1506329I-1502J0D01*
G02X1506890Y1010525I1503J0D01*
G01X1506926Y1010554D01*
X1506965Y1010637D01*
X1506960Y1010999D01*
G03X1506881Y1011156I-200J-2D01*
G37*
G36*
G01X1373144Y1017669D02*
G02X1372557Y1018860I915J1191D01*
G02X1375561I1502J0D01*
G02X1375554Y1018721I-1502J6D01*
G01Y1018719D01*
X1375550Y1018672D01*
X1375585Y1018584D01*
X1375864Y1018338D01*
G03X1376037Y1018292I132J150D01*
G01X1376038D01*
G02X1376359Y1018327I322J-1467D01*
G02Y1015323I0J-1502D01*
G01X1376358D01*
G02X1375884Y1015400I1J1502D01*
G01X1375849Y1015412D01*
X1375776Y1015409D01*
X1375463Y1015274D01*
X1375411Y1015224D01*
X1375395Y1015190D01*
G02X1374034Y1014323I-1361J635D01*
G02X1372532Y1015825I0J1502D01*
G02X1373138Y1017031I1503J0D01*
G01X1373176Y1017059D01*
X1373219Y1017142D01*
X1373222Y1017509D01*
G03X1373144Y1017669I-200J2D01*
G37*
G36*
G01X1506881Y1023756D02*
G02X1506284Y1024954I905J1199D01*
G02X1509288I1502J0D01*
G02X1508727Y1023783I-1503J0D01*
G01X1508691Y1023754D01*
X1508652Y1023671D01*
X1508657Y1023309D01*
G03X1508736Y1023152I200J2D01*
G02X1509333Y1021954I-905J-1199D01*
G02X1506329I-1502J0D01*
G02X1506890Y1023125I1503J0D01*
G01X1506926Y1023154D01*
X1506965Y1023237D01*
X1506960Y1023599D01*
G03X1506881Y1023756I-200J-2D01*
G37*
G36*
G01X1474888Y1031518D02*
G03X1475045Y1031595I-1J200D01*
G02X1476230Y1032174I1185J-923D01*
G02Y1029170I0J-1502D01*
G02X1475045Y1029749I0J1502D01*
G03X1474888Y1029826I-158J-123D01*
G01X1474572D01*
G03X1474415Y1029749I1J-200D01*
G02X1473230Y1029170I-1185J923D01*
G02Y1032174I0J1502D01*
G02X1474415Y1031595I0J-1502D01*
G03X1474572Y1031518I158J123D01*
G01X1474888D01*
G37*
G36*
G01X1386269Y1031164D02*
G03X1386348Y1031283I-116J163D01*
G02X1387813Y1032454I1465J-331D01*
G02Y1029450I0J-1502D01*
G02X1387635Y1029461I3J1502D01*
G01X1387634D01*
G03X1387495Y1029426I-24J-199D01*
G01X1387276Y1029270D01*
G03X1387197Y1029151I116J-163D01*
G02X1385732Y1027980I-1465J331D01*
G02Y1030984I0J1502D01*
G02X1385910Y1030973I-3J-1502D01*
G01X1385911D01*
G03X1386050Y1031008I24J199D01*
G01X1386269Y1031164D01*
G37*
G36*
G01X1328233Y1061828D02*
X1328234Y1061829D01*
G02X1329221Y1062199I987J-1131D01*
G02X1330723Y1060697I0J-1502D01*
G02X1330317Y1059670I-1502J0D01*
G01X1330291Y1059643D01*
X1330263Y1059572D01*
Y1059222D01*
X1330291Y1059151D01*
X1330317Y1059124D01*
G02X1330723Y1058097I-1096J-1027D01*
G02X1329221Y1056595I-1502J0D01*
G02X1328234Y1056965I0J1501D01*
G01X1328233D01*
Y1056966D01*
G03X1328103Y1057014I-130J-152D01*
G01X1327839D01*
G03X1327709Y1056966I0J-200D01*
G01X1327708Y1056965D01*
G02X1325734I-987J1131D01*
G01X1325733D01*
Y1056966D01*
G03X1325603Y1057014I-130J-152D01*
G01X1325339D01*
G03X1325209Y1056966I0J-200D01*
G01X1325208Y1056965D01*
G02X1323234I-987J1131D01*
G01X1323233D01*
Y1056966D01*
G03X1323103Y1057014I-130J-152D01*
G01X1322839D01*
G03X1322709Y1056966I0J-200D01*
G01X1322708Y1056965D01*
G02X1320734I-987J1131D01*
G01X1320733D01*
Y1056966D01*
G03X1320603Y1057014I-130J-152D01*
G01X1320339D01*
G03X1320209Y1056966I0J-200D01*
G01X1320208Y1056965D01*
G02X1319221Y1056595I-987J1131D01*
G02X1317719Y1058097I0J1502D01*
G02X1318125Y1059124I1502J0D01*
G01X1318151Y1059151D01*
X1318179Y1059222D01*
Y1059572D01*
X1318151Y1059643D01*
X1318125Y1059670D01*
G02X1317719Y1060697I1096J1027D01*
G02X1319221Y1062199I1502J0D01*
G02X1320208Y1061829I0J-1501D01*
G01X1320209D01*
Y1061828D01*
G03X1320339Y1061780I130J152D01*
G01X1320603D01*
G03X1320733Y1061828I0J200D01*
G01X1320734Y1061829D01*
G02X1322708I987J-1131D01*
G01X1322709D01*
Y1061828D01*
G03X1322839Y1061780I130J152D01*
G01X1323103D01*
G03X1323233Y1061828I0J200D01*
G01X1323234Y1061829D01*
G02X1325208I987J-1131D01*
G01X1325209D01*
Y1061828D01*
G03X1325339Y1061780I130J152D01*
G01X1325603D01*
G03X1325733Y1061828I0J200D01*
G01X1325734Y1061829D01*
G02X1327708I987J-1131D01*
G01X1327709Y1061828D01*
G03X1327839Y1061780I130J152D01*
G01X1328103D01*
G03X1328233Y1061828I0J200D01*
G37*
G36*
G01X1416363D02*
X1416364Y1061829D01*
G02X1417351Y1062199I987J-1131D01*
G02X1418853Y1060697I0J-1502D01*
G02X1418447Y1059670I-1502J0D01*
G01X1418421Y1059643D01*
X1418393Y1059572D01*
Y1059222D01*
X1418421Y1059151D01*
X1418447Y1059124D01*
G02X1418853Y1058097I-1096J-1027D01*
G02X1417351Y1056595I-1502J0D01*
G02X1416364Y1056965I0J1501D01*
G01X1416363D01*
Y1056966D01*
G03X1416233Y1057014I-130J-152D01*
G01X1415969D01*
G03X1415839Y1056966I0J-200D01*
G01X1415838Y1056965D01*
G02X1413864I-987J1131D01*
G01X1413863D01*
Y1056966D01*
G03X1413733Y1057014I-130J-152D01*
G01X1413469D01*
G03X1413339Y1056966I0J-200D01*
G01X1413338Y1056965D01*
G02X1411364I-987J1131D01*
G01X1411363D01*
Y1056966D01*
G03X1411233Y1057014I-130J-152D01*
G01X1410969D01*
G03X1410839Y1056966I0J-200D01*
G01X1410838Y1056965D01*
G02X1408864I-987J1131D01*
G01X1408863D01*
Y1056966D01*
G03X1408733Y1057014I-130J-152D01*
G01X1408469D01*
G03X1408339Y1056966I0J-200D01*
G01X1408338Y1056965D01*
G02X1407351Y1056595I-987J1131D01*
G02X1405849Y1058097I0J1502D01*
G02X1406255Y1059124I1502J0D01*
G01X1406281Y1059151D01*
X1406309Y1059222D01*
Y1059572D01*
X1406281Y1059643D01*
X1406255Y1059670D01*
G02X1405849Y1060697I1096J1027D01*
G02X1407351Y1062199I1502J0D01*
G02X1408338Y1061829I0J-1501D01*
G01X1408339D01*
Y1061828D01*
G03X1408469Y1061780I130J152D01*
G01X1408733D01*
G03X1408863Y1061828I0J200D01*
G01X1408864Y1061829D01*
G02X1410838I987J-1131D01*
G01X1410839D01*
Y1061828D01*
G03X1410969Y1061780I130J152D01*
G01X1411233D01*
G03X1411363Y1061828I0J200D01*
G01X1411364Y1061829D01*
G02X1413338I987J-1131D01*
G01X1413339D01*
Y1061828D01*
G03X1413469Y1061780I130J152D01*
G01X1413733D01*
G03X1413863Y1061828I0J200D01*
G01X1413864Y1061829D01*
G02X1415838I987J-1131D01*
G01X1415839Y1061828D01*
G03X1415969Y1061780I130J152D01*
G01X1416233D01*
G03X1416363Y1061828I0J200D01*
G37*
G36*
G01X1414689Y1087927D02*
X1414690Y1087928D01*
G02X1415677Y1088298I987J-1131D01*
G02X1417179Y1086796I0J-1502D01*
G02X1416809Y1085809I-1501J0D01*
G01Y1085808D01*
X1416808D01*
G03X1416760Y1085678I152J-130D01*
G01Y1085414D01*
G03X1416808Y1085284I200J0D01*
G01X1416809Y1085283D01*
G02X1417179Y1084296I-1131J-987D01*
G02X1415677Y1082794I-1502J0D01*
G02X1414690Y1083164I0J1501D01*
G01X1414689D01*
Y1083165D01*
G03X1414559Y1083213I-130J-152D01*
G01X1414295D01*
G03X1414165Y1083165I0J-200D01*
G01X1414164Y1083164D01*
G02X1412190I-987J1131D01*
G01X1412189D01*
Y1083165D01*
G03X1412059Y1083213I-130J-152D01*
G01X1411795D01*
G03X1411665Y1083165I0J-200D01*
G01X1411664Y1083164D01*
G02X1409690I-987J1131D01*
G01X1409689D01*
Y1083165D01*
G03X1409559Y1083213I-130J-152D01*
G01X1409295D01*
G03X1409165Y1083165I0J-200D01*
G01X1409164Y1083164D01*
G02X1407190I-987J1131D01*
G01X1407189D01*
Y1083165D01*
G03X1407059Y1083213I-130J-152D01*
G01X1406795D01*
G03X1406665Y1083165I0J-200D01*
G01X1406664Y1083164D01*
G02X1405677Y1082794I-987J1131D01*
G02X1404175Y1084296I0J1502D01*
G02X1404545Y1085283I1501J0D01*
G01Y1085284D01*
X1404546D01*
G03X1404594Y1085414I-152J130D01*
G01Y1085678D01*
G03X1404546Y1085808I-200J0D01*
G01X1404545Y1085809D01*
G02X1404175Y1086796I1131J987D01*
G02X1405677Y1088298I1502J0D01*
G02X1406664Y1087928I0J-1501D01*
G01X1406665D01*
Y1087927D01*
G03X1406795Y1087879I130J152D01*
G01X1407059D01*
G03X1407189Y1087927I0J200D01*
G01X1407190Y1087928D01*
G02X1409164I987J-1131D01*
G01X1409165D01*
Y1087927D01*
G03X1409295Y1087879I130J152D01*
G01X1409559D01*
G03X1409689Y1087927I0J200D01*
G01X1409690Y1087928D01*
G02X1411664I987J-1131D01*
G01X1411665D01*
Y1087927D01*
G03X1411795Y1087879I130J152D01*
G01X1412059D01*
G03X1412189Y1087927I0J200D01*
G01X1412190Y1087928D01*
G02X1414164I987J-1131D01*
G01X1414165Y1087927D01*
G03X1414295Y1087879I130J152D01*
G01X1414559D01*
G03X1414689Y1087927I0J200D01*
G37*
G36*
G01X1391615Y1088176D02*
G02X1391189Y1089224I1076J1048D01*
G02X1394193I1502J0D01*
G02X1393823Y1088237I-1501J0D01*
G01Y1088236D01*
X1393822D01*
G03X1393774Y1088106I152J-130D01*
G01Y1087842D01*
G03X1393822Y1087712I200J0D01*
G01X1393823Y1087711D01*
G02Y1085737I-1131J-987D01*
G01Y1085736D01*
X1393822D01*
G03X1393774Y1085606I152J-130D01*
G01Y1085342D01*
G03X1393822Y1085212I200J0D01*
G01X1393823Y1085211D01*
G02Y1083237I-1131J-987D01*
G01Y1083236D01*
X1393822D01*
G03X1393774Y1083106I152J-130D01*
G01Y1082842D01*
G03X1393822Y1082712I200J0D01*
G01X1393823Y1082711D01*
G02X1394193Y1081724I-1131J-987D01*
G02X1392691Y1080222I-1502J0D01*
G02X1391704Y1080592I0J1501D01*
G01X1391703D01*
Y1080593D01*
G03X1391573Y1080641I-130J-152D01*
G01X1391309D01*
G03X1391179Y1080593I0J-200D01*
G01X1391178Y1080592D01*
G02X1390191Y1080222I-987J1131D01*
G02X1388689Y1081724I0J1502D01*
G02X1389059Y1082711I1501J0D01*
G01Y1082712D01*
X1389060D01*
G03X1389108Y1082842I-152J130D01*
G01Y1083106D01*
G03X1389060Y1083236I-200J0D01*
G01X1389059Y1083237D01*
G02Y1085211I1131J987D01*
G01Y1085212D01*
X1389060D01*
G03X1389108Y1085342I-152J130D01*
G01Y1085606D01*
G03X1389060Y1085736I-200J0D01*
G01X1389059Y1085737D01*
G02X1388689Y1086724I1131J987D01*
G02X1390191Y1088226I1502J0D01*
G02X1391239Y1087800I0J-1502D01*
G03X1391378Y1087743I140J143D01*
G01X1391504D01*
G03X1391643Y1087800I-1J200D01*
G02X1391672Y1087827I1038J-1086D01*
G01Y1088037D01*
G03X1391615Y1088176I-200J-1D01*
G37*
G36*
G01X1387536Y1091857D02*
G02X1386949Y1093048I915J1191D01*
G02X1389953I1502J0D01*
G02X1389423Y1091903I-1502J0D01*
G03X1389352Y1091746I129J-153D01*
G01X1389361Y1091389D01*
X1389402Y1091309D01*
X1389438Y1091281D01*
G02X1390025Y1090090I-915J-1191D01*
G02X1387021I-1502J0D01*
G02X1387551Y1091235I1502J0D01*
G03X1387622Y1091392I-129J153D01*
G01X1387613Y1091749D01*
X1387572Y1091829D01*
X1387536Y1091857D01*
G37*
G36*
G01X1348932Y1093314D02*
X1348941Y1093363D01*
G02X1350418Y1094590I1477J-275D01*
G02X1351920Y1093088I0J-1502D01*
G02X1351435Y1091982I-1504J0D01*
G03X1351370Y1091835I135J-148D01*
G01Y1091541D01*
G03X1351435Y1091394I200J1D01*
G02X1351920Y1090288I-1019J-1106D01*
G02X1350418Y1088786I-1502J0D01*
G02X1349579Y1089042I0J1503D01*
G01X1349578Y1089043D01*
G03X1349402Y1089066I-111J-166D01*
G01X1349056Y1088949D01*
X1348991Y1088883D01*
X1348976Y1088838D01*
G02X1348684Y1088330I-1423J480D01*
G01Y1088328D01*
X1348683D01*
G03X1348635Y1088198I152J-130D01*
G01Y1087934D01*
G03X1348683Y1087804I200J0D01*
G01X1348684Y1087803D01*
G02Y1085829I-1131J-987D01*
G01Y1085828D01*
X1348683D01*
G03X1348635Y1085698I152J-130D01*
G01Y1085434D01*
G03X1348683Y1085304I200J0D01*
G01X1348684Y1085303D01*
G02Y1083329I-1131J-987D01*
G01Y1083328D01*
X1348683D01*
G03X1348635Y1083198I152J-130D01*
G01Y1082934D01*
G03X1348683Y1082804I200J0D01*
G01X1348684Y1082803D01*
G02X1349054Y1081816I-1131J-987D01*
G02X1347552Y1080314I-1502J0D01*
G02X1346565Y1080684I0J1501D01*
G01X1346564D01*
Y1080685D01*
G03X1346434Y1080733I-130J-152D01*
G01X1346170D01*
G03X1346040Y1080685I0J-200D01*
G01X1346039Y1080684D01*
G02X1345052Y1080314I-987J1131D01*
G02X1343550Y1081816I0J1502D01*
G02X1343920Y1082803I1501J0D01*
G01Y1082804D01*
X1343921D01*
G03X1343969Y1082934I-152J130D01*
G01Y1083198D01*
G03X1343921Y1083328I-200J0D01*
G01X1343920Y1083329D01*
G02Y1085303I1131J987D01*
G01Y1085304D01*
X1343921D01*
G03X1343969Y1085434I-152J130D01*
G01Y1085698D01*
G03X1343921Y1085828I-200J0D01*
G01X1343920Y1085829D01*
G02X1343550Y1086816I1131J987D01*
G02X1345052Y1088318I1502J0D01*
G02X1346100Y1087892I0J-1502D01*
G03X1346239Y1087835I140J143D01*
G01X1346365D01*
G03X1346504Y1087892I-1J200D01*
G02X1346533Y1087919I1038J-1086D01*
G01Y1088129D01*
G03X1346476Y1088268I-200J-1D01*
G02X1346050Y1089316I1076J1048D01*
G02X1346420Y1090303I1501J0D01*
G01Y1090304D01*
X1346421D01*
G03X1346469Y1090434I-152J130D01*
G01Y1090698D01*
G03X1346421Y1090828I-200J0D01*
G01X1346420Y1090829D01*
G02X1346050Y1091816I1131J987D01*
G02X1347552Y1093318I1502J0D01*
G01X1347554D01*
G02X1348339Y1093096I-1J-1502D01*
G01X1348381Y1093070D01*
X1348479Y1093063D01*
X1348872Y1093238D01*
X1348932Y1093314D01*
G37*
G36*
G01X1414988Y1091982D02*
G02X1414503Y1093088I1019J1106D01*
G02X1417507I1502J0D01*
G02X1417022Y1091982I-1504J0D01*
G03X1416957Y1091835I135J-148D01*
G01Y1091541D01*
G03X1417022Y1091394I200J1D01*
G02X1417507Y1090288I-1019J-1106D01*
G02X1414503I-1502J0D01*
G02X1414988Y1091394I1504J0D01*
G03X1415053Y1091541I-135J148D01*
G01Y1091835D01*
G03X1414988Y1091982I-200J-1D01*
G37*
G36*
G01X1322098Y1092771D02*
G02X1321519Y1093956I923J1185D01*
G02X1324523I1502J0D01*
G02X1323944Y1092771I-1502J0D01*
G03X1323867Y1092614I123J-158D01*
G01Y1092298D01*
G03X1323944Y1092141I200J1D01*
G02X1324523Y1090956I-923J-1185D01*
G02X1323863Y1089712I-1502J0D01*
G01X1323820Y1089683D01*
X1323773Y1089589D01*
X1323796Y1089142D01*
X1323852Y1089054D01*
X1323899Y1089029D01*
G02X1324225Y1088792I-712J-1322D01*
G01X1324226Y1088791D01*
G03X1324396Y1088739I137J146D01*
G01X1324759Y1088800D01*
X1324834Y1088855D01*
X1324856Y1088897D01*
G02X1325399Y1089482I1333J-692D01*
G01X1325400Y1089483D01*
G03X1325493Y1089634I-106J169D01*
G01X1325527Y1089999D01*
X1325493Y1090086D01*
X1325458Y1090118D01*
G02X1324969Y1091227I1013J1109D01*
G02X1327973I1502J0D01*
G02X1327261Y1089950I-1501J0D01*
G01X1327260Y1089949D01*
G03X1327167Y1089798I106J-169D01*
G01X1327133Y1089433D01*
X1327167Y1089346D01*
X1327202Y1089314D01*
G02X1327374Y1089128I-1013J-1109D01*
G03X1327531Y1089051I158J123D01*
G01X1327847D01*
G03X1328004Y1089128I-1J200D01*
G02X1329189Y1089707I1185J-923D01*
G02X1330691Y1088205I0J-1502D01*
G02X1330112Y1087020I-1502J0D01*
G03X1330035Y1086863I123J-158D01*
G01Y1086547D01*
G03X1330112Y1086390I200J1D01*
G02X1330691Y1085205I-923J-1185D01*
G02X1330235Y1084127I-1502J0D01*
G01X1330206Y1084099D01*
X1330175Y1084026D01*
X1330171Y1083661D01*
X1330201Y1083588D01*
X1330230Y1083559D01*
G02X1330665Y1082502I-1067J-1057D01*
G01Y1082501D01*
G02X1329163Y1080999I-1502J0D01*
G02X1327978Y1081578I0J1502D01*
G03X1327821Y1081655I-158J-123D01*
G01X1327505D01*
G03X1327348Y1081578I1J-200D01*
G02X1324978I-1185J923D01*
G03X1324821Y1081655I-158J-123D01*
G01X1324505D01*
G03X1324348Y1081578I1J-200D01*
G02X1323163Y1080999I-1185J923D01*
G02X1321661Y1082501I0J1502D01*
G02X1322117Y1083579I1502J0D01*
G01X1322146Y1083607D01*
X1322177Y1083680D01*
X1322181Y1084045D01*
X1322151Y1084118D01*
X1322122Y1084147D01*
G02X1321687Y1085204I1067J1057D01*
G01Y1085205D01*
G02X1322057Y1086192I1501J0D01*
G01Y1086193D01*
X1322058D01*
G03X1322106Y1086323I-152J130D01*
G01Y1086587D01*
G03X1322058Y1086717I-200J0D01*
G01X1322057Y1086718D01*
G02X1321687Y1087705I1131J987D01*
G02X1322347Y1088949I1502J0D01*
G01X1322390Y1088978D01*
X1322437Y1089072D01*
X1322414Y1089519D01*
X1322358Y1089607D01*
X1322311Y1089632D01*
G02X1321519Y1090956I711J1324D01*
G02X1322098Y1092141I1502J0D01*
G03X1322175Y1092298I-123J158D01*
G01Y1092614D01*
G03X1322098Y1092771I-200J-1D01*
G37*
G36*
G01X1495235Y1103893D02*
G02X1494638Y1105091I905J1199D01*
G02X1497642I1502J0D01*
G02X1497081Y1103920I-1503J0D01*
G01X1497045Y1103891D01*
X1497006Y1103808D01*
X1497011Y1103446D01*
G03X1497090Y1103289I200J2D01*
G02X1497687Y1102091I-905J-1199D01*
G02X1494683I-1502J0D01*
G02X1495244Y1103262I1503J0D01*
G01X1495280Y1103291D01*
X1495319Y1103374D01*
X1495314Y1103736D01*
G03X1495235Y1103893I-200J-2D01*
G37*
G36*
G01X1435477Y1106372D02*
G02X1435382Y1106897I1407J526D01*
G02X1438386I1502J0D01*
G02X1436984Y1105398I-1502J0D01*
G01X1436937Y1105395D01*
X1436855Y1105347D01*
X1436629Y1104998D01*
X1436619Y1104905D01*
X1436636Y1104860D01*
G02X1436731Y1104335I-1407J-526D01*
G02X1436674Y1103925I-1503J0D01*
G01X1436662Y1103881D01*
X1436677Y1103792D01*
X1436885Y1103500D01*
G03X1437035Y1103416I163J115D01*
G01X1437036D01*
G02X1438451Y1101917I-86J-1499D01*
G02X1435447I-1502J0D01*
G02X1435504Y1102327I1503J0D01*
G01X1435516Y1102371D01*
X1435501Y1102460D01*
X1435293Y1102752D01*
G03X1435143Y1102836I-163J-115D01*
G01X1435142D01*
G02X1434690Y1102933I85J1499D01*
G01X1434648Y1102949D01*
X1434559Y1102943D01*
X1434250Y1102766D01*
G03X1434152Y1102626I99J-174D01*
G01Y1102625D01*
G02X1433733Y1101810I-1481J246D01*
G01X1431319Y1099397D01*
G03X1431260Y1099255I141J-142D01*
G01Y1097813D01*
G02X1430821Y1096753I-1501J1D01*
G01X1428846Y1094778D01*
G02X1427784Y1094338I-1062J1062D01*
G01X1425128D01*
G02X1424066Y1094778I0J1502D01*
G01X1419864Y1098981D01*
G03X1419722Y1099040I-142J-141D01*
G01X1412274D01*
G03X1412132Y1098981I0J-200D01*
G01X1407930Y1094778D01*
G02X1406868Y1094338I-1062J1062D01*
G01X1403727D01*
G02X1402665Y1094778I0J1502D01*
G01X1401454Y1095989D01*
G02X1401014Y1097051I1062J1062D01*
G01Y1100436D01*
G03X1400956Y1100578I-200J1D01*
G01X1400684Y1100849D01*
G03X1400401I-142J-141D01*
G01X1399526Y1099973D01*
G02X1398466Y1099534I-1061J1062D01*
G01X1383744D01*
G03X1383602Y1099475I0J-200D01*
G01X1380119Y1095992D01*
G03X1380060Y1095850I141J-142D01*
G01Y1038534D01*
G02X1377058I-1501J0D01*
G01Y1096557D01*
G02X1377497Y1097617I1501J-1D01*
G01X1381977Y1102097D01*
G02X1383037Y1102536I1061J-1062D01*
G01X1397759D01*
G03X1397901Y1102595I0J200D01*
G01X1398983Y1103677D01*
G03X1399042Y1103819I-141J142D01*
G01Y1105005D01*
G03X1398968Y1105160I-200J0D01*
G01X1398727Y1105356D01*
G03X1398562Y1105396I-125J-156D01*
G01X1398558D01*
G03X1398438Y1105318I42J-196D01*
G01X1398257Y1105068D01*
X1398238Y1104996D01*
X1398242Y1104959D01*
G02X1398251Y1104792I-1493J-164D01*
G02X1395247I-1502J0D01*
G02X1396446Y1106263I1502J0D01*
G01X1396447D01*
G03X1396567Y1106341I-42J196D01*
G01X1396748Y1106591D01*
X1396767Y1106663D01*
X1396763Y1106700D01*
G02X1396754Y1106867I1493J164D01*
G02X1398256Y1108369I1502J0D01*
G02X1399699Y1107285I0J-1502D01*
G01X1399709Y1107248D01*
X1399757Y1107187D01*
X1400065Y1107010D01*
X1400142Y1106999D01*
X1400179Y1107009D01*
G02X1400543Y1107054I365J-1457D01*
G02X1401983Y1105977I0J-1501D01*
G01X1401995Y1105935D01*
X1402050Y1105871D01*
X1402397Y1105706D01*
X1402482Y1105704D01*
X1402521Y1105721D01*
G02X1403001Y1105834I580J-1386D01*
G01X1403048Y1105837D01*
X1403130Y1105885D01*
X1403356Y1106234D01*
X1403366Y1106327D01*
X1403349Y1106372D01*
G02X1403254Y1106897I1407J526D01*
G02X1406258I1502J0D01*
G02X1404856Y1105398I-1502J0D01*
G01X1404809Y1105395D01*
X1404727Y1105347D01*
X1404501Y1104998D01*
X1404491Y1104905D01*
X1404508Y1104860D01*
G02X1404603Y1104335I-1407J-526D01*
G02X1404546Y1103925I-1503J0D01*
G01X1404534Y1103881D01*
X1404549Y1103792D01*
X1404757Y1103500D01*
G03X1404907Y1103416I163J115D01*
G01X1404908D01*
G02X1406323Y1101917I-86J-1499D01*
G02X1404821Y1100415I-1502J0D01*
G01X1404819D01*
G02X1404502Y1100449I1J1502D01*
G01X1404458Y1100458D01*
X1404370Y1100438D01*
X1404093Y1100214D01*
G03X1404018Y1100058I125J-156D01*
G01Y1097756D01*
G03X1404077Y1097614I200J0D01*
G01X1404290Y1097401D01*
G03X1404432Y1097342I142J141D01*
G01X1406163D01*
G03X1406305Y1097401I0J200D01*
G01X1410507Y1101603D01*
G02X1411567Y1102042I1061J-1062D01*
G01X1420429D01*
G02X1421489Y1101603I-1J-1501D01*
G01X1425691Y1097401D01*
G03X1425833Y1097342I142J141D01*
G01X1427079D01*
G03X1427221Y1097401I0J200D01*
G01X1428199Y1098378D01*
G03X1428258Y1098520I-141J142D01*
G01Y1099962D01*
G02X1428697Y1101022I1501J-1D01*
G01X1431111Y1103435D01*
G03X1431170Y1103577I-141J142D01*
G01Y1105005D01*
G03X1431096Y1105160I-200J0D01*
G01X1430855Y1105356D01*
G03X1430690Y1105396I-125J-156D01*
G01X1430686D01*
G03X1430566Y1105318I42J-196D01*
G01X1430385Y1105068D01*
X1430366Y1104996D01*
X1430370Y1104959D01*
G02X1430379Y1104792I-1493J-164D01*
G02X1427375I-1502J0D01*
G02X1428574Y1106263I1502J0D01*
G01X1428575D01*
G03X1428695Y1106341I-42J196D01*
G01X1428876Y1106591D01*
X1428895Y1106663D01*
X1428891Y1106700D01*
G02X1428882Y1106867I1493J164D01*
G02X1430384Y1108369I1502J0D01*
G02X1431827Y1107285I0J-1502D01*
G01X1431837Y1107248D01*
X1431885Y1107187D01*
X1432193Y1107010D01*
X1432270Y1106999D01*
X1432307Y1107009D01*
G02X1432671Y1107054I365J-1457D01*
G02X1434111Y1105977I0J-1501D01*
G01X1434123Y1105935D01*
X1434178Y1105871D01*
X1434525Y1105706D01*
X1434610Y1105704D01*
X1434649Y1105721D01*
G02X1435129Y1105834I580J-1386D01*
G01X1435176Y1105837D01*
X1435258Y1105885D01*
X1435484Y1106234D01*
X1435494Y1106327D01*
X1435477Y1106372D01*
G37*
G36*
G01X1327766Y1114779D02*
X1327767Y1114780D01*
G02X1328754Y1115150I987J-1131D01*
G02Y1112146I0J-1502D01*
G02X1327767Y1112516I0J1501D01*
G01X1327766D01*
Y1112517D01*
G03X1327636Y1112565I-130J-152D01*
G01X1327372D01*
G03X1327242Y1112517I0J-200D01*
G01X1327241Y1112516D01*
G02X1326254Y1112146I-987J1131D01*
G02Y1115150I0J1502D01*
G02X1327241Y1114780I0J-1501D01*
G01X1327242D01*
Y1114779D01*
G03X1327372Y1114731I130J152D01*
G01X1327636D01*
G03X1327766Y1114779I0J200D01*
G37*
G36*
G01X1425481D02*
X1425482Y1114780D01*
G02X1426469Y1115150I987J-1131D01*
G02Y1112146I0J-1502D01*
G02X1425482Y1112516I0J1501D01*
G01X1425481D01*
Y1112517D01*
G03X1425351Y1112565I-130J-152D01*
G01X1425087D01*
G03X1424957Y1112517I0J-200D01*
G01X1424956Y1112516D01*
G02X1423969Y1112146I-987J1131D01*
G02Y1115150I0J1502D01*
G02X1424956Y1114780I0J-1501D01*
G01X1424957D01*
Y1114779D01*
G03X1425087Y1114731I130J152D01*
G01X1425351D01*
G03X1425481Y1114779I0J200D01*
G37*
G36*
G01X1495235Y1116493D02*
G02X1494638Y1117691I905J1199D01*
G02X1497642I1502J0D01*
G02X1497081Y1116520I-1503J0D01*
G01X1497045Y1116491D01*
X1497006Y1116408D01*
X1497011Y1116046D01*
G03X1497090Y1115889I200J2D01*
G02X1497687Y1114691I-905J-1199D01*
G02X1494683I-1502J0D01*
G02X1495244Y1115862I1503J0D01*
G01X1495280Y1115891D01*
X1495319Y1115974D01*
X1495314Y1116336D01*
G03X1495235Y1116493I-200J-2D01*
G37*
G36*
G01X1442233Y1117409D02*
G02X1441863Y1118396I1131J987D01*
G02X1444867I1502J0D01*
G02X1444497Y1117409I-1501J0D01*
G01Y1117408D01*
X1444496D01*
G03X1444448Y1117278I152J-130D01*
G01Y1117014D01*
G03X1444496Y1116884I200J0D01*
G01X1444497Y1116883D01*
G02X1444867Y1115896I-1131J-987D01*
G02X1441863I-1502J0D01*
G02X1442233Y1116883I1501J0D01*
G01Y1116884D01*
X1442234D01*
G03X1442282Y1117014I-152J130D01*
G01Y1117278D01*
G03X1442234Y1117408I-200J0D01*
G01X1442233Y1117409D01*
G37*
G36*
G01X1322347Y1117735D02*
G02X1321903Y1118801I1058J1066D01*
G02X1324907I1502J0D01*
G02X1324463Y1117735I-1502J0D01*
G03X1324404Y1117593I141J-142D01*
G01Y1117309D01*
G03X1324463Y1117167I200J0D01*
G02X1324907Y1116101I-1058J-1066D01*
G02X1323688Y1114626I-1502J0D01*
G01X1323645Y1114618D01*
X1323577Y1114569D01*
X1323379Y1114236D01*
X1323370Y1114151D01*
X1323383Y1114110D01*
G02X1323456Y1113648I-1429J-463D01*
G02X1322459Y1112234I-1501J0D01*
G03X1322333Y1112095I68J-188D01*
G01X1322238Y1111725D01*
X1322261Y1111629D01*
X1322294Y1111592D01*
G02X1322671Y1110597I-1125J-995D01*
G02X1322224Y1109528I-1502J0D01*
G01X1322197Y1109502D01*
X1322166Y1109432D01*
X1322153Y1109081D01*
X1322178Y1109011D01*
X1322203Y1108982D01*
G02X1322571Y1107997I-1134J-985D01*
G02X1321069Y1106495I-1502J0D01*
G02X1319616Y1107615I0J1503D01*
G01X1319607Y1107650D01*
X1319565Y1107710D01*
X1319282Y1107898D01*
X1319211Y1107914D01*
X1319175Y1107909D01*
G02X1318969Y1107895I-205J1488D01*
G02X1318763Y1107909I-1J1502D01*
G01X1318727Y1107914D01*
X1318656Y1107898D01*
X1318373Y1107710D01*
X1318331Y1107650D01*
X1318322Y1107615D01*
G02X1316869Y1106495I-1453J383D01*
G02X1315367Y1107997I0J1502D01*
G02X1315897Y1109142I1502J0D01*
G03X1315968Y1109294I-129J153D01*
G01Y1109600D01*
G03X1315897Y1109752I-200J-1D01*
G02X1315367Y1110897I972J1145D01*
G02X1315897Y1112042I1502J0D01*
G03X1315968Y1112194I-129J153D01*
G01Y1112500D01*
G03X1315897Y1112652I-200J-1D01*
G02X1315367Y1113797I972J1145D01*
G02X1316869Y1115299I1502J0D01*
G02X1318325Y1114167I0J-1502D01*
G01X1318334Y1114130D01*
X1318379Y1114068D01*
X1318674Y1113879D01*
X1318749Y1113865D01*
X1318787Y1113872D01*
G02X1319069Y1113899I284J-1475D01*
G02X1319872Y1113666I0J-1502D01*
G01X1319914Y1113639D01*
X1320011Y1113632D01*
X1320409Y1113804D01*
X1320469Y1113880D01*
X1320479Y1113929D01*
G02X1321671Y1115123I1475J-281D01*
G01X1321714Y1115131D01*
X1321782Y1115180D01*
X1321980Y1115513D01*
X1321989Y1115598D01*
X1321976Y1115639D01*
G02X1321903Y1116101I1429J463D01*
G02X1322347Y1117167I1502J0D01*
G03X1322406Y1117309I-141J142D01*
G01Y1117593D01*
G03X1322347Y1117735I-200J0D01*
G37*
G36*
G01X1420062D02*
G02X1419618Y1118801I1058J1066D01*
G02X1422622I1502J0D01*
G02X1422178Y1117735I-1502J0D01*
G03X1422119Y1117593I141J-142D01*
G01Y1117309D01*
G03X1422178Y1117167I200J0D01*
G02X1422622Y1116101I-1058J-1066D01*
G02X1421403Y1114626I-1502J0D01*
G01X1421360Y1114618D01*
X1421292Y1114569D01*
X1421094Y1114236D01*
X1421085Y1114151D01*
X1421098Y1114110D01*
G02X1421171Y1113648I-1429J-463D01*
G02X1420174Y1112234I-1501J0D01*
G03X1420048Y1112095I68J-188D01*
G01X1419953Y1111725D01*
X1419976Y1111629D01*
X1420009Y1111592D01*
G02X1420386Y1110597I-1125J-995D01*
G02X1419939Y1109528I-1502J0D01*
G01X1419912Y1109502D01*
X1419881Y1109432D01*
X1419868Y1109081D01*
X1419893Y1109011D01*
X1419918Y1108982D01*
G02X1420286Y1107997I-1134J-985D01*
G02X1418784Y1106495I-1502J0D01*
G02X1417331Y1107615I0J1503D01*
G01X1417322Y1107650D01*
X1417280Y1107710D01*
X1416997Y1107898D01*
X1416926Y1107914D01*
X1416890Y1107909D01*
G02X1416684Y1107895I-205J1488D01*
G02X1416478Y1107909I-1J1502D01*
G01X1416442Y1107914D01*
X1416371Y1107898D01*
X1416088Y1107710D01*
X1416046Y1107650D01*
X1416037Y1107615D01*
G02X1414584Y1106495I-1453J383D01*
G02X1413082Y1107997I0J1502D01*
G02X1413612Y1109142I1502J0D01*
G03X1413683Y1109294I-129J153D01*
G01Y1109600D01*
G03X1413612Y1109752I-200J-1D01*
G02X1413082Y1110897I972J1145D01*
G02X1413612Y1112042I1502J0D01*
G03X1413683Y1112194I-129J153D01*
G01Y1112500D01*
G03X1413612Y1112652I-200J-1D01*
G02X1413082Y1113797I972J1145D01*
G02X1414584Y1115299I1502J0D01*
G02X1416040Y1114167I0J-1502D01*
G01X1416049Y1114130D01*
X1416094Y1114068D01*
X1416389Y1113879D01*
X1416464Y1113865D01*
X1416502Y1113872D01*
G02X1416784Y1113899I284J-1475D01*
G02X1417587Y1113666I0J-1502D01*
G01X1417629Y1113639D01*
X1417726Y1113632D01*
X1418124Y1113804D01*
X1418184Y1113880D01*
X1418194Y1113929D01*
G02X1419386Y1115123I1475J-281D01*
G01X1419429Y1115131D01*
X1419497Y1115180D01*
X1419695Y1115513D01*
X1419704Y1115598D01*
X1419691Y1115639D01*
G02X1419618Y1116101I1429J463D01*
G02X1420062Y1117167I1502J0D01*
G03X1420121Y1117309I-141J142D01*
G01Y1117593D01*
G03X1420062Y1117735I-200J0D01*
G37*
G36*
G01X1704313Y1173207D02*
G02X1703400Y1172898I-913J1194D01*
G02Y1175902I0J1502D01*
G02X1704896Y1174538I0J-1502D01*
G03X1705537Y1174258I398J37D01*
G02X1706450Y1174567I913J-1194D01*
G02Y1171563I0J-1502D01*
G02X1704954Y1172927I0J1502D01*
G03X1704313Y1173207I-398J-37D01*
G37*
G36*
G01X1723796Y1158666D02*
G02X1725298Y1160168I0J1502D01*
G02X1725184Y1159594I-1502J0D01*
G03X1725580Y1159043I370J-152D01*
G02X1725680Y1159046I95J-1499D01*
G02X1724178Y1157544I0J-1502D01*
G02X1724292Y1158118I1502J0D01*
G03X1723896Y1158669I-370J152D01*
G02X1723796Y1158666I-95J1499D01*
G37*
G36*
G01X1739075Y1148843D02*
G02X1738415Y1150087I842J1244D01*
G02X1741419I1502J0D01*
G02X1740759Y1148843I-1502J0D01*
G03Y1148181I224J-331D01*
G02X1741419Y1146937I-842J-1244D01*
G02X1738415I-1502J0D01*
G02X1739075Y1148181I1502J0D01*
G03Y1148843I-224J331D01*
G37*
G36*
G01X1783314Y1148953D02*
G03X1783316Y1148955I-140J142D01*
G02X1784302Y1149324I986J-1133D01*
G02Y1146320I0J-1502D01*
G02X1783316Y1146689I0J1502D01*
G03X1783314Y1146691I-142J-140D01*
G03X1783184Y1146739I-130J-152D01*
G01X1782920D01*
G03X1782790Y1146691I0J-200D01*
G01X1782789Y1146690D01*
G02X1781802Y1146320I-987J1131D01*
G02Y1149324I0J1502D01*
G02X1782788Y1148955I0J-1502D01*
G03X1782790Y1148953I142J140D01*
G03X1782920Y1148905I130J152D01*
G01X1783184D01*
G03X1783314Y1148953I0J200D01*
G37*
G36*
G01X1776411D02*
G03X1776413Y1148955I-140J142D01*
G02X1777399Y1149324I986J-1133D01*
G02Y1146320I0J-1502D01*
G02X1776413Y1146689I0J1502D01*
G03X1776411Y1146691I-142J-140D01*
G03X1776281Y1146739I-130J-152D01*
G01X1776017D01*
G03X1775887Y1146691I0J-200D01*
G01X1775886Y1146690D01*
G02X1774899Y1146320I-987J1131D01*
G02Y1149324I0J1502D01*
G02X1775885Y1148955I0J-1502D01*
G03X1775887Y1148953I142J140D01*
G03X1776017Y1148905I130J152D01*
G01X1776281D01*
G03X1776411Y1148953I0J200D01*
G37*
G36*
G01X1815397Y1146043D02*
G03X1815399Y1146045I-140J142D01*
G02X1816385Y1146414I986J-1133D01*
G02Y1143410I0J-1502D01*
G02X1815399Y1143779I0J1502D01*
G03X1815397Y1143781I-142J-140D01*
G03X1815267Y1143829I-130J-152D01*
G01X1815003D01*
G03X1814873Y1143781I0J-200D01*
G01X1814872Y1143780D01*
G02X1813885Y1143410I-987J1131D01*
G02Y1146414I0J1502D01*
G02X1814871Y1146045I0J-1502D01*
G03X1814873Y1146043I142J140D01*
G03X1815003Y1145995I130J152D01*
G01X1815267D01*
G03X1815397Y1146043I0J200D01*
G37*
G36*
G01X1808547D02*
G03X1808549Y1146045I-140J142D01*
G02X1809535Y1146414I986J-1133D01*
G02Y1143410I0J-1502D01*
G02X1808549Y1143779I0J1502D01*
G03X1808547Y1143781I-142J-140D01*
G03X1808417Y1143829I-130J-152D01*
G01X1808153D01*
G03X1808023Y1143781I0J-200D01*
G01X1808022Y1143780D01*
G02X1807035Y1143410I-987J1131D01*
G02Y1146414I0J1502D01*
G02X1808021Y1146045I0J-1502D01*
G03X1808023Y1146043I142J140D01*
G03X1808153Y1145995I130J152D01*
G01X1808417D01*
G03X1808547Y1146043I0J200D01*
G37*
G36*
G01X1662873Y1140649D02*
G02X1664075Y1139447I1202J0D01*
G02X1663853Y1139468I2J1202D01*
G03X1663757Y1139463I-38J-197D01*
G03X1663674Y1139413I59J-191D01*
G01X1663440Y1139179D01*
G03X1663385Y1139001I142J-141D01*
G02X1663406Y1138779I-1181J-224D01*
G02X1661002I-1202J0D01*
G02X1661023Y1139000I1202J-3D01*
G01X1661032Y1139049D01*
X1661003Y1139143D01*
X1660698Y1139448D01*
X1660604Y1139477D01*
X1660555Y1139468D01*
G02X1660334Y1139447I-224J1181D01*
G02X1661536Y1140649I0J1202D01*
G02X1661515Y1140428I-1202J3D01*
G01X1661506Y1140379D01*
X1661535Y1140285D01*
X1661840Y1139980D01*
X1661934Y1139951D01*
X1661983Y1139960D01*
G02X1662204Y1139981I224J-1181D01*
G02X1662426Y1139960I-2J-1202D01*
G03X1662522Y1139965I38J197D01*
G03X1662605Y1140015I-59J191D01*
G01X1662839Y1140249D01*
G03X1662894Y1140427I-142J141D01*
G02X1662873Y1140649I1181J224D01*
G37*
G36*
G01X1783386Y1140953D02*
G03X1783388Y1140955I-140J142D01*
G02X1784374Y1141324I986J-1133D01*
G02Y1138320I0J-1502D01*
G02X1783388Y1138689I0J1502D01*
G03X1783386Y1138691I-142J-140D01*
G03X1783256Y1138739I-130J-152D01*
G01X1782992D01*
G03X1782862Y1138691I0J-200D01*
G01X1782861Y1138690D01*
G02X1781874Y1138320I-987J1131D01*
G02Y1141324I0J1502D01*
G02X1782860Y1140955I0J-1502D01*
G03X1782862Y1140953I142J140D01*
G03X1782992Y1140905I130J152D01*
G01X1783256D01*
G03X1783386Y1140953I0J200D01*
G37*
G36*
G01X1776411D02*
G03X1776413Y1140955I-140J142D01*
G02X1777399Y1141324I986J-1133D01*
G02Y1138320I0J-1502D01*
G02X1776413Y1138689I0J1502D01*
G03X1776411Y1138691I-142J-140D01*
G03X1776281Y1138739I-130J-152D01*
G01X1776017D01*
G03X1775887Y1138691I0J-200D01*
G01X1775886Y1138690D01*
G02X1774899Y1138320I-987J1131D01*
G02Y1141324I0J1502D01*
G02X1775885Y1140955I0J-1502D01*
G03X1775887Y1140953I142J140D01*
G03X1776017Y1140905I130J152D01*
G01X1776281D01*
G03X1776411Y1140953I0J200D01*
G37*
G36*
G01X1815397Y1138043D02*
G03X1815399Y1138045I-140J142D01*
G02X1816385Y1138414I986J-1133D01*
G02Y1135410I0J-1502D01*
G02X1815399Y1135779I0J1502D01*
G03X1815397Y1135781I-142J-140D01*
G03X1815267Y1135829I-130J-152D01*
G01X1815003D01*
G03X1814873Y1135781I0J-200D01*
G01X1814872Y1135780D01*
G02X1813885Y1135410I-987J1131D01*
G02Y1138414I0J1502D01*
G02X1814871Y1138045I0J-1502D01*
G03X1814873Y1138043I142J140D01*
G03X1815003Y1137995I130J152D01*
G01X1815267D01*
G03X1815397Y1138043I0J200D01*
G37*
G36*
G01X1808547D02*
G03X1808549Y1138045I-140J142D01*
G02X1809535Y1138414I986J-1133D01*
G02Y1135410I0J-1502D01*
G02X1808549Y1135779I0J1502D01*
G03X1808547Y1135781I-142J-140D01*
G03X1808417Y1135829I-130J-152D01*
G01X1808153D01*
G03X1808023Y1135781I0J-200D01*
G01X1808022Y1135780D01*
G02X1807035Y1135410I-987J1131D01*
G02Y1138414I0J1502D01*
G02X1808021Y1138045I0J-1502D01*
G03X1808023Y1138043I142J140D01*
G03X1808153Y1137995I130J152D01*
G01X1808417D01*
G03X1808547Y1138043I0J200D01*
G37*
G36*
G01X1698830Y1137586D02*
X1699142D01*
G03X1699298Y1137661I0J200D01*
G02X1700236Y1138111I938J-753D01*
G02Y1135707I0J-1202D01*
G02X1699298Y1136157I0J1203D01*
G03X1699142Y1136232I-156J-125D01*
G01X1698830D01*
G03X1698674Y1136157I0J-200D01*
G02X1697736Y1135707I-938J753D01*
G02X1697515Y1135728I3J1202D01*
G01X1697466Y1135737D01*
X1697372Y1135708D01*
X1697067Y1135403D01*
X1697038Y1135309D01*
X1697047Y1135260D01*
G02X1697068Y1135039I-1181J-224D01*
G02X1694664I-1202J0D01*
G02X1694685Y1135260I1202J-3D01*
G01X1694694Y1135309D01*
X1694665Y1135403D01*
X1694360Y1135708D01*
X1694266Y1135737D01*
X1694217Y1135728D01*
G02X1693996Y1135707I-224J1181D01*
G02X1693775Y1135728I3J1202D01*
G01X1693726Y1135737D01*
X1693632Y1135708D01*
X1693327Y1135403D01*
X1693298Y1135309D01*
X1693307Y1135260D01*
G02X1693328Y1135039I-1181J-224D01*
G02X1690924I-1202J0D01*
G02X1690945Y1135260I1202J-3D01*
G01X1690954Y1135309D01*
X1690925Y1135403D01*
X1690620Y1135708D01*
X1690526Y1135737D01*
X1690477Y1135728D01*
G02X1690256Y1135707I-224J1181D01*
G01X1690255D01*
G02X1690101Y1135717I1J1202D01*
G01X1690100D01*
G03X1689931Y1135657I-25J-198D01*
G01X1689674Y1135391D01*
X1689646Y1135301D01*
X1689654Y1135254D01*
G02X1689672Y1135040I-1269J-214D01*
G01Y1135039D01*
G02X1687098I-1287J0D01*
G01Y1135040D01*
G02X1687116Y1135252I1287J-3D01*
G01Y1135254D01*
X1687123Y1135301D01*
X1687110Y1135345D01*
G03X1687062Y1135426I-191J-59D01*
G01X1686806Y1135692D01*
X1686717Y1135723D01*
X1686670Y1135717D01*
G02X1686515Y1135707I-155J1192D01*
G02X1686360Y1135717I0J1202D01*
G01X1686313Y1135723D01*
X1686224Y1135692D01*
X1685968Y1135426D01*
G03X1685920Y1135345I143J-140D01*
G01X1685907Y1135301D01*
X1685914Y1135254D01*
Y1135252D01*
G02X1685932Y1135040I-1269J-215D01*
G01Y1135039D01*
G02X1683358I-1287J0D01*
G01Y1135040D01*
G02X1683376Y1135252I1287J-3D01*
G01Y1135254D01*
X1683383Y1135301D01*
X1683370Y1135345D01*
G03X1683322Y1135426I-191J-59D01*
G01X1683066Y1135692D01*
X1682977Y1135723D01*
X1682930Y1135717D01*
G02X1682776Y1135707I-155J1192D01*
G01X1682775D01*
G02X1682554Y1135728I3J1202D01*
G01X1682505Y1135737D01*
X1682411Y1135708D01*
X1682106Y1135403D01*
X1682077Y1135309D01*
X1682086Y1135260D01*
G02X1682107Y1135039I-1181J-224D01*
G02X1680905Y1136241I-1202J0D01*
G02X1681126Y1136220I-3J-1202D01*
G01X1681175Y1136211D01*
X1681269Y1136240D01*
X1681574Y1136545D01*
X1681603Y1136639D01*
X1681594Y1136688D01*
G02X1681573Y1136909I1181J224D01*
G02X1683977I1202J0D01*
G01Y1136908D01*
G02X1683967Y1136754I-1202J1D01*
G01X1683961Y1136707D01*
X1683992Y1136618D01*
X1684258Y1136362D01*
G03X1684339Y1136314I140J143D01*
G01X1684383Y1136301D01*
X1684430Y1136308D01*
X1684432D01*
G02X1684644Y1136326I215J-1269D01*
G01X1684646D01*
G02X1684858Y1136308I-3J-1287D01*
G01X1684860D01*
X1684907Y1136301D01*
X1684951Y1136314D01*
G03X1685032Y1136362I-59J191D01*
G01X1685298Y1136618D01*
X1685329Y1136707D01*
X1685323Y1136754D01*
G02X1685313Y1136908I1192J155D01*
G01Y1136909D01*
G02X1687717I1202J0D01*
G01Y1136908D01*
G02X1687707Y1136754I-1202J1D01*
G01X1687701Y1136707D01*
X1687732Y1136618D01*
X1687998Y1136362D01*
G03X1688079Y1136314I140J143D01*
G01X1688123Y1136301D01*
X1688170Y1136308D01*
X1688172D01*
G02X1688384Y1136326I215J-1269D01*
G01X1688386D01*
G02X1688600Y1136308I0J-1287D01*
G01X1688601D01*
G03X1688772Y1136361I33J197D01*
G01X1689004Y1136584D01*
G03X1689066Y1136727I-138J145D01*
G01Y1136741D01*
X1689064Y1136754D01*
G02X1689054Y1136908I1192J155D01*
G01Y1136909D01*
G02X1691458I1202J0D01*
G02X1691437Y1136688I-1202J3D01*
G01X1691428Y1136639D01*
X1691457Y1136545D01*
X1691762Y1136240D01*
X1691856Y1136211D01*
X1691905Y1136220D01*
G02X1692126Y1136241I224J-1181D01*
G02X1692347Y1136220I-3J-1202D01*
G01X1692396Y1136211D01*
X1692490Y1136240D01*
X1692795Y1136545D01*
X1692824Y1136639D01*
X1692815Y1136688D01*
G02X1692794Y1136909I1181J224D01*
G02X1695198I1202J0D01*
G02X1695177Y1136688I-1202J3D01*
G01X1695168Y1136639D01*
X1695197Y1136545D01*
X1695502Y1136240D01*
X1695596Y1136211D01*
X1695645Y1136220D01*
G02X1695866Y1136241I224J-1181D01*
G02X1696087Y1136220I-3J-1202D01*
G01X1696136Y1136211D01*
X1696230Y1136240D01*
X1696535Y1136545D01*
X1696564Y1136639D01*
X1696555Y1136688D01*
G02X1696534Y1136909I1181J224D01*
G02X1697736Y1138111I1202J0D01*
G02X1698674Y1137661I0J-1203D01*
G03X1698830Y1137586I156J125D01*
G37*
G36*
G01X1670353Y1136909D02*
G02X1672757I1202J0D01*
G02X1672736Y1136688I-1202J3D01*
G01X1672727Y1136639D01*
X1672756Y1136545D01*
X1673061Y1136240D01*
X1673155Y1136211D01*
X1673204Y1136220D01*
G02X1673425Y1136241I224J-1181D01*
G02X1672223Y1135039I0J-1202D01*
G02X1672244Y1135260I1202J-3D01*
G01X1672253Y1135309D01*
X1672224Y1135403D01*
X1671919Y1135708D01*
X1671825Y1135737D01*
X1671776Y1135728D01*
G02X1671555Y1135707I-224J1181D01*
G02X1671334Y1135728I3J1202D01*
G01X1671285Y1135737D01*
X1671191Y1135708D01*
X1670886Y1135403D01*
X1670857Y1135309D01*
X1670866Y1135260D01*
G02X1670887Y1135039I-1181J-224D01*
G02X1669685Y1136241I-1202J0D01*
G02X1669906Y1136220I-3J-1202D01*
G01X1669955Y1136211D01*
X1670049Y1136240D01*
X1670354Y1136545D01*
X1670383Y1136639D01*
X1670374Y1136688D01*
G02X1670353Y1136909I1181J224D01*
G37*
G36*
G01X1731379Y1134726D02*
Y1134729D01*
G02X1732881Y1133227I1502J0D01*
G01X1732880D01*
G02X1732587Y1133256I1J1502D01*
G03X1732402Y1133196I-39J-196D01*
G01X1732170Y1132948D01*
G03X1732124Y1132759I147J-136D01*
G01Y1132758D01*
G02X1732177Y1132364I-1449J-396D01*
G01Y1132361D01*
G02X1729173I-1502J0D01*
G01Y1132363D01*
G02X1729220Y1132735I1502J-1D01*
G01Y1132736D01*
G03X1729190Y1132901I-194J50D01*
G01X1728989Y1133185D01*
X1728914Y1133229D01*
X1728870Y1133233D01*
G02X1728842Y1133237I198J1488D01*
G03X1728742Y1133225I-27J-199D01*
G01Y1133224D01*
G03X1728662Y1133167I72J-186D01*
G01X1728415Y1132875D01*
X1728394Y1132779D01*
X1728408Y1132730D01*
G02X1728465Y1132321I-1445J-410D01*
G01Y1132319D01*
G02X1725461I-1502J0D01*
G02X1725498Y1132648I1502J-2D01*
G01X1725508Y1132694D01*
X1725486Y1132785D01*
X1725220Y1133101D01*
X1725134Y1133138D01*
X1725087Y1133136D01*
G02X1725010Y1133134I-77J1500D01*
G01X1725008D01*
G02X1726510Y1134636I0J1502D01*
G02X1726473Y1134307I-1502J2D01*
G01X1726463Y1134261D01*
X1726485Y1134170D01*
X1726751Y1133854D01*
X1726837Y1133817D01*
X1726884Y1133819D01*
G02X1726962Y1133821I77J-1500D01*
G01X1726963D01*
G02X1727131Y1133811I-5J-1502D01*
G01X1727133D01*
X1727184Y1133806D01*
X1727229Y1133824D01*
G03X1727309Y1133881I-72J186D01*
G01X1727556Y1134173D01*
X1727577Y1134269D01*
X1727563Y1134318D01*
G02X1727506Y1134727I1445J410D01*
G01Y1134729D01*
G02X1730510I1502J0D01*
G01Y1134727D01*
G02X1730463Y1134355I-1502J1D01*
G01Y1134354D01*
G03X1730493Y1134189I194J-50D01*
G01X1730693Y1133905D01*
X1730769Y1133861D01*
X1730813Y1133857D01*
G02X1730968Y1133834I-143J-1495D01*
G01X1731020Y1133824D01*
X1731118Y1133855D01*
X1731386Y1134142D01*
G03X1731432Y1134331I-147J136D01*
G01Y1134332D01*
G02X1731379Y1134726I1449J396D01*
G37*
G36*
G01X1718961Y1135417D02*
G03X1719673I356J183D01*
G02X1721008Y1136231I1335J-688D01*
G02Y1133227I0J-1502D01*
G02X1719673Y1134041I0J1502D01*
G03X1718961I-356J-183D01*
G02X1717626Y1133227I-1335J688D01*
G02Y1136231I0J1502D01*
G02X1718961Y1135417I0J-1502D01*
G37*
G36*
G01X1805700Y1134355D02*
X1806064D01*
X1806138Y1134386D01*
X1806166Y1134414D01*
G02X1807232Y1134858I1066J-1058D01*
G02Y1131854I0J-1502D01*
G02X1806166Y1132298I0J1502D01*
G01X1806138Y1132326D01*
X1806064Y1132357D01*
X1805700D01*
X1805626Y1132326D01*
X1805598Y1132298D01*
G02X1804532Y1131854I-1066J1058D01*
G02Y1134858I0J1502D01*
G02X1805598Y1134414I0J-1502D01*
G01X1805626Y1134386D01*
X1805700Y1134355D01*
G37*
G36*
G01X1791689Y1131821D02*
X1792053D01*
X1792127Y1131852D01*
X1792155Y1131880D01*
G02X1793221Y1132324I1066J-1058D01*
G02Y1129320I0J-1502D01*
G02X1792155Y1129764I0J1502D01*
G01X1792127Y1129792D01*
X1792053Y1129823D01*
X1791689D01*
X1791615Y1129792D01*
X1791587Y1129764D01*
G02X1790521Y1129320I-1066J1058D01*
G02X1789494Y1129726I0J1502D01*
G01X1789493Y1129727D01*
G03X1789357Y1129780I-136J-147D01*
G01X1789085D01*
G03X1788949Y1129727I0J-200D01*
G01X1788948Y1129726D01*
G02X1786894I-1027J1096D01*
G01X1786893Y1129727D01*
G03X1786757Y1129780I-136J-147D01*
G01X1786485D01*
G03X1786349Y1129727I0J-200D01*
G01X1786348Y1129726D01*
G02X1785321Y1129320I-1027J1096D01*
G02Y1132324I0J1502D01*
G02X1786348Y1131918I0J-1502D01*
G01X1786349Y1131917D01*
G03X1786485Y1131864I136J147D01*
G01X1786757D01*
G03X1786893Y1131917I0J200D01*
G01X1786894Y1131918D01*
G02X1788948I1027J-1096D01*
G01X1788949Y1131917D01*
G03X1789085Y1131864I136J147D01*
G01X1789357D01*
G03X1789493Y1131917I0J200D01*
G01X1789494Y1131918D01*
G02X1790521Y1132324I1027J-1096D01*
G02X1791587Y1131880I0J-1502D01*
G01X1791615Y1131852D01*
X1791689Y1131821D01*
G37*
G36*
G01X1773367D02*
X1773731D01*
X1773805Y1131852D01*
X1773833Y1131880D01*
G02X1774899Y1132324I1066J-1058D01*
G02Y1129320I0J-1502D01*
G02X1773833Y1129764I0J1502D01*
G01X1773805Y1129792D01*
X1773731Y1129823D01*
X1773367D01*
X1773293Y1129792D01*
X1773265Y1129764D01*
G02X1772199Y1129320I-1066J1058D01*
G02X1771172Y1129726I0J1502D01*
G01X1771171Y1129727D01*
G03X1771035Y1129780I-136J-147D01*
G01X1770763D01*
G03X1770627Y1129727I0J-200D01*
G01X1770626Y1129726D01*
G02X1768572I-1027J1096D01*
G01X1768571Y1129727D01*
G03X1768435Y1129780I-136J-147D01*
G01X1768163D01*
G03X1768027Y1129727I0J-200D01*
G01X1768026Y1129726D01*
G02X1766999Y1129320I-1027J1096D01*
G02Y1132324I0J1502D01*
G02X1768026Y1131918I0J-1502D01*
G01X1768027Y1131917D01*
G03X1768163Y1131864I136J147D01*
G01X1768435D01*
G03X1768571Y1131917I0J200D01*
G01X1768572Y1131918D01*
G02X1770626I1027J-1096D01*
G01X1770627Y1131917D01*
G03X1770763Y1131864I136J147D01*
G01X1771035D01*
G03X1771171Y1131917I0J200D01*
G01X1771172Y1131918D01*
G02X1772199Y1132324I1027J-1096D01*
G02X1773265Y1131880I0J-1502D01*
G01X1773293Y1131852D01*
X1773367Y1131821D01*
G37*
G36*
G01X1805070Y1125327D02*
X1805434D01*
X1805508Y1125358D01*
X1805536Y1125386D01*
G02X1806602Y1125830I1066J-1058D01*
G02Y1122826I0J-1502D01*
G02X1805536Y1123270I0J1502D01*
G01X1805508Y1123298D01*
X1805434Y1123329D01*
X1805070D01*
X1804996Y1123298D01*
X1804968Y1123270D01*
G02X1803902Y1122826I-1066J1058D01*
G02X1802875Y1123232I0J1502D01*
G01X1802874Y1123233D01*
G03X1802738Y1123286I-136J-147D01*
G01X1802466D01*
G03X1802330Y1123233I0J-200D01*
G01X1802329Y1123232D01*
G02X1800275I-1027J1096D01*
G01X1800274Y1123233D01*
G03X1800138Y1123286I-136J-147D01*
G01X1799866D01*
G03X1799730Y1123233I0J-200D01*
G01X1799729Y1123232D01*
G02X1798702Y1122826I-1027J1096D01*
G02Y1125830I0J1502D01*
G02X1799729Y1125424I0J-1502D01*
G01X1799730Y1125423D01*
G03X1799866Y1125370I136J147D01*
G01X1800138D01*
G03X1800274Y1125423I0J200D01*
G01X1800275Y1125424D01*
G02X1802329I1027J-1096D01*
G01X1802330Y1125423D01*
G03X1802466Y1125370I136J147D01*
G01X1802738D01*
G03X1802874Y1125423I0J200D01*
G01X1802875Y1125424D01*
G02X1803902Y1125830I1027J-1096D01*
G02X1804968Y1125386I0J-1502D01*
G01X1804996Y1125358D01*
X1805070Y1125327D01*
G37*
G36*
G01X1821496Y1125288D02*
X1821860D01*
X1821934Y1125319D01*
X1821962Y1125347D01*
G02X1823028Y1125791I1066J-1058D01*
G02Y1122787I0J-1502D01*
G02X1821962Y1123231I0J1502D01*
G01X1821934Y1123259D01*
X1821860Y1123290D01*
X1821496D01*
X1821422Y1123259D01*
X1821394Y1123231D01*
G02X1820328Y1122787I-1066J1058D01*
G02X1819301Y1123193I0J1502D01*
G01X1819300Y1123194D01*
G03X1819164Y1123247I-136J-147D01*
G01X1818892D01*
G03X1818756Y1123194I0J-200D01*
G01X1818755Y1123193D01*
G02X1816701I-1027J1096D01*
G01X1816700Y1123194D01*
G03X1816564Y1123247I-136J-147D01*
G01X1816292D01*
G03X1816156Y1123194I0J-200D01*
G01X1816155Y1123193D01*
G02X1815128Y1122787I-1027J1096D01*
G02Y1125791I0J1502D01*
G02X1816155Y1125385I0J-1502D01*
G01X1816156Y1125384D01*
G03X1816292Y1125331I136J147D01*
G01X1816564D01*
G03X1816700Y1125384I0J200D01*
G01X1816701Y1125385D01*
G02X1818755I1027J-1096D01*
G01X1818756Y1125384D01*
G03X1818892Y1125331I136J147D01*
G01X1819164D01*
G03X1819300Y1125384I0J200D01*
G01X1819301Y1125385D01*
G02X1820328Y1125791I1027J-1096D01*
G02X1821394Y1125347I0J-1502D01*
G01X1821422Y1125319D01*
X1821496Y1125288D01*
G37*
G36*
G01X1791689Y1122121D02*
X1792053D01*
X1792127Y1122152D01*
X1792155Y1122180D01*
G02X1793221Y1122624I1066J-1058D01*
G02Y1119620I0J-1502D01*
G02X1792155Y1120064I0J1502D01*
G01X1792127Y1120092D01*
X1792053Y1120123D01*
X1791689D01*
X1791615Y1120092D01*
X1791587Y1120064D01*
G02X1790521Y1119620I-1066J1058D01*
G02X1789494Y1120026I0J1502D01*
G01X1789493Y1120027D01*
G03X1789357Y1120080I-136J-147D01*
G01X1789085D01*
G03X1788949Y1120027I0J-200D01*
G01X1788948Y1120026D01*
G02X1786894I-1027J1096D01*
G01X1786893Y1120027D01*
G03X1786757Y1120080I-136J-147D01*
G01X1786485D01*
G03X1786349Y1120027I0J-200D01*
G01X1786348Y1120026D01*
G02X1785321Y1119620I-1027J1096D01*
G02Y1122624I0J1502D01*
G02X1786348Y1122218I0J-1502D01*
G01X1786349Y1122217D01*
G03X1786485Y1122164I136J147D01*
G01X1786757D01*
G03X1786893Y1122217I0J200D01*
G01X1786894Y1122218D01*
G02X1788948I1027J-1096D01*
G01X1788949Y1122217D01*
G03X1789085Y1122164I136J147D01*
G01X1789357D01*
G03X1789493Y1122217I0J200D01*
G01X1789494Y1122218D01*
G02X1790521Y1122624I1027J-1096D01*
G02X1791587Y1122180I0J-1502D01*
G01X1791615Y1122152D01*
X1791689Y1122121D01*
G37*
G36*
G01X1773267D02*
X1773631D01*
X1773705Y1122152D01*
X1773733Y1122180D01*
G02X1774799Y1122624I1066J-1058D01*
G02Y1119620I0J-1502D01*
G02X1773733Y1120064I0J1502D01*
G01X1773705Y1120092D01*
X1773631Y1120123D01*
X1773267D01*
X1773193Y1120092D01*
X1773165Y1120064D01*
G02X1772099Y1119620I-1066J1058D01*
G02X1771072Y1120026I0J1502D01*
G01X1771071Y1120027D01*
G03X1770935Y1120080I-136J-147D01*
G01X1770663D01*
G03X1770527Y1120027I0J-200D01*
G01X1770526Y1120026D01*
G02X1768472I-1027J1096D01*
G01X1768471Y1120027D01*
G03X1768335Y1120080I-136J-147D01*
G01X1768063D01*
G03X1767927Y1120027I0J-200D01*
G01X1767926Y1120026D01*
G02X1766899Y1119620I-1027J1096D01*
G02Y1122624I0J1502D01*
G02X1767926Y1122218I0J-1502D01*
G01X1767927Y1122217D01*
G03X1768063Y1122164I136J147D01*
G01X1768335D01*
G03X1768471Y1122217I0J200D01*
G01X1768472Y1122218D01*
G02X1770526I1027J-1096D01*
G01X1770527Y1122217D01*
G03X1770663Y1122164I136J147D01*
G01X1770935D01*
G03X1771071Y1122217I0J200D01*
G01X1771072Y1122218D01*
G02X1772099Y1122624I1027J-1096D01*
G02X1773165Y1122180I0J-1502D01*
G01X1773193Y1122152D01*
X1773267Y1122121D01*
G37*
G36*
G01X1741722Y1119053D02*
Y1119055D01*
G02X1744726I1502J0D01*
G02X1744532Y1118317I-1501J0D01*
G01X1744531Y1118316D01*
G03X1744525Y1118134I175J-97D01*
G01X1744662Y1117839D01*
G03X1744807Y1117727I181J85D01*
G02X1746031Y1116251I-278J-1476D01*
G02X1744529Y1114749I-1502J0D01*
G02X1743543Y1115118I0J1502D01*
G03X1743541Y1115120I-142J-140D01*
G03X1743411Y1115168I-130J-152D01*
G01X1743147D01*
G03X1743017Y1115120I0J-200D01*
G01X1743016Y1115119D01*
G02X1742029Y1114749I-987J1131D01*
G02X1740527Y1116251I0J1502D01*
G02X1741673Y1117710I1502J0D01*
G01X1741674D01*
X1741676Y1117711D01*
G03X1741811Y1117826I-49J194D01*
G01X1741955Y1118166D01*
X1741949Y1118259D01*
X1741925Y1118300D01*
G02X1741722Y1119053I1299J754D01*
G37*
G36*
G01X1821396Y1115588D02*
X1821760D01*
X1821834Y1115619D01*
X1821862Y1115647D01*
G02X1822928Y1116091I1066J-1058D01*
G02Y1113087I0J-1502D01*
G02X1821862Y1113531I0J1502D01*
G01X1821834Y1113559D01*
X1821760Y1113590D01*
X1821396D01*
X1821322Y1113559D01*
X1821294Y1113531D01*
G02X1820228Y1113087I-1066J1058D01*
G02X1819201Y1113493I0J1502D01*
G01X1819200Y1113494D01*
G03X1819064Y1113547I-136J-147D01*
G01X1818792D01*
G03X1818656Y1113494I0J-200D01*
G01X1818655Y1113493D01*
G02X1816601I-1027J1096D01*
G01X1816600Y1113494D01*
G03X1816464Y1113547I-136J-147D01*
G01X1816192D01*
G03X1816056Y1113494I0J-200D01*
G01X1816055Y1113493D01*
G02X1815028Y1113087I-1027J1096D01*
G02Y1116091I0J1502D01*
G02X1816055Y1115685I0J-1502D01*
G01X1816056Y1115684D01*
G03X1816192Y1115631I136J147D01*
G01X1816464D01*
G03X1816600Y1115684I0J200D01*
G01X1816601Y1115685D01*
G02X1818655I1027J-1096D01*
G01X1818656Y1115684D01*
G03X1818792Y1115631I136J147D01*
G01X1819064D01*
G03X1819200Y1115684I0J200D01*
G01X1819201Y1115685D01*
G02X1820228Y1116091I1027J-1096D01*
G02X1821294Y1115647I0J-1502D01*
G01X1821322Y1115619D01*
X1821396Y1115588D01*
G37*
G36*
G01X1804674D02*
X1805038D01*
X1805112Y1115619D01*
X1805140Y1115647D01*
G02X1806206Y1116091I1066J-1058D01*
G02Y1113087I0J-1502D01*
G02X1805140Y1113531I0J1502D01*
G01X1805112Y1113559D01*
X1805038Y1113590D01*
X1804674D01*
X1804600Y1113559D01*
X1804572Y1113531D01*
G02X1803506Y1113087I-1066J1058D01*
G02X1802479Y1113493I0J1502D01*
G01X1802478Y1113494D01*
G03X1802342Y1113547I-136J-147D01*
G01X1802070D01*
G03X1801934Y1113494I0J-200D01*
G01X1801933Y1113493D01*
G02X1799879I-1027J1096D01*
G01X1799878Y1113494D01*
G03X1799742Y1113547I-136J-147D01*
G01X1799470D01*
G03X1799334Y1113494I0J-200D01*
G01X1799333Y1113493D01*
G02X1798306Y1113087I-1027J1096D01*
G02Y1116091I0J1502D01*
G02X1799333Y1115685I0J-1502D01*
G01X1799334Y1115684D01*
G03X1799470Y1115631I136J147D01*
G01X1799742D01*
G03X1799878Y1115684I0J200D01*
G01X1799879Y1115685D01*
G02X1801933I1027J-1096D01*
G01X1801934Y1115684D01*
G03X1802070Y1115631I136J147D01*
G01X1802342D01*
G03X1802478Y1115684I0J200D01*
G01X1802479Y1115685D01*
G02X1803506Y1116091I1027J-1096D01*
G02X1804572Y1115647I0J-1502D01*
G01X1804600Y1115619D01*
X1804674Y1115588D01*
G37*
G36*
G01X1588069Y1114468D02*
G02X1589271Y1113266I1202J0D01*
G02X1589050Y1113287I3J1202D01*
G01X1589001Y1113296D01*
X1588907Y1113267D01*
X1588602Y1112962D01*
X1588573Y1112868D01*
X1588582Y1112819D01*
G02X1588603Y1112598I-1181J-224D01*
G02X1586199I-1202J0D01*
G02X1586220Y1112819I1202J-3D01*
G01X1586229Y1112868D01*
X1586200Y1112962D01*
X1585895Y1113267D01*
X1585801Y1113296D01*
X1585752Y1113287D01*
G02X1585531Y1113266I-224J1181D01*
G02X1586733Y1114468I0J1202D01*
G02X1586712Y1114247I-1202J3D01*
G01X1586703Y1114198D01*
X1586732Y1114104D01*
X1587037Y1113799D01*
X1587131Y1113770D01*
X1587180Y1113779D01*
G02X1587401Y1113800I224J-1181D01*
G02X1587622Y1113779I-3J-1202D01*
G01X1587671Y1113770D01*
X1587765Y1113799D01*
X1588070Y1114104D01*
X1588099Y1114198D01*
X1588090Y1114247D01*
G02X1588069Y1114468I1181J224D01*
G37*
G36*
G01X1782138Y1112133D02*
X1782139Y1112134D01*
G02X1783166Y1112540I1027J-1096D01*
G02X1784668Y1111038I0J-1502D01*
G01Y1111037D01*
G02X1784290Y1110041I-1502J0D01*
G01X1784264Y1110011D01*
X1784238Y1109940D01*
X1784251Y1109586D01*
X1784282Y1109516D01*
X1784310Y1109489D01*
G02X1784764Y1108413I-1048J-1076D01*
G02X1783262Y1106911I-1502J0D01*
G02X1782235Y1107317I0J1502D01*
G01X1782234Y1107318D01*
G03X1782098Y1107371I-136J-147D01*
G01X1781826D01*
G03X1781690Y1107318I0J-200D01*
G01X1781689Y1107317D01*
G02X1779635I-1027J1096D01*
G01X1779634Y1107318D01*
G03X1779498Y1107371I-136J-147D01*
G01X1779226D01*
G03X1779090Y1107318I0J-200D01*
G01X1779089Y1107317D01*
G02X1777035I-1027J1096D01*
G01X1777034Y1107318D01*
G03X1776898Y1107371I-136J-147D01*
G01X1776626D01*
G03X1776490Y1107318I0J-200D01*
G01X1776489Y1107317D01*
G02X1775462Y1106911I-1027J1096D01*
G02X1773960Y1108413I0J1502D01*
G01Y1108414D01*
G02X1774338Y1109410I1502J0D01*
G01X1774364Y1109440D01*
X1774390Y1109511D01*
X1774377Y1109865D01*
X1774346Y1109935D01*
X1774318Y1109962D01*
G02X1773864Y1111038I1048J1076D01*
G02X1775366Y1112540I1502J0D01*
G02X1776393Y1112134I0J-1502D01*
G01X1776394Y1112133D01*
G03X1776530Y1112080I136J147D01*
G01X1776802D01*
G03X1776938Y1112133I0J200D01*
G01X1776939Y1112134D01*
G02X1778993I1027J-1096D01*
G01X1778994Y1112133D01*
G03X1779130Y1112080I136J147D01*
G01X1779402D01*
G03X1779538Y1112133I0J200D01*
G01X1779539Y1112134D01*
G02X1781593I1027J-1096D01*
G01X1781594Y1112133D01*
G03X1781730Y1112080I136J147D01*
G01X1782002D01*
G03X1782138Y1112133I0J200D01*
G37*
G36*
G01X1824028Y1104803D02*
X1823980Y1104830D01*
G02X1823204Y1106145I726J1315D01*
G02X1826208I1502J0D01*
G02X1825453Y1104842I-1502J0D01*
G03X1825352Y1104667I99J-174D01*
G01X1825356Y1104264D01*
X1825411Y1104172D01*
X1825459Y1104145D01*
G02X1826235Y1102830I-726J-1315D01*
G02X1825803Y1101776I-1502J0D01*
G01X1825802Y1101775D01*
X1825800Y1101773D01*
G03X1825744Y1101635I144J-139D01*
G01X1825741Y1101357D01*
G03X1825795Y1101219I200J-1D01*
G01X1825796Y1101218D01*
X1825797Y1101217D01*
G02X1826208Y1100185I-1090J-1032D01*
G01Y1100182D01*
G02X1826072Y1099559I-1502J2D01*
G01X1826054Y1099520D01*
X1826053Y1099436D01*
X1826188Y1099123D01*
G03X1826307Y1099013I184J79D01*
G01X1826308D01*
G02X1827326Y1097746I-476J-1425D01*
G01X1827331Y1097701D01*
X1827377Y1097625D01*
X1827671Y1097431D01*
G03X1827839Y1097406I111J166D01*
G02X1828272Y1097470I434J-1438D01*
G02Y1094466I0J-1502D01*
G02X1826778Y1095811I0J1502D01*
G01X1826773Y1095856D01*
X1826727Y1095932D01*
X1826433Y1096126D01*
G03X1826265Y1096151I-111J-166D01*
G02X1825832Y1096087I-434J1438D01*
G02X1824330Y1097589I0J1502D01*
G01Y1097592D01*
G02X1824466Y1098215I1502J-2D01*
G01X1824484Y1098254D01*
X1824485Y1098338D01*
X1824350Y1098651D01*
G03X1824231Y1098761I-184J-79D01*
G01X1824230D01*
G02X1823204Y1100185I475J1424D01*
G02X1823636Y1101239I1502J0D01*
G01X1823637Y1101240D01*
X1823639Y1101242D01*
G03X1823695Y1101380I-144J139D01*
G01X1823698Y1101658D01*
G03X1823644Y1101796I-200J1D01*
G01X1823643Y1101797D01*
X1823642Y1101798D01*
G02X1823231Y1102830I1090J1032D01*
G02X1823986Y1104133I1502J0D01*
G03X1824087Y1104308I-99J174D01*
G01X1824083Y1104711D01*
X1824028Y1104803D01*
G37*
G36*
G01X1815833Y1095960D02*
G02X1815254Y1097145I923J1185D01*
G02X1818258I1502J0D01*
G02X1817679Y1095960I-1502J0D01*
G03X1817604Y1095832I123J-158D01*
G03X1817602Y1095802I198J-28D01*
G01Y1095488D01*
G03X1817604Y1095458I200J-2D01*
G03X1817679Y1095330I198J30D01*
G02X1818258Y1094145I-923J-1185D01*
G02X1815254I-1502J0D01*
G02X1815833Y1095330I1502J0D01*
G03X1815908Y1095458I-123J158D01*
G03X1815910Y1095488I-198J28D01*
G01Y1095802D01*
G03X1815908Y1095832I-200J2D01*
G03X1815833Y1095960I-198J-30D01*
G37*
G36*
G01X1769655Y1028512D02*
G03X1770271Y1028845I216J337D01*
G02X1771773Y1030331I1502J-16D01*
G02Y1027327I0J-1502D01*
G02X1770962Y1027565I0J1501D01*
G03X1770346Y1027232I-216J-337D01*
G02X1768844Y1025746I-1502J16D01*
G02Y1028750I0J1502D01*
G02X1769655Y1028512I0J-1501D01*
G37*
G54D37*
X1812130Y1205349D03*
X1783278Y1208140D03*
X1802670Y1210905D03*
X1834665Y1213239D03*
X1806835Y1214668D03*
X1814741Y1217093D03*
X1807243Y1219955D03*
X1800489Y1220598D03*
X1805126Y1225745D03*
X1811482Y1226423D03*
X1772188Y1428369D03*
X1812202Y1432624D03*
X1803885Y1435046D03*
X1783178Y1437550D03*
X1787745Y1437765D03*
X1778227Y1438099D03*
X1786091Y1443715D03*
X1795374Y1444543D03*
X1806428D03*
X1596836Y1446488D03*
X1601968Y1453442D03*
X1597457Y1460662D03*
X1605430Y1468023D03*
X1778104Y1470289D03*
X1591775Y1473090D03*
X1809342Y1476733D03*
X1600008Y1488492D03*
X1596038Y1492000D03*
X1430374Y1492474D03*
X1420877Y1494706D03*
X1591333Y1501980D03*
X1421964Y1502813D03*
X1608500Y1506000D03*
X1591925Y1512075D03*
X1601500Y1514500D03*
X1608500Y1515000D03*
X1604000Y1519000D03*
X1423930Y1520364D03*
X1613790Y1523334D03*
X1590748Y1523377D03*
X1443103Y1527201D03*
X1609348Y1527334D03*
X1429587Y1527450D03*
X1446135Y1530876D03*
X1613790Y1531334D03*
X1609348Y1535334D03*
X1408536Y1536570D03*
X1600732Y1539334D03*
X1441145Y1540415D03*
X1598574Y1543373D03*
X1433405Y1546001D03*
X1407747Y1549054D03*
X1408044Y1559306D03*
X1443769Y1562173D03*
X1440153Y1563093D03*
X1432913Y1568679D03*
X1407255Y1571732D03*
X1758390Y1577905D03*
X1766313Y1580198D03*
X1761072Y1590719D03*
X1759947Y1599029D03*
X1765040Y1599511D03*
X1750685Y1621654D03*
X1773820Y1631238D03*
X1762041Y1631511D03*
X1768422Y1632245D03*
X1760422Y1640303D03*
X1768422D03*
X1772422D03*
X19859Y1520657D03*
X71910Y1625009D03*
X60554Y1615152D03*
X69816Y1592527D03*
X74909Y1593009D03*
X82291Y1633801D03*
X78291D03*
Y1625743D03*
X70291Y1633801D03*
X83689Y1624736D03*
X762671Y1619367D03*
X756358Y1613767D03*
X732268Y1618260D03*
X732825Y1604100D03*
X777059Y1608982D03*
X768361Y1610083D03*
X744924Y1617709D03*
X741705Y1622015D03*
X736067Y1611892D03*
X749704Y1608631D03*
X737892Y1602340D03*
X749786Y1590517D03*
X738775Y1597866D03*
X747140Y1581335D03*
X784046Y1600438D03*
X781110Y1595254D03*
X759802Y1590864D03*
X763542Y1590186D03*
X621727Y1556800D03*
X595809Y1532133D03*
Y1546214D03*
X591809Y1542407D03*
X581803Y1493687D03*
X578859Y1497758D03*
X588859Y1490895D03*
X590826Y1495688D03*
X588507Y1514141D03*
X582027Y1502800D03*
X577931Y1505687D03*
X581803Y1509687D03*
X575809Y1532912D03*
X587809Y1528389D03*
X583809Y1533025D03*
X579809Y1528163D03*
X587809Y1545854D03*
X583809Y1541607D03*
X577571Y1544013D03*
X570796Y1530309D03*
X567324Y1528151D03*
X565400Y1535100D03*
X563968Y1541445D03*
X568279Y1538438D03*
X572507Y1541375D03*
X459290Y1297035D03*
X463290D03*
X451304Y1297045D03*
X444288Y1314391D03*
X434424Y1286274D03*
X430527Y1289198D03*
X440906D03*
X439434Y1322369D03*
X419619Y1539978D03*
X421454Y1544625D03*
X422539Y1534361D03*
X426701Y1541947D03*
X418151Y1552470D03*
X417461Y1569584D03*
X419545Y1317722D03*
X413127Y1318011D03*
X413526Y1288938D03*
X419977Y1288843D03*
X413640Y1292856D03*
X404500Y1452500D03*
X408964Y1531149D03*
X399373Y1555855D03*
X405496Y1561024D03*
X400396D03*
X410596D03*
X401461Y1569560D03*
X397461D03*
X404324Y1271889D03*
Y1275889D03*
X407767Y1292198D03*
X403678Y1295426D03*
X398584Y1313443D03*
X409220Y1315516D03*
X404583Y1316131D03*
X408787Y1321795D03*
X382017Y1559700D03*
X395296Y1561024D03*
X391740Y1550729D03*
Y1555829D03*
X381900Y1544800D03*
X391740Y1545629D03*
Y1540529D03*
X386415Y1321645D03*
X391691Y1326715D03*
X255909Y1542043D03*
X250790Y1539759D03*
X234976Y1481676D03*
X237633Y1511909D03*
X244600Y1531700D03*
X240808Y1519942D03*
X235687Y1522578D03*
X237580Y1528604D03*
X245937Y1524237D03*
X239949Y1541327D03*
X244912Y1539389D03*
X226135Y1502442D03*
X230758Y1505046D03*
X226971Y1514578D03*
X227552Y1530675D03*
X232622Y1531104D03*
X226971Y1522578D03*
X219981Y1530797D03*
X223322Y1518578D03*
X222119Y1539941D03*
X227882Y1540816D03*
X233753Y1539752D03*
X224780Y1478149D03*
X217985Y1483055D03*
X225765Y1471985D03*
X233313Y1476699D03*
X221899Y1488800D03*
X218021Y1494724D03*
X222843Y1498442D03*
X217614Y1489671D03*
X233180Y1486442D03*
X233166Y1491454D03*
X53197Y1017759D03*
Y1014205D03*
X55699Y1072761D03*
X61588Y1074481D03*
X62109Y1079656D03*
Y1091656D03*
X60269Y1198820D03*
X63094Y1207604D03*
X55596Y1210466D03*
X48704Y1017982D03*
X47314Y1072228D03*
X41172Y1079064D03*
X46166Y1093757D03*
X48585Y1123867D03*
X55188Y1205179D03*
X51023Y1201416D03*
X48842Y1211109D03*
X53479Y1216256D03*
X31631Y1198651D03*
X38823Y1009273D03*
X44999Y1009510D03*
X50541Y1009589D03*
X38197Y1017759D03*
X44197D03*
X41197Y1014205D03*
X47197D03*
X20216Y1009748D03*
X14357Y1009906D03*
X17033Y1006819D03*
X20197Y1017759D03*
Y1014205D03*
X14197Y1017759D03*
Y1014205D03*
X26155Y1009985D03*
X32093Y1009748D03*
X35197Y1014205D03*
X26197Y1017759D03*
X32197D03*
X29197Y1014205D03*
X395380Y1485778D03*
X395199Y1482223D03*
X401011Y1307258D03*
X418430Y1394237D03*
X420636Y1383912D03*
X410172Y1402446D03*
X391757Y1383480D03*
X391852Y1389931D03*
X395112Y1395690D03*
X420925Y1390330D03*
X395770Y1389817D03*
X398340Y1399779D03*
X399959Y1352153D03*
X392234Y1369579D03*
Y1364501D03*
X729600Y1625165D03*
X771383Y1616917D03*
X749439Y1458777D03*
X740530Y1524113D03*
X781124Y1583553D03*
X23603Y1449735D03*
X54843Y1501625D03*
X48089Y1501387D03*
X26231Y1554167D03*
X22381Y1554152D03*
X33189Y1501373D03*
X39095Y1501361D03*
X60303Y1534436D03*
X6951Y1538547D03*
X47621Y1343672D03*
X15889Y1494254D03*
X10089D03*
X60277Y1528395D03*
X60227Y1514751D03*
X18879Y1534334D03*
X6489Y1501334D03*
X55862Y1541791D03*
X10367Y1553080D03*
X65478Y1541980D03*
X19735Y1530499D03*
X19745Y1508846D03*
X12599Y1438143D03*
X16304Y1468196D03*
X58443Y1272257D03*
X47074Y1555923D03*
X64747Y1555890D03*
X40951Y1555932D03*
X778045Y1619395D03*
X738325Y1634485D03*
X743331Y1627871D03*
X778358Y1627418D03*
X755187Y1580821D03*
X60747Y1555890D03*
X389700Y1536900D03*
X98943Y200864D03*
X557751Y750851D03*
X475588Y1043055D03*
X470610Y1033783D03*
X471755Y1038665D03*
X470978Y1046591D03*
X753035Y141247D03*
X1038678Y776750D03*
X528500Y1106365D03*
X525525Y1110092D03*
X514566Y1000766D03*
X514690Y996766D03*
Y1004766D03*
X514566Y1016266D03*
X514649Y1020266D03*
X514843Y1030766D03*
X519500Y1028377D03*
X498585Y1016266D03*
X506566Y1012266D03*
X496372Y1106298D03*
X494677Y830468D03*
X495470Y844271D03*
X495073Y835586D03*
X495700Y849389D03*
X493091Y989550D03*
X498435Y1008766D03*
X506566Y996766D03*
Y1008766D03*
X498524Y997590D03*
X489406Y797558D03*
X489572Y822805D03*
X479448Y828594D03*
X490706Y859339D03*
X477574Y860815D03*
X487091Y989550D03*
X480711Y999941D03*
X477857Y1004375D03*
X485678Y1039880D03*
X485633Y1036155D03*
X463404Y846870D03*
X465492Y861970D03*
X471726Y883705D03*
X474540Y927341D03*
X471110Y921577D03*
X471068Y930235D03*
X475018Y992568D03*
X467345Y996480D03*
X459360Y1004680D03*
X459700Y1035716D03*
X477765Y1093432D03*
X460498Y870334D03*
X459360Y1012325D03*
X443591Y1019766D03*
X451140Y1021793D03*
X447091Y1019766D03*
X450875Y1028416D03*
X443091Y1034266D03*
X459700Y1032266D03*
X443091Y1026266D03*
X427810Y1110092D03*
X425062Y883981D03*
X409231Y1118801D03*
X404468Y864407D03*
X396306Y864409D03*
X406770Y869767D03*
X405466Y881299D03*
X397431Y870654D03*
X401108Y878487D03*
X397252Y962861D03*
X396671Y968287D03*
X392910Y948536D03*
X393998Y971780D03*
X378790Y1001083D03*
X380280Y1006071D03*
X383710Y1007283D03*
X382465Y1012430D03*
X383391Y804000D03*
X386589Y864408D03*
X383462Y860535D03*
X392584Y875845D03*
X382675Y870151D03*
X391614Y930676D03*
X384856Y947987D03*
X368067Y925136D03*
X370214Y943812D03*
X368626Y931346D03*
X368964Y937738D03*
X372858Y935136D03*
X366761Y934550D03*
X379928Y949774D03*
X378875Y961862D03*
X370214Y947812D03*
X370101Y953699D03*
X370214Y963812D03*
Y971812D03*
X378928Y967812D03*
X358207Y836462D03*
X333985Y1017945D03*
X341077Y1018056D03*
X281980Y953926D03*
X275123Y847874D03*
X248556Y824003D03*
X136862Y857244D03*
X129666Y857514D03*
X133424Y857303D03*
X68598Y859415D03*
X52077Y905295D03*
X48429Y916430D03*
X47264Y919649D03*
X241204Y814841D03*
X237591Y815266D03*
X248506Y812042D03*
X365691Y815127D03*
X371507Y815303D03*
X362042Y814772D03*
X1001676Y678015D03*
X1022937Y691421D03*
X1013486Y750773D03*
X1779404Y826570D03*
X1791041Y818795D03*
X1773810Y990821D03*
X1173034Y765060D03*
X1170465Y677836D03*
X1162863Y678519D03*
X1159173Y678462D03*
X1169256Y694983D03*
X1166115Y718469D03*
X1163774Y713347D03*
X1171934Y733857D03*
X1164732Y802269D03*
X1169697Y791935D03*
X1164925Y791607D03*
X1161535Y844167D03*
X1152485Y764552D03*
X1154985Y802897D03*
X1153485Y813142D03*
X1153229Y848581D03*
X1111785Y686971D03*
X1116296Y691851D03*
X1118105Y707592D03*
X795011Y95111D03*
X769609Y124283D03*
X775118Y110784D03*
X780118D03*
X779697Y124663D03*
X774675Y124879D03*
X44563Y482165D03*
X62224Y473045D03*
X41643Y473419D03*
Y464919D03*
X49643Y464419D03*
X48596Y451419D03*
X63154Y462371D03*
X48643Y442919D03*
X57857Y446071D03*
X67670Y464818D03*
X459461Y473805D03*
X459414Y468689D03*
X459757Y463520D03*
X451144Y468809D03*
X1770135Y490711D03*
X1745231Y489036D03*
X1750879Y541940D03*
X1692379Y622912D03*
X1618538Y618288D03*
X1627224Y643252D03*
X1613362Y656321D03*
X1621362D03*
X1617362D03*
X1619950Y678519D03*
X1616260Y678462D03*
X1571755Y577937D03*
X1579260Y604567D03*
X1579760Y595500D03*
X1580354Y616317D03*
X1580418Y610072D03*
X1576297Y627600D03*
X1572141Y662981D03*
X1569434Y677111D03*
X1568872Y686971D03*
X1575192Y707592D03*
X1556588Y545528D03*
X1562385Y610400D03*
X1564670Y650122D03*
X1565132Y668153D03*
X1561552Y665455D03*
X1519185Y603600D03*
Y619600D03*
X1520729Y634190D03*
X1519185Y623600D03*
X1524200Y646098D03*
X1513284Y552466D03*
X1455419Y578986D03*
X1458912Y581659D03*
X1454944Y596729D03*
X1458944Y605443D03*
X1450944D03*
X1461474Y655807D03*
X1438944Y605637D03*
X1448994Y596782D03*
X1443775Y596089D03*
X1438944Y597232D03*
X1434944Y605443D03*
X1437790Y625013D03*
X1449993Y578405D03*
X1435668Y582747D03*
X1435119Y590801D03*
X1434944Y597130D03*
X1430944Y605443D03*
X1425452Y633473D03*
X1430175Y627852D03*
X1420452Y628078D03*
X1405619Y541135D03*
X1405992Y534909D03*
X1405708Y552726D03*
X1405685Y546553D03*
X1407754Y616905D03*
X1407566Y622285D03*
X1411622Y610548D03*
X1407835Y627713D03*
X1418439Y633736D03*
X1288144Y489036D03*
X1160275Y656321D03*
X1164275D03*
X1161451Y618288D03*
X1156275Y656321D03*
X1126622Y506256D03*
X1114668Y577937D03*
X1122173Y604567D03*
X1122673Y595500D03*
X1123267Y616317D03*
X1123331Y610072D03*
X1115054Y662981D03*
X1099501Y545528D03*
X1105298Y610400D03*
X998332Y578986D03*
X1001825Y581659D03*
X997857Y596729D03*
X1001857Y605443D03*
X1002883Y622521D03*
X1005800Y637600D03*
X992906Y578405D03*
X986688Y596089D03*
X991907Y596782D03*
X981857Y597232D03*
X993857Y605443D03*
X980703Y625013D03*
X978032Y590801D03*
X978581Y582747D03*
X977857Y597130D03*
X973857Y605443D03*
X977857D03*
X968365Y633473D03*
X972354Y627908D03*
X961352Y633736D03*
X963365Y628078D03*
X958124Y492354D03*
X957977Y500202D03*
X949823Y495982D03*
X959600Y496486D03*
X949823Y491982D03*
X948905Y534909D03*
X950667Y616905D03*
X954535Y610548D03*
X956345Y633716D03*
X948532Y541135D03*
X936653Y526836D03*
X948621Y552726D03*
X948598Y546553D03*
X931627Y557641D03*
Y569578D03*
Y581578D03*
Y577578D03*
Y573578D03*
X944296Y611071D03*
X723656Y705858D03*
X720985Y711658D03*
X723177Y728219D03*
X724362Y504731D03*
X711463Y546712D03*
X704364Y618288D03*
X711328Y653821D03*
X705390Y655789D03*
X705776Y678519D03*
X715802Y706446D03*
X699188Y656321D03*
X702086Y678462D03*
X702691Y762971D03*
Y756971D03*
X702677Y775159D03*
X657581Y577937D03*
X665586Y595500D03*
X665086Y604567D03*
X666180Y616317D03*
X666244Y610072D03*
X665643Y646055D03*
X662092Y666275D03*
X657967Y662981D03*
X659209Y691851D03*
X661018Y707592D03*
X642414Y545528D03*
X648211Y610400D03*
X650958Y668153D03*
X598462Y504684D03*
X599110Y552466D03*
X605011Y603600D03*
Y619600D03*
Y623600D03*
X577638Y769772D03*
X578271Y763556D03*
X578204Y775137D03*
X563200Y739600D03*
X571493Y763090D03*
X544738Y581659D03*
X544770Y605443D03*
X551475Y661504D03*
X543101Y698772D03*
X540379Y719785D03*
X541245Y578986D03*
X535819Y578405D03*
X529601Y596089D03*
X540770Y596729D03*
X534820Y596782D03*
X524770Y597232D03*
X536770Y605443D03*
X537578Y772428D03*
X520945Y590801D03*
X521494Y582747D03*
X520770Y597130D03*
X511278Y633473D03*
X515267Y627908D03*
X523616Y625013D03*
X510425Y683246D03*
X501224Y492050D03*
X492736Y495982D03*
X502493Y495917D03*
X500890Y500202D03*
X497448Y610548D03*
X506278Y628078D03*
X499258Y633716D03*
X504265Y633736D03*
X492736Y491982D03*
X493580Y616905D03*
X493392Y622285D03*
X484772Y621311D03*
X487209Y611071D03*
X493778Y633724D03*
X493661Y627713D03*
X484772Y625311D03*
Y629311D03*
X483059Y662649D03*
X468558Y495669D03*
Y516609D03*
X464199Y510184D03*
X459929Y491669D03*
X460537Y501905D03*
X459952Y496842D03*
X447279Y637031D03*
X447921Y630789D03*
X453552Y631779D03*
X446987Y643360D03*
X443144Y628667D03*
X441162Y638313D03*
X380963Y731000D03*
X391470Y732865D03*
X381875Y740341D03*
X373971Y489036D03*
X337078Y551381D03*
X335399Y544718D03*
X320785Y553287D03*
X321119Y622912D03*
X252688Y636364D03*
X248690Y678519D03*
X248090Y691114D03*
X254634Y698241D03*
X247536Y602689D03*
X247278Y618288D03*
X246102Y656321D03*
X250102D03*
X242102D03*
X245000Y678462D03*
X244267Y696911D03*
X208000Y604567D03*
X203500Y606929D03*
X208500Y595500D03*
X209094Y616317D03*
X209158Y610072D03*
X203741Y612592D03*
X203460Y618400D03*
X208540Y621591D03*
X205941Y668934D03*
X185328Y545528D03*
X191125Y610400D03*
X142024Y552466D03*
X147925Y603600D03*
Y619600D03*
X149469Y634190D03*
X147925Y623600D03*
X152658Y645389D03*
X119099Y755052D03*
X111993Y710102D03*
X120250Y758841D03*
X86788Y581659D03*
X87684Y605443D03*
X95539Y664443D03*
X84159Y578986D03*
X78733Y578405D03*
X77734Y596782D03*
X72515Y596089D03*
X83684Y596729D03*
X79684Y605443D03*
X84845Y659857D03*
X73914Y660107D03*
X82648Y670679D03*
X79043Y667391D03*
X84314Y686107D03*
X82562Y680037D03*
X78735Y683426D03*
X63859Y590801D03*
X64408Y582747D03*
X67684Y605637D03*
X63684Y597130D03*
X67684Y597232D03*
X59684Y605443D03*
X63684D03*
X58181Y627908D03*
X66530Y625013D03*
X43948Y492108D03*
X45256Y495993D03*
X43804Y500202D03*
X40362Y610548D03*
X49192Y628078D03*
X35650Y495982D03*
Y491982D03*
X34732Y534909D03*
X34359Y541135D03*
X34448Y552726D03*
X34425Y546553D03*
X36306Y622285D03*
X36494Y616905D03*
X30123Y611071D03*
X36575Y627713D03*
X27686Y629311D03*
X1108045Y668153D03*
X113505Y796856D03*
X109591Y796905D03*
X118467Y796785D03*
X373703Y782555D03*
X380607Y786932D03*
X380331Y782627D03*
X432303Y785067D03*
X1178045Y312193D03*
X1431000Y591000D03*
X658392Y200864D03*
X943183Y281652D03*
X1786170Y448931D03*
X1792527Y452799D03*
X1786693Y459170D03*
X1791088Y77296D03*
X1804758Y294429D03*
X1793524Y303343D03*
X1805196Y300952D03*
X1809095Y435101D03*
X1803700Y440101D03*
X1803530Y431112D03*
X1809358Y442114D03*
X1803335Y452718D03*
X1809346Y452601D03*
X1797907Y452987D03*
X1809338Y447121D03*
X1804933Y461607D03*
X1796933D03*
X1796136Y471334D03*
X1800933Y461607D03*
X1768586Y467560D03*
X1764903Y470382D03*
X1776561Y467560D03*
X1779232Y55513D03*
X1775457Y68581D03*
X1785246Y60660D03*
X1781832Y60513D03*
X1775470Y80581D03*
X1790664Y71908D03*
X1781960Y85731D03*
X1790712Y81713D03*
X1779600Y88801D03*
X1790373Y94663D03*
X1786466Y85923D03*
Y94279D03*
X1782517Y94351D03*
X1777653Y103621D03*
X1785886Y168665D03*
Y176665D03*
X1777172Y172665D03*
X1777109Y178560D03*
X1785779Y192665D03*
X1785886Y196665D03*
X1777289Y200864D03*
X1785999Y186778D03*
X1785918Y204864D03*
X1777378Y212455D03*
X1777312Y207037D03*
X1785918Y208864D03*
X1781559Y219379D03*
X1782187Y228631D03*
X1761941Y106186D03*
X1773364Y112083D03*
X1771714Y171523D03*
X1762102Y168697D03*
X1763190Y191941D03*
X1771244Y192490D03*
X1776519Y190185D03*
X1767202Y192300D03*
X1774679Y221642D03*
X1759112Y256303D03*
X1763887Y266114D03*
X1761360Y281982D03*
X1753784Y265701D03*
X1758871Y265896D03*
X1755419Y281716D03*
X1748497Y371060D03*
X1752497Y371076D03*
X1750135Y379088D03*
X1755433Y379028D03*
X1744180Y383966D03*
X1756553Y466409D03*
X1767552Y76587D03*
Y72615D03*
X1762010Y97475D03*
X1768991Y100625D03*
X1738824Y456034D03*
Y461034D03*
X1751456Y98551D03*
X1755006Y103783D03*
X1758848Y177616D03*
X1759429Y172190D03*
X1721746Y377173D03*
X1715228Y387966D03*
X1718851Y391533D03*
X1720571Y385644D03*
X1725746Y385123D03*
X1718318Y399918D03*
X1725154Y406060D03*
X1721423Y412106D03*
X1724627Y459330D03*
X1724580Y454214D03*
X1743175Y92874D03*
X1729896Y90615D03*
X1734267Y95236D03*
X1734217Y99961D03*
X1736333Y258880D03*
X1744524Y379429D03*
X1741746Y377173D03*
X1737786D03*
X1729751D03*
X1737746Y385123D03*
X1741420Y391569D03*
X1739847Y401066D03*
X1697984Y226320D03*
X1705686Y230556D03*
X1709941Y228747D03*
X1700945Y228646D03*
X1704671Y242078D03*
X1699902Y232971D03*
X1696552Y244571D03*
X1703895Y256394D03*
X1700223Y292141D03*
X1698292Y303962D03*
X1713788Y97667D03*
X1724584Y90650D03*
X1724334Y95236D03*
X1710547Y238714D03*
X1683556Y204864D03*
Y208864D03*
X1679197Y219379D03*
X1693932Y249108D03*
X1685313Y248371D03*
X1683523Y324518D03*
X1677810Y324466D03*
X1686408Y332584D03*
X1687424Y347937D03*
X1680518Y377912D03*
Y381912D03*
X1704934Y97667D03*
X1709184Y95111D03*
X1700590Y102495D03*
X1698851Y125107D03*
X1700324Y142862D03*
X1701365Y148717D03*
X1673203Y328867D03*
X1668979Y339559D03*
X1673723Y353881D03*
X1670323Y353534D03*
X1670260Y377912D03*
X1669260Y391496D03*
X1663618Y393858D03*
X1663780Y384410D03*
X1666959Y382047D03*
X1670260Y386500D03*
X1669260Y409000D03*
X1665260Y398583D03*
X1670348Y397912D03*
X1667260Y403500D03*
X1688011Y86012D03*
Y94374D03*
X1683152Y86046D03*
X1680155Y94351D03*
X1684104Y94279D03*
X1694291Y110784D03*
X1689291D03*
X1683782Y124283D03*
X1693870Y124663D03*
X1688848Y124879D03*
X1695214Y138838D03*
X1682189Y161306D03*
X1679440Y157370D03*
X1683524Y168665D03*
Y176665D03*
Y192665D03*
X1683637Y186778D03*
X1649773Y449961D03*
X1653490Y458572D03*
X1645826Y446606D03*
X1647133Y463479D03*
X1647604Y467367D03*
X1676870Y55513D03*
X1673095Y68581D03*
X1673108Y80581D03*
X1665190Y76587D03*
Y72615D03*
X1679598Y85731D03*
X1677238Y88801D03*
X1675291Y103621D03*
X1666629Y100625D03*
X1671002Y112083D03*
X1667208Y141247D03*
X1671695Y143518D03*
X1669352Y171523D03*
X1674810Y172665D03*
X1674747Y178560D03*
X1674157Y190185D03*
X1668882Y192490D03*
X1667318Y198828D03*
X1674927Y200864D03*
X1664840Y192300D03*
X1674950Y207037D03*
X1675016Y212455D03*
X1672317Y221642D03*
X1679825Y228631D03*
X1658645Y143740D03*
X1656025Y148277D03*
X1656486Y177616D03*
X1659740Y168697D03*
X1657067Y172190D03*
X1660828Y191941D03*
X1656750Y256303D03*
X1656509Y265896D03*
X1661525Y266114D03*
X1651422Y265701D03*
X1653057Y281716D03*
X1658998Y281982D03*
X1658200Y315039D03*
X1654771Y352088D03*
X1645685Y381500D03*
X1648835Y390500D03*
X1650044Y435158D03*
X1649789Y440489D03*
X1646209Y442606D03*
X1650087Y444841D03*
X1635170Y442856D03*
X1632439Y452265D03*
X1633225Y458455D03*
X1636271Y453881D03*
X1635185Y446595D03*
X1649094Y98551D03*
X1659648Y97475D03*
X1659579Y106186D03*
X1652644Y103783D03*
X1647406Y147540D03*
X1651178Y141247D03*
X1640813Y92874D03*
X1631905Y95236D03*
X1631855Y99961D03*
X1633971Y258880D03*
X1640030Y335550D03*
X1636561Y343072D03*
X1630691Y347432D03*
X1640197Y374690D03*
X1603324Y230556D03*
X1607579Y227824D03*
X1598583Y228646D03*
X1608185Y238714D03*
X1602309Y242078D03*
X1597540Y232971D03*
X1604677Y253198D03*
X1596691Y287397D03*
X1596197Y293477D03*
X1602138Y351047D03*
X1596253Y375633D03*
X1596534Y379760D03*
X1599527Y396718D03*
X1622222Y90650D03*
X1627534Y90615D03*
X1621972Y95236D03*
X1628636Y422088D03*
X1625772Y438323D03*
X1625938Y445873D03*
X1592635Y455911D03*
X1591443Y465332D03*
X1602572Y97667D03*
X1611426D03*
X1606822Y95111D03*
X1598228Y102495D03*
X1597962Y142862D03*
X1599003Y148717D03*
X1586929Y110784D03*
X1591929D03*
X1586486Y124879D03*
X1591508Y124663D03*
X1596489Y125107D03*
X1592852Y138838D03*
X1581162Y168665D03*
Y176665D03*
Y192665D03*
Y196665D03*
X1581275Y186778D03*
X1581194Y204864D03*
X1595622Y226320D03*
X1594190Y244571D03*
X1591570Y249108D03*
X1582951Y248371D03*
X1595069Y337361D03*
X1595109Y342663D03*
X1594466Y350984D03*
X1574775Y333549D03*
X1563877Y329863D03*
Y343363D03*
Y334363D03*
X1578587Y341787D03*
X1578420Y338309D03*
X1563877Y352363D03*
X1575935Y382109D03*
X1585649Y86012D03*
Y94374D03*
X1580790Y86046D03*
X1571895Y58013D03*
X1570733Y68581D03*
X1570746Y80581D03*
X1577236Y85731D03*
X1574876Y88801D03*
X1581742Y94279D03*
X1577793Y94351D03*
X1572929Y103621D03*
X1568640Y112083D03*
X1581420Y124283D03*
X1569333Y143518D03*
X1579827Y161306D03*
X1577078Y157370D03*
X1566990Y171523D03*
X1572385Y178560D03*
X1572448Y172665D03*
X1571795Y190185D03*
X1566520Y192490D03*
X1572565Y200864D03*
X1572654Y212455D03*
X1572588Y207037D03*
X1581194Y208864D03*
X1569955Y221642D03*
X1576835Y219379D03*
X1577463Y228631D03*
X1563877Y325363D03*
Y316363D03*
X1557378Y168697D03*
X1554705Y172190D03*
X1554124Y177616D03*
X1558466Y191941D03*
X1554388Y256303D03*
X1559163Y266114D03*
X1554147Y265896D03*
X1556636Y281982D03*
X1550695Y281716D03*
X1550931Y305158D03*
X1554403Y316363D03*
X1553534Y327337D03*
X1553910Y331798D03*
X1553597Y336601D03*
X1553862Y344867D03*
X1545583Y316363D03*
X1539140Y320863D03*
X1545636Y325363D03*
X1542797Y329863D03*
X1545846Y334363D03*
X1544951Y343363D03*
X1551175Y347283D03*
X1545434Y352363D03*
X1562828Y72615D03*
Y76587D03*
X1564267Y100625D03*
X1557286Y97475D03*
X1550282Y103783D03*
X1557217Y106186D03*
X1548816Y141247D03*
X1564846D03*
X1556283Y143740D03*
X1553663Y148277D03*
X1518780Y463600D03*
X1546732Y98551D03*
X1538451Y92874D03*
X1545044Y147540D03*
X1549060Y265701D03*
X1525172Y90615D03*
X1519860Y90650D03*
X1529493Y99961D03*
X1529543Y95236D03*
X1519610D03*
X1500962Y230556D03*
X1505217Y227824D03*
X1505823Y238714D03*
X1499947Y242078D03*
X1503884Y295549D03*
X1501684Y336561D03*
X1515909Y354601D03*
X1493260Y226320D03*
X1496221Y228646D03*
X1495178Y232971D03*
X1491828Y244571D03*
X1489208Y249108D03*
X1499171Y256394D03*
X1497446Y295877D03*
X1486360Y322700D03*
X1500659Y330024D03*
X1495605Y322700D03*
X1486360Y345200D03*
X1500386Y344642D03*
X1486913Y340327D03*
X1487152Y331272D03*
X1495689Y332534D03*
X1495521Y340700D03*
X1486360Y349700D03*
X1495521Y349681D03*
X1495925Y358700D03*
X1499839Y354001D03*
X1486890Y368576D03*
X1494286Y372699D03*
X1509064Y97667D03*
X1504460Y95111D03*
X1484124Y124879D03*
X1477465Y161306D03*
X1474716Y157370D03*
X1478800Y168665D03*
Y176665D03*
X1470023Y178560D03*
X1470086Y172665D03*
X1469433Y190185D03*
X1478800Y192665D03*
Y196665D03*
X1470203Y200864D03*
X1478913Y186778D03*
X1478832Y204864D03*
X1470292Y212455D03*
X1470226Y207037D03*
X1478832Y208864D03*
X1467593Y221642D03*
X1474473Y219379D03*
X1475101Y228631D03*
X1480589Y248371D03*
X1477549Y327200D03*
Y322700D03*
Y345200D03*
Y340700D03*
Y331700D03*
Y358700D03*
Y349700D03*
Y354200D03*
X1468309Y408861D03*
X1475236Y412482D03*
X1466231Y423671D03*
X1469538Y416795D03*
X1466653Y428582D03*
X1471375Y433115D03*
X1498621Y19043D03*
X1489556Y17645D03*
X1498621Y31043D03*
Y23043D03*
X1489829Y29424D03*
X1490563Y23043D03*
X1500210Y97667D03*
X1483287Y94374D03*
X1495866Y102495D03*
X1489567Y110784D03*
X1494127Y125107D03*
X1489146Y124663D03*
X1495600Y142862D03*
X1496641Y148717D03*
X1490490Y138838D03*
X1452026Y256303D03*
X1456801Y266114D03*
X1454274Y281982D03*
X1459060Y320861D03*
Y325361D03*
Y329861D03*
Y338861D03*
Y343361D03*
Y334361D03*
Y347861D03*
Y352361D03*
X1458214Y406231D03*
X1464536Y433114D03*
X1479972Y40780D03*
X1472146Y55513D03*
X1468371Y68581D03*
X1474874Y85731D03*
X1483287Y86012D03*
X1468384Y80581D03*
X1472514Y88801D03*
X1478428Y86046D03*
X1475431Y94351D03*
X1479380Y94279D03*
X1470567Y103621D03*
X1466278Y112083D03*
X1484567Y110784D03*
X1479058Y124283D03*
X1448822Y345324D03*
X1448500Y340575D03*
X1439712Y336673D03*
X1449060Y356861D03*
X1441180Y354909D03*
X1447502Y360785D03*
X1434697Y347125D03*
X1439719Y350387D03*
X1443041Y363648D03*
X1442633Y371502D03*
X1445906Y366030D03*
X1436930Y461818D03*
X1457347Y31518D03*
X1457829Y26425D03*
X1460466Y76587D03*
Y72615D03*
X1461905Y100625D03*
X1454924Y97475D03*
X1454855Y106186D03*
X1462484Y141247D03*
X1466971Y143518D03*
X1453921Y143740D03*
X1455016Y168697D03*
X1452343Y172190D03*
X1464628Y171523D03*
X1464158Y192490D03*
X1456104Y191941D03*
X1447920Y103783D03*
X1442682Y147540D03*
X1446454Y141247D03*
X1451301Y148277D03*
X1451762Y177616D03*
X1451785Y265896D03*
X1446698Y265701D03*
X1448333Y281716D03*
X1448948Y326448D03*
X1449060Y320861D03*
X1438829Y329861D03*
X1437064Y320861D03*
X1440420Y346833D03*
X1422810Y90615D03*
X1427131Y99961D03*
X1427181Y95236D03*
X1434166Y325361D03*
X1434164Y339232D03*
X1434038Y334114D03*
X1435818Y352361D03*
X1434997Y442603D03*
X1427117Y443071D03*
X1432414Y459371D03*
X1444370Y98551D03*
X1436089Y92874D03*
X1406702Y97667D03*
X1417498Y90650D03*
X1417248Y95236D03*
X1402098Y95111D03*
X1403461Y238714D03*
X1416912Y386903D03*
X1408854Y381207D03*
X1416470Y381397D03*
X1397848Y97667D03*
X1393504Y102495D03*
X1391765Y125107D03*
X1393238Y142862D03*
X1394279Y148717D03*
X1388128Y138838D03*
X1390898Y226320D03*
X1402855Y227824D03*
X1398600Y230556D03*
X1393859Y228646D03*
X1397585Y242078D03*
X1392816Y232971D03*
X1389466Y244571D03*
X1396809Y256394D03*
X1395726Y320529D03*
X1395568Y325529D03*
X1395726Y330529D03*
X1395736Y335529D03*
X1395726Y340529D03*
Y345529D03*
Y360529D03*
Y350529D03*
Y355529D03*
X1391896Y365529D03*
X1387847Y366710D03*
X1382205Y110784D03*
X1387205D03*
X1386784Y124663D03*
X1376696Y124283D03*
X1381762Y124879D03*
X1375103Y161306D03*
X1372354Y157370D03*
X1386846Y249108D03*
X1378227Y248371D03*
X1384265Y320871D03*
Y325371D03*
Y329871D03*
X1375073Y356871D03*
X1335440Y452799D03*
X1329083Y448931D03*
X1329606Y459170D03*
X1336646Y22627D03*
X1336551Y26534D03*
X1340320Y147540D03*
X1344092Y141247D03*
X1351559Y143740D03*
X1348939Y148277D03*
X1340104Y279117D03*
X1344007Y279054D03*
X1341169Y325926D03*
X1347990Y322539D03*
X1346009Y336080D03*
X1346093Y340805D03*
X1349636Y340862D03*
X1338471Y356959D03*
X1346065Y347106D03*
X1349763Y371908D03*
X1346443Y431112D03*
X1352008Y435101D03*
X1352271Y442114D03*
X1346613Y440101D03*
X1352259Y452601D03*
X1352251Y447121D03*
X1346248Y452718D03*
X1340820Y452987D03*
X1347846Y461607D03*
X1339846D03*
X1339049Y471334D03*
X1343846Y461607D03*
X1360122Y141247D03*
X1364609Y143518D03*
X1311488Y471560D03*
X1307835Y470382D03*
X1319474Y467560D03*
X1324120Y22742D03*
X1328318Y27333D03*
X1336623Y30483D03*
X1322853Y37530D03*
X1328799Y168665D03*
Y176665D03*
Y192665D03*
Y196665D03*
X1328912Y186778D03*
X1328831Y204864D03*
X1324472Y219379D03*
X1325100Y228631D03*
X1325573Y326719D03*
X1332563Y326356D03*
X1332359Y322685D03*
X1320085Y172665D03*
X1320022Y178560D03*
X1306103Y191941D03*
X1319432Y190185D03*
X1314157Y192490D03*
X1320202Y200864D03*
X1310115Y192300D03*
X1320225Y207037D03*
X1320291Y212455D03*
X1317592Y221642D03*
X1306800Y266114D03*
X1313103Y339606D03*
X1294000Y324000D03*
X1544736Y305156D03*
X1303000Y331000D03*
X1292500Y335000D03*
X1293000Y338500D03*
X1299959Y356954D03*
X1294080Y349820D03*
X1291410Y371060D03*
X1295410Y371076D03*
X1293048Y379088D03*
X1298346Y379028D03*
X1299466Y466409D03*
X1310853Y37543D03*
X1314887Y45448D03*
X1318859D03*
X1311904Y100625D03*
X1320566Y103621D03*
X1304854Y106186D03*
X1316277Y112083D03*
X1305015Y168697D03*
X1314627Y171523D03*
X1302139Y26325D03*
X1302785Y31168D03*
X1294369Y98551D03*
X1304923Y97475D03*
X1297919Y103783D03*
X1301761Y177616D03*
X1302342Y172190D03*
X1302025Y256303D03*
X1296697Y265701D03*
X1301784Y265896D03*
X1304273Y281982D03*
X1298332Y281716D03*
X1279246Y258880D03*
X1271571Y281185D03*
X1289345Y330655D03*
X1284419Y359377D03*
X1287437Y379429D03*
X1280699Y377173D03*
X1284659D03*
X1274436Y377350D03*
X1280659Y385123D03*
X1284333Y391569D03*
X1282760Y401066D03*
X1281737Y461034D03*
Y456034D03*
X1261764Y391533D03*
X1263484Y385644D03*
X1268659Y385123D03*
X1268067Y406060D03*
X1261231Y399918D03*
X1264336Y412106D03*
X1267540Y459330D03*
X1267493Y454214D03*
X1286088Y92874D03*
X1272809Y90615D03*
X1277130Y99961D03*
X1277180Y95236D03*
X1243503Y102495D03*
X1241764Y125107D03*
X1243237Y142862D03*
X1244278Y148717D03*
X1240897Y226320D03*
X1248599Y230556D03*
X1252854Y227824D03*
X1243858Y228646D03*
X1253460Y238714D03*
X1247584Y242078D03*
X1242815Y232971D03*
X1246808Y256394D03*
X1267497Y90650D03*
X1267247Y95236D03*
X1232204Y110784D03*
X1237204D03*
X1236783Y124663D03*
X1226695Y124283D03*
X1231761Y124879D03*
X1238127Y138838D03*
X1225102Y161306D03*
X1226437Y176665D03*
Y168665D03*
Y192665D03*
X1226550Y186778D03*
X1226469Y204864D03*
Y208864D03*
X1239465Y244571D03*
X1236845Y249108D03*
X1228226Y248371D03*
X1226436Y324518D03*
X1229922Y324550D03*
X1238293Y317296D03*
X1229438Y332584D03*
X1229942Y347937D03*
X1247847Y97667D03*
X1256701D03*
X1252097Y95111D03*
X1217070Y190185D03*
X1207753Y192300D03*
X1211795Y192490D03*
X1210268Y198671D03*
X1217863Y207037D03*
X1217929Y212455D03*
X1215230Y221642D03*
X1222110Y219379D03*
X1222738Y228631D03*
X1220723Y324466D03*
X1211892Y339559D03*
X1215776Y331072D03*
X1213173Y377912D03*
X1217177Y369925D03*
X1209872Y382047D03*
X1212173Y391496D03*
X1206693Y384410D03*
X1213173Y386500D03*
X1213261Y397912D03*
X1210173Y403500D03*
X1212173Y409000D03*
X1230924Y86012D03*
Y94374D03*
X1226065Y86046D03*
X1227017Y94279D03*
X1223068Y94351D03*
X1201113Y315039D03*
X1190127Y324142D03*
X1195800Y324000D03*
X1206531Y393858D03*
X1208173Y398583D03*
X1192702Y440489D03*
X1192957Y435158D03*
X1193000Y444841D03*
X1192686Y449961D03*
X1196403Y458572D03*
X1219783Y55513D03*
X1216008Y68581D03*
X1216021Y80581D03*
X1208103Y72615D03*
Y76587D03*
X1222511Y85731D03*
X1220151Y88801D03*
X1218204Y103621D03*
X1209542Y100625D03*
X1213915Y112083D03*
X1210121Y141247D03*
X1214608Y143518D03*
X1222353Y157370D03*
X1212265Y171523D03*
X1217723Y172665D03*
X1217660Y178560D03*
X1217840Y200864D03*
X1192007Y98551D03*
X1202561Y97475D03*
X1202492Y106186D03*
X1195557Y103783D03*
X1190319Y147540D03*
X1194091Y141247D03*
X1201558Y143740D03*
X1198938Y148277D03*
X1199980Y172190D03*
X1202653Y168697D03*
X1199399Y177616D03*
X1203741Y191941D03*
X1199663Y256303D03*
X1199422Y265896D03*
X1204438Y266114D03*
X1194335Y265701D03*
X1201911Y281982D03*
X1195970Y281716D03*
X1179901Y306366D03*
X1181706Y310131D03*
X1181379Y316049D03*
X1174929Y319167D03*
X1179761Y336380D03*
X1187996Y331992D03*
X1191748Y392676D03*
X1188598Y381500D03*
X1178083Y442856D03*
X1189122Y442606D03*
X1176699Y451108D03*
X1176138Y458455D03*
X1179184Y453881D03*
Y446595D03*
X1188739Y446606D03*
X1190046Y463479D03*
X1171445Y422088D03*
X1168685Y438323D03*
X1168398Y456309D03*
X1168851Y445873D03*
X1183726Y92874D03*
X1174818Y95236D03*
X1177035Y257919D03*
X1146237Y230556D03*
X1150492Y227824D03*
X1151098Y238714D03*
X1145222Y242078D03*
X1147590Y253198D03*
X1145587Y339148D03*
X1142440Y396718D03*
X1170447Y90615D03*
X1165135Y90650D03*
X1174768Y99961D03*
X1164885Y95236D03*
X1138535Y226320D03*
X1141496Y228646D03*
X1140453Y232971D03*
X1137103Y244571D03*
X1134483Y249108D03*
X1125864Y248371D03*
X1137830Y336230D03*
X1135548Y455804D03*
X1134629Y465551D03*
X1145485Y97667D03*
X1154339D03*
X1149735Y95111D03*
X1128562Y86012D03*
Y94374D03*
X1141141Y102495D03*
X1129842Y110784D03*
X1134842D03*
X1139402Y125107D03*
X1129399Y124879D03*
X1134421Y124663D03*
X1140875Y142862D03*
X1141916Y148717D03*
X1135765Y138838D03*
X1114781Y58013D03*
X1113646Y68581D03*
X1113659Y80581D03*
X1120149Y85731D03*
X1117789Y88801D03*
X1123703Y86046D03*
X1120706Y94351D03*
X1124655Y94279D03*
X1115842Y103621D03*
X1111553Y112083D03*
X1124333Y124283D03*
X1112246Y143518D03*
X1122740Y161306D03*
X1119991Y157370D03*
X1124075Y168665D03*
Y176665D03*
X1115298Y178560D03*
X1115361Y172665D03*
X1115478Y200864D03*
X1114708Y190185D03*
X1124188Y186778D03*
X1124107Y204864D03*
X1115501Y207037D03*
X1115567Y212455D03*
X1124107Y208864D03*
X1112868Y221642D03*
X1119748Y219379D03*
X1120376Y228631D03*
X1115000Y329000D03*
Y334000D03*
Y339000D03*
X1118848Y382109D03*
X1097301Y256303D03*
X1102076Y266114D03*
X1097060Y265896D03*
X1099549Y281982D03*
X1093478Y310305D03*
X1108779Y327705D03*
X1487318Y318200D03*
X1097976Y340477D03*
X1105012Y353504D03*
X1091031Y374810D03*
X1105741Y76587D03*
Y72615D03*
X1100199Y97475D03*
X1107180Y100625D03*
X1093195Y103783D03*
X1100130Y106186D03*
X1107759Y141247D03*
X1099196Y143740D03*
X1096576Y148277D03*
X1100291Y168697D03*
X1097618Y172190D03*
X1109903Y171523D03*
X1097037Y177616D03*
X1101379Y191941D03*
X1109433Y192490D03*
X1087957Y147540D03*
X1091729Y141247D03*
X1091973Y265701D03*
X1093608Y281716D03*
X1082297Y340770D03*
X1092554Y340318D03*
X1085615Y339815D03*
X1092561Y353374D03*
X1089645Y98551D03*
X1081364Y92874D03*
X1062773Y90650D03*
X1068085Y90615D03*
X1072456Y95236D03*
X1072406Y99961D03*
X1062523Y95236D03*
X1051977Y97667D03*
X1047373Y95111D03*
X1048130Y227824D03*
X1048736Y238714D03*
X1045364Y279895D03*
X1051796Y279965D03*
X1043123Y97667D03*
X1038779Y102495D03*
X1032480Y110784D03*
X1037040Y125107D03*
X1032059Y124663D03*
X1038513Y142862D03*
X1039554Y148717D03*
X1033403Y138838D03*
X1036173Y226320D03*
X1043875Y230556D03*
X1039134Y228646D03*
X1042860Y242078D03*
X1038091Y232971D03*
X1034741Y244571D03*
X1032121Y249108D03*
X1042084Y256394D03*
X1015059Y55513D03*
X1026200Y86012D03*
X1017787Y85731D03*
X1026200Y94374D03*
X1015427Y88801D03*
X1022293Y94279D03*
X1018344Y94351D03*
X1021341Y86046D03*
X1027480Y110784D03*
X1021971Y124283D03*
X1027037Y124879D03*
X1020378Y161306D03*
X1017629Y157370D03*
X1021713Y176665D03*
Y168665D03*
Y196665D03*
X1021826Y186778D03*
X1021713Y192665D03*
X1021745Y204864D03*
Y208864D03*
X1017386Y219379D03*
X1018014Y228631D03*
X1023502Y248371D03*
X1011297Y80581D03*
X1003379Y72615D03*
Y76587D03*
X1004818Y100625D03*
X997837Y97475D03*
X1013480Y103621D03*
X997768Y106186D03*
X1009191Y112083D03*
X1005397Y141247D03*
X1009884Y143518D03*
X1012936Y178560D03*
X997929Y168697D03*
X1012999Y172665D03*
X999017Y191941D03*
X1003029Y192300D03*
X1012346Y190185D03*
X1007071Y192490D03*
X1013139Y207037D03*
X1013205Y212455D03*
X1010506Y221642D03*
X999714Y266114D03*
X994675Y177616D03*
X994939Y256303D03*
X989611Y265701D03*
X994698Y265896D03*
X991246Y281716D03*
X997187Y281982D03*
X987517Y314092D03*
X981843Y464818D03*
X1011284Y68581D03*
X971826Y430187D03*
X972030Y446071D03*
X977327Y462371D03*
X987283Y98551D03*
X990833Y103783D03*
X985595Y147540D03*
X989367Y141247D03*
X996834Y143740D03*
X994214Y148277D03*
X995256Y172190D03*
X947040Y223885D03*
X946482Y255940D03*
X963816Y464419D03*
X979002Y92874D03*
X965723Y90615D03*
X970094Y95236D03*
X970044Y99961D03*
X934678Y125107D03*
X936151Y142862D03*
X937192Y148717D03*
X934477Y211491D03*
X946234Y213390D03*
X942179Y215727D03*
X937438Y213817D03*
X936395Y218142D03*
X933403Y245507D03*
X936962Y249807D03*
X944248Y239844D03*
X934128Y355168D03*
X934464Y358618D03*
X944238Y360828D03*
X934047Y369160D03*
X936175Y364823D03*
X949615Y97667D03*
X960411Y90650D03*
X960161Y95236D03*
X930727Y302571D03*
X923732Y304585D03*
X923311Y349959D03*
X929943Y372600D03*
X940761Y97667D03*
X945011Y95111D03*
X936417Y102495D03*
X930118Y110784D03*
X925118D03*
X924675Y124879D03*
X929697Y124663D03*
X919609Y124283D03*
X931041Y138838D03*
X918016Y161306D03*
X915267Y157370D03*
X907522Y143518D03*
X910977Y243307D03*
Y262205D03*
Y248032D03*
X913288Y372752D03*
X883233Y147540D03*
X887005Y141247D03*
X894472Y143740D03*
X891852Y148277D03*
X895140Y265236D03*
X876200Y86012D03*
X867787Y85731D03*
X865427Y88801D03*
X876200Y94374D03*
X872293Y94279D03*
X868344Y94351D03*
X871341Y86046D03*
X871713Y168665D03*
Y176665D03*
Y196665D03*
Y192665D03*
X871826Y186778D03*
X871745Y204864D03*
Y208864D03*
X867386Y219379D03*
X853379Y76587D03*
Y72615D03*
X854818Y100625D03*
X859191Y112083D03*
X863480Y103621D03*
X862999Y172665D03*
X862936Y178560D03*
X849017Y191941D03*
X857071Y192490D03*
X862346Y190185D03*
X853029Y192300D03*
X863205Y212455D03*
X863139Y207037D03*
X860506Y221642D03*
X866015Y224536D03*
X865059Y55513D03*
X861284Y68581D03*
X861297Y80581D03*
X844939Y256303D03*
X844698Y265896D03*
X839611Y265701D03*
X849714Y266114D03*
X841246Y281716D03*
X847187Y281982D03*
X837283Y98551D03*
X847837Y97475D03*
X847768Y106186D03*
X840833Y103783D03*
X847929Y168697D03*
X844675Y177616D03*
X845256Y172190D03*
X829002Y92874D03*
X820094Y95236D03*
X820044Y99961D03*
X822160Y258880D03*
X822477Y309368D03*
X810411Y90650D03*
X815723Y90615D03*
X810161Y95236D03*
X817456Y305368D03*
Y313368D03*
X809490Y305368D03*
X817100Y319600D03*
X809490Y325368D03*
Y317368D03*
Y321368D03*
X786151Y142862D03*
X787192Y148717D03*
X795768Y227824D03*
X791513Y230556D03*
X786772Y228646D03*
X796374Y238714D03*
X790498Y242078D03*
X785729Y232971D03*
X789722Y256394D03*
X769351Y176665D03*
Y168665D03*
Y192665D03*
X769464Y186778D03*
X769383Y204864D03*
X783811Y226320D03*
X782379Y244571D03*
X779759Y249108D03*
X771140Y248371D03*
X784118Y303962D03*
X772162Y332584D03*
X772859Y347937D03*
X799615Y97667D03*
X790761D03*
X786417Y102495D03*
X769349Y324518D03*
X759029Y328867D03*
X754805Y339559D03*
X759624Y353961D03*
X756086Y377912D03*
X766344D03*
X756086Y386500D03*
X766344Y381912D03*
X755086Y391496D03*
X756174Y397912D03*
X755086Y409000D03*
X773838Y86012D03*
Y94374D03*
X768979Y86046D03*
X784678Y125107D03*
X781041Y138838D03*
X768016Y161306D03*
X735599Y449961D03*
X739316Y458572D03*
X762697Y55513D03*
X758922Y68581D03*
X758935Y80581D03*
X763065Y88801D03*
X765982Y94351D03*
X769931Y94279D03*
X765425Y85731D03*
X761118Y103621D03*
X756829Y112083D03*
X757522Y143518D03*
X765267Y157370D03*
X760637Y172665D03*
X760574Y178560D03*
X754709Y192490D03*
X759984Y190185D03*
X753182Y198671D03*
X769383Y208864D03*
X760843Y212455D03*
X760777Y207037D03*
X758144Y221642D03*
X765024Y219379D03*
X763653Y224536D03*
X741852Y148277D03*
X745567Y168697D03*
X742894Y172190D03*
X742313Y177616D03*
X746655Y191941D03*
X750667Y192300D03*
X742577Y256303D03*
X747352Y266114D03*
X742336Y265896D03*
X744825Y281982D03*
X738884Y281716D03*
X741051Y316389D03*
X749444Y393858D03*
X749606Y384410D03*
X752785Y382047D03*
X753086Y403500D03*
X751086Y398583D03*
X722097Y453881D03*
X731952Y446606D03*
X722097Y446595D03*
X732959Y463479D03*
X733430Y467367D03*
X751017Y76587D03*
Y72615D03*
X752456Y100625D03*
X745475Y97475D03*
X738471Y103783D03*
X745406Y106186D03*
X737005Y141247D03*
X744472Y143740D03*
X733233Y147540D03*
X719798Y258880D03*
X737249Y265701D03*
X723404Y379657D03*
X721900Y384500D03*
X723440Y391496D03*
X734661Y393633D03*
X731511Y381113D03*
X723440Y398583D03*
X732035Y442606D03*
X718338Y305272D03*
X717105Y410964D03*
X717420Y404334D03*
X720996Y442856D03*
X711598Y438323D03*
X719051Y458455D03*
X719612Y451108D03*
X710643Y456335D03*
X711764Y445873D03*
X726640Y92874D03*
X734921Y98551D03*
X708049Y90650D03*
X713361Y90615D03*
X717732Y95236D03*
X717682Y99961D03*
X707799Y95236D03*
X689151Y230556D03*
X693406Y227824D03*
X694012Y238714D03*
X688136Y242078D03*
X690504Y253198D03*
X689486Y339583D03*
X697253Y97667D03*
X692649Y95111D03*
X685353Y396718D03*
X678461Y455981D03*
X675237Y465611D03*
X688399Y97667D03*
X671476Y94374D03*
X684055Y102495D03*
X677756Y110784D03*
X672756D03*
X682316Y125107D03*
X677335Y124663D03*
X683789Y142862D03*
X684830Y148717D03*
X678679Y138838D03*
X681449Y226320D03*
X684410Y228646D03*
X683367Y232971D03*
X677397Y249108D03*
X680017Y244571D03*
X682857Y339477D03*
X687055Y376456D03*
X661761Y382109D03*
X657507Y58013D03*
X656560Y68581D03*
X671476Y86012D03*
X656573Y80581D03*
X660703Y88801D03*
X663620Y94351D03*
X667569Y94279D03*
X663063Y85731D03*
X666617Y86046D03*
X658756Y103621D03*
X654467Y112083D03*
X667247Y124283D03*
X672313Y124879D03*
X665654Y161306D03*
X662905Y157370D03*
X666989Y176665D03*
Y168665D03*
X658275Y172665D03*
X658212Y178560D03*
X657622Y190185D03*
X666989Y196665D03*
Y192665D03*
X667102Y186778D03*
X667021Y204864D03*
Y208864D03*
X658481Y212455D03*
X658415Y207037D03*
X655782Y221642D03*
X662662Y219379D03*
X663290Y228631D03*
X668886Y248371D03*
X640215Y256303D03*
X644990Y266114D03*
X642463Y281982D03*
X648655Y76587D03*
Y72615D03*
X650094Y100625D03*
X643113Y97475D03*
X643044Y106186D03*
X655160Y143518D03*
X642110Y143740D03*
X640532Y172190D03*
X643205Y168697D03*
X644293Y191941D03*
X652347Y192490D03*
X639974Y265896D03*
X634887Y265701D03*
X636522Y281716D03*
X624278Y92874D03*
X632559Y98551D03*
X636109Y103783D03*
X630871Y147540D03*
X634643Y141247D03*
X639490Y148277D03*
X639951Y177616D03*
X604606Y463600D03*
X610999Y90615D03*
X615370Y95236D03*
X615320Y99961D03*
X605437Y95236D03*
X594891Y97667D03*
X605687Y90650D03*
X590287Y95111D03*
X591650Y238714D03*
X592900Y309871D03*
X569938Y378317D03*
X586037Y97667D03*
X581693Y102495D03*
X575394Y110784D03*
X579954Y125107D03*
X581427Y142862D03*
X582468Y148717D03*
X576317Y138838D03*
X579087Y226320D03*
X586789Y230556D03*
X591044Y227824D03*
X582048Y228646D03*
X585774Y242078D03*
X581005Y232971D03*
X577655Y244571D03*
X584998Y256394D03*
X578193Y336391D03*
X584679Y336285D03*
X573479Y374705D03*
X551536Y359223D03*
Y354723D03*
Y350223D03*
Y345723D03*
Y377223D03*
Y372723D03*
Y368223D03*
Y363723D03*
Y381723D03*
X551620Y390723D03*
X553563Y384987D03*
X557973Y55513D03*
X569114Y86012D03*
X558341Y88801D03*
X569114Y94374D03*
X561258Y94351D03*
X565207Y94279D03*
X560701Y85731D03*
X564255Y86046D03*
X570394Y110784D03*
X574973Y124663D03*
X564885Y124283D03*
X569951Y124879D03*
X563292Y161306D03*
X560543Y157370D03*
X564627Y176665D03*
Y168665D03*
Y196665D03*
Y192665D03*
X564740Y186778D03*
X564659Y204864D03*
Y208864D03*
X560300Y219379D03*
X560928Y228631D03*
X575035Y249108D03*
X566416Y248371D03*
X541706Y386223D03*
X533189Y390723D03*
X531953Y385749D03*
X554198Y68581D03*
X554211Y80581D03*
X546293Y76587D03*
Y72615D03*
X547732Y100625D03*
X552105Y112083D03*
X556394Y103621D03*
X540682Y106186D03*
X552798Y143518D03*
X540843Y168697D03*
X555850Y178560D03*
X555913Y172665D03*
X541931Y191941D03*
X555260Y190185D03*
X549985Y192490D03*
X556119Y212455D03*
X556053Y207037D03*
X553420Y221642D03*
X542628Y266114D03*
X530197Y98551D03*
X540751Y97475D03*
X533747Y103783D03*
X532281Y141247D03*
X528509Y147540D03*
X539748Y143740D03*
X537128Y148277D03*
X538170Y172190D03*
X537589Y177616D03*
X537853Y256303D03*
X532525Y265701D03*
X537612Y265896D03*
X534160Y281716D03*
X540101Y281982D03*
X532659Y359557D03*
X526388Y351301D03*
X531612Y354272D03*
X531636Y349057D03*
X528812Y369164D03*
X533211Y364746D03*
X533115Y371856D03*
X530144Y376062D03*
X531953Y380749D03*
X542034Y392209D03*
X512958Y99961D03*
X519638Y314346D03*
X512943Y443071D03*
X520823Y442603D03*
X518240Y459371D03*
X517310Y470045D03*
X522756Y461818D03*
X482636Y256394D03*
X492817Y357111D03*
X491843Y351089D03*
X481724Y373589D03*
Y369089D03*
X490885Y373589D03*
X491053Y365423D03*
X491289Y391589D03*
X481724Y382589D03*
Y378089D03*
X490885Y382570D03*
X490985Y412342D03*
X488438Y418417D03*
X489485Y439903D03*
X485485D03*
X481485Y439900D03*
Y431917D03*
X489485Y431417D03*
X503325Y90650D03*
X508637Y90615D03*
X503075Y95236D03*
X496023Y362913D03*
X497048Y369450D03*
X495750Y377531D03*
X495203Y386890D03*
X503729Y439919D03*
X503682Y448419D03*
X500729Y469905D03*
X496729Y470419D03*
X504729Y469905D03*
X496729Y461919D03*
X504729Y461419D03*
X513008Y95236D03*
X521916Y92874D03*
X492529Y97667D03*
X483675D03*
X487925Y95111D03*
X479331Y102495D03*
X479065Y142862D03*
X480106Y148717D03*
X476725Y226320D03*
X484427Y230556D03*
X488682Y227824D03*
X479686Y228646D03*
X483412Y242078D03*
X478643Y232971D03*
X489288Y238714D03*
X473032Y110784D03*
X468032D03*
X477592Y125107D03*
X462523Y124283D03*
X467589Y124879D03*
X472611Y124663D03*
X473955Y138838D03*
X460930Y161306D03*
X475293Y244571D03*
X472673Y249108D03*
X464054Y248371D03*
X472810Y347995D03*
X472913Y360089D03*
X472608Y352495D03*
X467335Y359944D03*
X472913Y369089D03*
Y373589D03*
X469530Y366754D03*
X472913Y387089D03*
Y391589D03*
Y382589D03*
Y378089D03*
X470796Y394592D03*
X426647Y452987D03*
X421267Y452799D03*
X414910Y448931D03*
X415433Y459170D03*
X425673Y461607D03*
X424876Y471334D03*
X429919Y141247D03*
X437386Y143740D03*
X434766Y148277D03*
X441296Y325061D03*
X436666Y322583D03*
X443424Y332988D03*
X440538Y355372D03*
X435886Y353867D03*
X432270Y431112D03*
X432440Y440101D03*
X438098Y442114D03*
X437835Y435101D03*
X432075Y452718D03*
X438086Y452601D03*
X438078Y447121D03*
X450436Y143518D03*
X458181Y157370D03*
X443480Y344014D03*
X397315Y471560D03*
X405301Y467560D03*
X422473Y22627D03*
X422450Y30483D03*
X422378Y26534D03*
X414145Y27486D03*
X426147Y147540D03*
X414626Y176665D03*
Y168665D03*
Y196665D03*
Y192665D03*
X414739Y186778D03*
X414658Y204864D03*
Y208864D03*
X415129Y325181D03*
X422988Y323627D03*
X426830Y359026D03*
X421413Y359053D03*
X405912Y172665D03*
X405849Y178560D03*
X399984Y192490D03*
X405259Y190185D03*
X406029Y200864D03*
X395942Y192300D03*
X406052Y207037D03*
X403419Y221642D03*
X410299Y219379D03*
X410927Y228631D03*
X410086Y336795D03*
X387852Y256303D03*
X387611Y265896D03*
X382524Y265701D03*
X392627Y266114D03*
X384159Y281716D03*
X390100Y281982D03*
X384173Y379028D03*
X393662Y470382D03*
X385293Y466409D03*
X410789Y22627D03*
X396680Y37543D03*
X408680Y37530D03*
X400714Y45448D03*
X404686D03*
X397731Y100625D03*
X402104Y112083D03*
X406393Y103621D03*
X367564Y456034D03*
Y461034D03*
X388612Y31168D03*
X387948Y27288D03*
X380196Y98551D03*
X390750Y97475D03*
X390681Y106186D03*
X383746Y103783D03*
X387588Y177616D03*
X390842Y168697D03*
X388169Y172190D03*
X391930Y191941D03*
X371915Y92874D03*
X363007Y95236D03*
X365073Y258880D03*
X365559Y354300D03*
X371417Y353820D03*
X377237Y371060D03*
X373264Y379429D03*
X378875Y379088D03*
X366526Y377173D03*
X370486D03*
X366486Y385123D03*
X370160Y391569D03*
X368587Y401066D03*
X339287Y238714D03*
X333411Y242078D03*
X332635Y256394D03*
X347058Y399918D03*
X345050Y454334D03*
X358636Y90615D03*
X353324Y90650D03*
X362957Y99961D03*
X353074Y95236D03*
X359376Y290592D03*
X351132Y322202D03*
X349120Y336100D03*
X351136Y372334D03*
X350486Y377173D03*
X347591Y391533D03*
X349311Y385644D03*
X354486Y385123D03*
X353894Y406060D03*
X350163Y412106D03*
X353320Y454214D03*
X353367Y459330D03*
X333674Y97667D03*
X342528D03*
X337924Y95111D03*
X329330Y102495D03*
X338681Y227824D03*
X334426Y230556D03*
X312263Y324518D03*
X301943Y328867D03*
X299000Y377912D03*
Y386500D03*
X299088Y397912D03*
X322847Y19806D03*
X321840Y14408D03*
X322113Y26187D03*
X316751Y86012D03*
Y94374D03*
X318031Y110784D03*
X323031D03*
X327591Y125107D03*
X322610Y124663D03*
X317588Y124879D03*
X329064Y142862D03*
X330105Y148717D03*
X323954Y138838D03*
X326724Y226320D03*
X329685Y228646D03*
X328642Y232971D03*
X322672Y249108D03*
X325292Y244571D03*
X314053Y248371D03*
X327032Y303962D03*
X318508Y324322D03*
X315944Y332584D03*
X316067Y347937D03*
X312256Y37543D03*
X305610Y55513D03*
X301835Y68581D03*
X301848Y80581D03*
X305978Y88801D03*
X312844Y94279D03*
X308895Y94351D03*
X308338Y85731D03*
X311892Y86046D03*
X299742Y112083D03*
X304031Y103621D03*
X312522Y124283D03*
X300435Y143518D03*
X310929Y161306D03*
X308180Y157370D03*
X303550Y172665D03*
X303487Y178560D03*
X312264Y176665D03*
Y168665D03*
Y196665D03*
Y192665D03*
X312377Y186778D03*
X312296Y204864D03*
Y208864D03*
X303756Y212455D03*
X303690Y207037D03*
X301057Y221642D03*
X307937Y219379D03*
X308565Y228631D03*
X288480Y168697D03*
X285226Y177616D03*
X289568Y191941D03*
X285490Y256303D03*
X290265Y266114D03*
X285249Y265896D03*
X287738Y281982D03*
X286940Y315039D03*
X297719Y339559D03*
X291396Y350223D03*
X292520Y384410D03*
X292358Y393858D03*
X298000Y391496D03*
X295699Y382047D03*
X296000Y403500D03*
X298000Y409000D03*
X294000Y398583D03*
X278827Y444841D03*
X282230Y458572D03*
X265011Y453881D03*
X280220Y448493D03*
X274866Y446606D03*
X275873Y463479D03*
X276344Y467367D03*
X289797Y36735D03*
X284666Y34068D03*
X290113Y23188D03*
X289631Y28281D03*
X293930Y76587D03*
Y72615D03*
X295369Y100625D03*
X288388Y97475D03*
X288319Y106186D03*
X281384Y103783D03*
X287385Y143740D03*
X284765Y148277D03*
X285807Y172190D03*
X276146Y147540D03*
X279918Y141247D03*
X280162Y265701D03*
X281797Y281716D03*
X277575Y395084D03*
X274425Y381500D03*
X274949Y442606D03*
X278784Y435158D03*
X278529Y440489D03*
X250962Y90650D03*
X256274Y90615D03*
X260595Y99961D03*
X260645Y95236D03*
X250712D03*
X262711Y258880D03*
X256475Y422088D03*
X254512Y438323D03*
X261965Y458455D03*
X254678Y445873D03*
X262526Y451108D03*
X277834Y98551D03*
X269553Y92874D03*
X222930Y244571D03*
X233417Y253198D03*
X230842Y313888D03*
X228267Y396718D03*
X221375Y455024D03*
X220349Y465622D03*
X240166Y97667D03*
X235562Y95111D03*
X236319Y227824D03*
X236925Y238714D03*
X231312Y97667D03*
X226968Y102495D03*
X220669Y110784D03*
X225229Y125107D03*
X220248Y124663D03*
X226702Y142862D03*
X227743Y148717D03*
X221592Y138838D03*
X224362Y226320D03*
X232064Y230556D03*
X227323Y228646D03*
X231049Y242078D03*
X226280Y232971D03*
X220310Y249108D03*
X203248Y55513D03*
X199473Y68581D03*
X199486Y80581D03*
X214389Y86012D03*
X203616Y88801D03*
X214389Y94374D03*
X206533Y94351D03*
X210482Y94279D03*
X209530Y86046D03*
X205976Y85731D03*
X201669Y103621D03*
X215669Y110784D03*
X210160Y124283D03*
X215226Y124879D03*
X205818Y157370D03*
X208567Y161306D03*
X209902Y176665D03*
Y168665D03*
Y196665D03*
Y192665D03*
X210015Y186778D03*
X209934Y204864D03*
Y208864D03*
X205575Y219379D03*
X206203Y228631D03*
X211691Y248371D03*
X204675Y382109D03*
X201125Y178560D03*
X186118Y168697D03*
X201188Y172665D03*
X187206Y191941D03*
X195260Y192490D03*
X200535Y190185D03*
X201394Y212455D03*
X201328Y207037D03*
X198695Y221642D03*
X183128Y256303D03*
X187903Y266114D03*
X185376Y281982D03*
X179435Y281716D03*
X170215Y311671D03*
X191568Y76587D03*
Y72615D03*
X193007Y100625D03*
X186026Y97475D03*
X185957Y106186D03*
X197380Y112083D03*
X193586Y141247D03*
X198073Y143518D03*
X175472Y98551D03*
X179022Y103783D03*
X173784Y147540D03*
X177556Y141247D03*
X185023Y143740D03*
X182403Y148277D03*
X182864Y177616D03*
X183445Y172190D03*
X177800Y265701D03*
X182887Y265896D03*
X147520Y463600D03*
X167191Y92874D03*
X153912Y90615D03*
X158283Y95236D03*
X158233Y99961D03*
X129702Y230556D03*
X133957Y227824D03*
X124961Y228646D03*
X128687Y242078D03*
X123918Y232971D03*
X134044Y246874D03*
X120568Y244571D03*
X127911Y256394D03*
X126131Y359511D03*
X125753Y365856D03*
X137804Y97667D03*
X148600Y90650D03*
X148350Y95236D03*
X134563Y238714D03*
X117886Y124663D03*
X112864Y124879D03*
X107798Y124283D03*
X119230Y138838D03*
X106205Y161306D03*
X107540Y176665D03*
Y168665D03*
Y196665D03*
Y192665D03*
X107653Y186778D03*
X107572Y204864D03*
Y208864D03*
X103213Y219379D03*
X117948Y249108D03*
X109329Y248371D03*
X128950Y97667D03*
X133200Y95111D03*
X124606Y102495D03*
X122867Y125107D03*
X124340Y142862D03*
X125381Y148717D03*
X122000Y226320D03*
X95711Y143518D03*
X103456Y157370D03*
X98826Y172665D03*
X98763Y178560D03*
X92898Y192490D03*
X98173Y190185D03*
X98966Y207037D03*
X99032Y212455D03*
X96333Y221642D03*
X103841Y228631D03*
X100120Y377898D03*
X98255Y374510D03*
X100066Y381976D03*
X118307Y110784D03*
X113307D03*
X73110Y98551D03*
X77804Y95879D03*
X76660Y103783D03*
X75194Y141247D03*
X71422Y147540D03*
X82661Y143740D03*
X80041Y148277D03*
X80502Y177616D03*
X81083Y172190D03*
X83756Y168697D03*
X84844Y191941D03*
X80766Y256303D03*
X75438Y265701D03*
X85541Y266114D03*
X80525Y265896D03*
X83014Y281982D03*
X77073Y281716D03*
X27340Y230556D03*
X31595Y227824D03*
X32201Y238714D03*
X23844Y239299D03*
X21556Y232971D03*
X26325Y262078D03*
X25549Y256394D03*
X31682Y266874D03*
X29116Y281129D03*
X25549Y276394D03*
X26629Y295619D03*
X45988Y90512D03*
X51550Y90615D03*
X64829Y92874D03*
X55871Y99961D03*
X55921Y95236D03*
X14807Y282181D03*
X15586Y269108D03*
X15499Y288542D03*
X32350Y63562D03*
Y59562D03*
Y67562D03*
X26588Y97667D03*
X35442D03*
X22439Y102495D03*
X26565Y177448D03*
X11011Y79720D03*
X8786Y88425D03*
X14264Y94236D03*
X10292D03*
X12786Y87903D03*
X18000Y90000D03*
X18298Y102141D03*
X10131Y115473D03*
X15143Y115581D03*
X14996Y133034D03*
X11442Y132719D03*
X19855Y133000D03*
Y141362D03*
X11999Y141415D03*
X15948Y141267D03*
X16909Y153263D03*
X12247Y166341D03*
X17313Y166937D03*
X21909Y153263D03*
X22335Y166721D03*
X16709Y175943D03*
X19638Y226320D03*
X22599Y228646D03*
X18206Y244571D03*
X15586Y249108D03*
X13715Y259381D03*
X18206Y264571D03*
X1756894Y472020D03*
X1756954Y477318D03*
X1768575Y475560D03*
X1764906Y474382D03*
X1777061Y475560D03*
X1790061Y474513D03*
X1299867Y477318D03*
X1299807Y472020D03*
X1311488Y475560D03*
X1307819Y474382D03*
X1319974Y475560D03*
X1332974Y474513D03*
X954182Y481467D03*
X958736Y482165D03*
X959816Y472905D03*
X963816D03*
X976397Y473045D03*
X393646Y474382D03*
X385634Y472020D03*
X385694Y477318D03*
X397315Y475560D03*
X405801D03*
X418801Y474513D03*
X497095Y481467D03*
X501649Y482165D03*
X40009Y481467D03*
X45643Y472905D03*
X49643D03*
X1093841Y371335D03*
X363893Y946863D03*
X1103432Y340544D03*
X1303000Y326692D03*
X1787674Y303130D03*
X1455013Y43128D03*
X464795Y1000647D03*
X201305Y200864D03*
X445949Y141247D03*
X295948D03*
X1098845Y353404D03*
X1480702Y368516D03*
X945018Y276051D03*
X903035Y141247D03*
X650673D03*
X548311D03*
X1611327Y735973D03*
X1501500Y321000D03*
X1486860Y327200D03*
X1501000Y317500D03*
X1615913Y692245D03*
X1578000Y678776D03*
X1624000Y760900D03*
X1611873Y795127D03*
X1609500Y776100D03*
X1630327Y774627D03*
X1620100Y738300D03*
X1606709Y819165D03*
X1611027Y722427D03*
X1611627Y780327D03*
X1612573Y761427D03*
X1635283Y728117D03*
X1613117Y828117D03*
X1620500Y723200D03*
X1616683Y744517D03*
X1628200Y711417D03*
X1620600Y705900D03*
X1612800D03*
X1628343Y747288D03*
X1606190Y803774D03*
X471876Y937236D03*
X74700Y842890D03*
X1802363Y989660D03*
X1786863Y985060D03*
X69049Y847718D03*
X53549Y843118D03*
X56049Y827218D03*
X86289Y822088D03*
X65549Y850718D03*
X1802000Y892447D03*
X488041Y1020440D03*
X1780016Y874400D03*
X1746884Y884649D03*
X1746600Y935100D03*
X1750915Y902055D03*
X1749267Y918413D03*
X1789537Y930498D03*
X1746897Y879199D03*
X1741800Y917900D03*
X1793474Y930374D03*
X1775904Y924546D03*
X1751200Y931100D03*
X1778047Y916120D03*
X1797365Y930761D03*
X379800Y769200D03*
X407000Y784700D03*
X430600Y797400D03*
X278739Y936439D03*
X397900Y789000D03*
X434100Y797400D03*
X372400Y746300D03*
X278400Y890839D03*
X406200Y741300D03*
X238400Y836900D03*
X275400Y864400D03*
X246311Y819000D03*
X469300Y799500D03*
X429253Y759847D03*
X279261Y926339D03*
X710196Y707562D03*
X275400Y899400D03*
X481742Y657477D03*
X557847Y744599D03*
X371436Y791188D03*
X1154652Y791056D03*
X721163Y738981D03*
X564362Y757979D03*
X520833Y773389D03*
X513551Y773203D03*
X567428Y750145D03*
X524598Y753387D03*
X573778Y747437D03*
X520549Y761982D03*
X509096Y753072D03*
X703600Y702212D03*
X494465Y657772D03*
X496070Y665976D03*
X488765Y667224D03*
X703680Y697094D03*
X713200Y699676D03*
X722473Y693718D03*
X716623Y702463D03*
X570038Y752339D03*
X536087Y702364D03*
X1808014Y984832D03*
X86367Y848086D03*
X423963Y625778D03*
X1018015Y751565D03*
X863116Y200864D03*
X556030D03*
X406118Y212455D03*
X760754Y200864D03*
X303667D03*
X1124075Y192665D03*
Y196665D03*
X90000Y871389D03*
X84367Y878286D03*
X76528Y878533D03*
X66342Y880067D03*
X113601Y881266D03*
X110887Y884000D03*
X122887D03*
X83079Y888515D03*
X74028Y889065D03*
X127067Y891495D03*
X123387Y892000D03*
X64175Y897500D03*
X76203Y897910D03*
X80339Y897943D03*
X72035Y898346D03*
X87853Y899220D03*
X103692Y900295D03*
X91387Y905295D03*
X71528Y913190D03*
X80593Y946082D03*
X76332Y953421D03*
X100200Y988800D03*
X95836Y988813D03*
X103836D03*
X107836D03*
X95836Y997860D03*
X99836D03*
X103836D03*
X107836D03*
X87632Y1007522D03*
X105971Y1025745D03*
X120579Y1021954D03*
X103184Y1177691D03*
X110409Y1024094D03*
X103124Y1102091D03*
Y1114691D03*
Y1127291D03*
Y1152491D03*
X94586Y1023900D03*
X91765Y1018307D03*
X97609Y1018469D03*
X100594Y1035088D03*
X97247Y1030568D03*
X90450Y1033542D03*
X103124Y1165091D03*
X84679Y1018368D03*
X102761Y1096233D03*
X119836Y988813D03*
X127836D03*
X123836D03*
X131836D03*
X135836D03*
X143836D03*
X151836D03*
X139836D03*
X147836D03*
X155836Y997860D03*
X159836Y988813D03*
X130434Y1144964D03*
X130380Y1155491D03*
Y1117691D03*
Y1130291D03*
X133870Y1142891D03*
Y1155491D03*
X153693Y1051037D03*
X160547Y1049283D03*
X160807Y1043955D03*
X159228Y1065613D03*
X155513Y1065148D03*
X145516Y1012354D03*
X148534Y1046476D03*
X146595Y1053457D03*
X144640Y1039439D03*
X145516Y1024954D03*
X341266Y1171956D03*
X335190Y1173065D03*
X342009Y1176100D03*
X355215Y1223170D03*
X351940Y1219895D03*
X349276Y1217228D03*
X346387Y1199256D03*
X350402Y1201043D03*
X354398D03*
X358368D03*
X348125Y1180175D03*
X348432Y1187215D03*
X361792Y1187310D03*
X357057Y1179542D03*
X357950Y1167768D03*
X352931D03*
X366521Y1208993D03*
X369839Y1218940D03*
X366402Y1200969D03*
X362402Y1201039D03*
X368917Y1195419D03*
X366222Y1180235D03*
X366429Y1185238D03*
X368661Y1182649D03*
X366133Y1170767D03*
X372501Y1123695D03*
X365748Y1134325D03*
X361621Y1134729D03*
X339251Y1138130D03*
X352545Y1142666D03*
X336755Y1143489D03*
X340500Y1147500D03*
X349700Y1148000D03*
X360877Y1157404D03*
X357947Y1159455D03*
X366133Y1162817D03*
X569186Y787332D03*
X582100Y787600D03*
X586060Y793145D03*
X550420Y793743D03*
X544515Y793875D03*
X540578Y793889D03*
X583501Y800831D03*
X545741Y804149D03*
X532304Y806649D03*
X544741Y809649D03*
X561401Y811242D03*
X553871Y811298D03*
X504341Y812040D03*
X567559Y812850D03*
X507095Y814784D03*
X544878Y816309D03*
X540807Y816556D03*
X579758Y817753D03*
X562400Y818900D03*
X582737Y819831D03*
X556741Y820149D03*
X521565Y820931D03*
X559741Y822149D03*
X531313Y822693D03*
X544741Y823149D03*
X548464Y823156D03*
X581158Y823473D03*
X509665Y824512D03*
X522481Y824661D03*
X506246Y824689D03*
X517702Y826600D03*
X531313Y826630D03*
X541129Y828335D03*
X573300Y829600D03*
X556326Y829989D03*
X532316Y833649D03*
X517832Y834558D03*
X536641Y838649D03*
X541129Y838865D03*
X560813Y840574D03*
X549241Y841388D03*
X524741Y845149D03*
X530741D03*
X520720Y846133D03*
X559196Y846296D03*
X545981Y846389D03*
X503741Y846830D03*
X527733Y847026D03*
X534632Y849830D03*
X545237Y850319D03*
X548665Y850399D03*
X557836Y851669D03*
X561134Y869291D03*
X546940Y871389D03*
X508248Y873319D03*
X520870Y874694D03*
X508049Y877789D03*
X540968Y878360D03*
X533468Y878533D03*
X523272Y880067D03*
X509791Y881932D03*
X579827Y884000D03*
X538468Y888033D03*
X530968Y888283D03*
X509428Y888390D03*
X580327Y892000D03*
X564165Y894411D03*
X559214Y897425D03*
X521115Y897500D03*
X533143Y897910D03*
X537279Y897943D03*
X528975Y898346D03*
X544793Y899220D03*
X509673Y900295D03*
X560814Y901022D03*
X583065Y903294D03*
X579251Y903364D03*
X509017Y905295D03*
X548327D03*
X586136Y908935D03*
X582706Y908959D03*
X545144Y909025D03*
X516902Y910251D03*
X511025Y911443D03*
X531076Y913190D03*
X576003Y935107D03*
X565003Y936807D03*
X568503D03*
X516256Y939157D03*
X577903Y940907D03*
X573103Y941307D03*
X514886Y952189D03*
X527879D03*
X577303Y954507D03*
X581903D03*
X591754Y956979D03*
X570603Y957207D03*
X562328Y957307D03*
X503144Y957934D03*
X552238Y959102D03*
X530473Y961728D03*
X586103Y961807D03*
X499595Y963963D03*
X528674Y964851D03*
X597556Y965829D03*
X493050Y976078D03*
X489163Y977163D03*
X506702Y978947D03*
X503933Y981392D03*
X509471Y981608D03*
X552923Y988813D03*
X556923D03*
X560923D03*
X564923D03*
X568923D03*
X572923D03*
X576923D03*
X580923D03*
X584923D03*
X588923D03*
X592923D03*
X596923D03*
X600923D03*
X604923D03*
X608923D03*
X616923D03*
X552923Y997860D03*
X556923D03*
X560923D03*
X564923D03*
X568923D03*
X572923D03*
X576923D03*
X580923D03*
X584923D03*
X588923D03*
X592923D03*
X596923D03*
X600923D03*
X604923D03*
X608923D03*
X612923D03*
X616923D03*
X544719Y1007522D03*
X568362Y1008262D03*
X571857Y1009354D03*
X577666D03*
X581166D03*
X568362Y1011762D03*
X599113Y1012354D03*
X602603D03*
X545094Y1013678D03*
X571857Y1016827D03*
X577704D03*
X592634Y1234921D03*
X594183Y1220068D03*
X583520Y1230407D03*
X586502Y1227300D03*
X593519Y1224472D03*
X592885Y1229402D03*
X575620Y1207737D03*
X563673Y1204932D03*
X560211Y1185164D03*
X566058D03*
X569520Y1177691D03*
X566020D03*
X560211D03*
X566058Y1172564D03*
X560211D03*
X569520Y1165091D03*
X560211D03*
X566020D03*
X569882Y1223749D03*
X564890Y1218169D03*
X569135Y1214372D03*
X584024Y1209607D03*
X578298Y1215195D03*
X587467Y1180691D03*
Y1168091D03*
X590957D03*
Y1180691D03*
X560211Y1134764D03*
X566058D03*
X560211Y1139891D03*
X566020D03*
X569520D03*
X587467Y1142891D03*
X590957D03*
X560211Y1147364D03*
X566058D03*
X560211Y1152491D03*
X566020D03*
X569520D03*
X587467Y1155491D03*
X590957D03*
X560211Y1159964D03*
X566058D03*
X587467Y1105091D03*
Y1117691D03*
X560211Y1109564D03*
X566058D03*
X560211Y1122164D03*
X566058D03*
X556493Y1118351D03*
X607993Y1036920D03*
X619086Y1056453D03*
X610780Y1051037D03*
X617634Y1049283D03*
X617894Y1043955D03*
X612955Y1062941D03*
X602603Y1024954D03*
X599113D03*
X604405Y1034870D03*
X606434Y1041904D03*
X581166Y1021954D03*
X577666D03*
X577704Y1029427D03*
X567484Y1024003D03*
X571857Y1029427D03*
X901739Y1091346D03*
X902389Y1081764D03*
X908799Y1088659D03*
X908278Y1083484D03*
X901694Y1095940D03*
X908799Y1100659D03*
X902353Y1104333D03*
X897056Y1091391D03*
X887862Y1088067D03*
X894004Y1081231D03*
X891055Y1095407D03*
X897056Y1095984D03*
X884906Y1102760D03*
X884890Y1098724D03*
X892856Y1102760D03*
X863334Y1009393D03*
X828385Y1120599D03*
X822006Y1130208D03*
X825335Y1137129D03*
X819026Y1128137D03*
X823220Y1162817D03*
Y1170767D03*
X818879Y1187310D03*
X823309Y1180235D03*
X823516Y1185238D03*
X823487Y1193019D03*
X819487D03*
X809632Y1142666D03*
X794716Y1186071D03*
X817964Y1157404D03*
X815034Y1159455D03*
X810018Y1167768D03*
X815037D03*
X814160Y1178240D03*
X814170Y1185205D03*
X805212Y1180175D03*
X805519Y1187215D03*
X815487Y1193019D03*
X811487D03*
X788600Y1006923D03*
X796338Y1138130D03*
X797160Y1146609D03*
X799020Y1175975D03*
X809393Y1187252D03*
X743062Y1004460D03*
X745673Y1007009D03*
X799631Y1025440D03*
X803673D03*
X798542Y1188345D03*
X795631Y1025440D03*
X806787Y1148000D03*
X897815Y1078042D03*
X901366Y1078069D03*
X849996Y1091073D03*
X850023Y1095179D03*
X793842Y1143384D03*
X798353Y1172011D03*
X829617Y939583D03*
X891367Y941126D03*
X909166Y994188D03*
X912690Y994350D03*
X900983Y940895D03*
X909811Y962400D03*
X903759Y951358D03*
X882763Y933472D03*
X872126Y934766D03*
X874066Y977928D03*
X865973Y978187D03*
X878976Y994020D03*
X853030Y934690D03*
X858601Y934505D03*
X867096Y935963D03*
X870209Y949384D03*
X851925Y951350D03*
X842856Y949146D03*
X835431Y977775D03*
X836423Y964669D03*
X824414Y939655D03*
X828964Y977780D03*
X825670Y964671D03*
X736000Y864266D03*
X742407Y988452D03*
X732713Y853890D03*
X724707Y893143D03*
X728692Y886653D03*
X736452Y890548D03*
X728503Y891692D03*
X722789Y927095D03*
X732306Y942682D03*
X720271Y931730D03*
X727116Y959326D03*
X733798Y950186D03*
X728846Y948331D03*
X913005Y969605D03*
X918265Y969745D03*
X816519Y931147D03*
X823552Y930700D03*
X832423Y964669D03*
X824168Y949538D03*
X865830Y961600D03*
X778205Y622912D03*
X781429Y545017D03*
X777708Y553287D03*
X806148Y1383715D03*
Y1375208D03*
X816648Y1377608D03*
X947308Y1325035D03*
X949970Y1321749D03*
X1007850Y1368835D03*
X931159Y1379427D03*
Y1383227D03*
X931137Y1375878D03*
X931199Y1371951D03*
X980166Y1373622D03*
X1008452Y1376752D03*
X1008312Y1363533D03*
X998600Y1369200D03*
X988784Y1361974D03*
X1008483Y1372734D03*
X1019391Y1377061D03*
X1021623Y1373216D03*
X985448Y1398271D03*
X998600Y1373400D03*
X927193Y1361547D03*
X980203Y1377559D03*
X980139Y1381496D03*
Y1393308D03*
X980047Y1397245D03*
X920255Y1383264D03*
X904177Y1359955D03*
X999283Y1377400D03*
X997401Y1381200D03*
X998643Y1398271D03*
X876622Y293721D03*
X869924Y305368D03*
X877977Y309368D03*
X869924Y313368D03*
X877977D03*
Y325368D03*
Y317368D03*
Y321368D03*
X869924D03*
Y328722D03*
X870413Y342791D03*
X869924Y333722D03*
X877977Y333368D03*
Y329368D03*
X863430Y309368D03*
Y316970D03*
X863114Y324505D03*
X863040Y330140D03*
X861770Y343006D03*
X858169Y495032D03*
X941872Y440942D03*
X933424Y458455D03*
X933161Y451442D03*
X933404Y463462D03*
X933412Y468942D03*
X927766Y456442D03*
X927596Y447453D03*
X921973Y469328D03*
X927401Y469059D03*
X916593Y469140D03*
X897736Y383125D03*
X910236Y465272D03*
X896592Y358369D03*
Y354369D03*
X888812Y357372D03*
X896592Y374369D03*
X891251Y387484D03*
X890553Y392038D03*
X868086Y373750D03*
X876736Y383125D03*
X877909Y391731D03*
X880736Y383125D03*
X882925Y391099D03*
X872736Y391754D03*
X867586Y393000D03*
Y385000D03*
X869342Y407627D03*
X868586Y398500D03*
X855017Y411969D03*
X863086Y374500D03*
X860586Y383000D03*
X861235Y394000D03*
X864086Y384000D03*
X861468Y483303D03*
Y487303D03*
X869454Y479303D03*
X869954Y487303D03*
X882954Y486256D03*
X891454Y486303D03*
X910759Y475511D03*
X928999Y477948D03*
X920999D03*
X924999D03*
X903959Y1207823D03*
X906784Y1216607D03*
X909077Y1232724D03*
X894713Y1210419D03*
X898878Y1214182D03*
X899286Y1219469D03*
X892532Y1220112D03*
X897169Y1225259D03*
X875321Y1207654D03*
X906309Y1226647D03*
X910633Y1222799D03*
X986600Y717641D03*
X965774Y706907D03*
X947556Y699550D03*
X956023Y706907D03*
X935281Y680945D03*
X913998Y597103D03*
X917811Y544325D03*
X923642Y561578D03*
X923453Y569578D03*
X923599Y581578D03*
X913728Y550495D03*
X914296Y558143D03*
X908846Y560124D03*
X898207Y599891D03*
X910789Y598726D03*
X892931Y534093D03*
X886549Y553963D03*
X887417Y566713D03*
X891673Y600049D03*
X895933Y609696D03*
X891933Y618143D03*
X876949Y571419D03*
X881131Y577349D03*
X881476Y588202D03*
X885556Y543664D03*
X899407Y560019D03*
X988240Y1023968D03*
X966366Y1081764D03*
X972255Y1083484D03*
X972776Y1088659D03*
X966330Y1104333D03*
X972776Y1100659D03*
X967936Y1207823D03*
X970761Y1216607D03*
X958690Y1210419D03*
X963263Y1219469D03*
X962855Y1214182D03*
X956509Y1220112D03*
X961146Y1225259D03*
X957981Y1081231D03*
X951839Y1088067D03*
X956833Y1102760D03*
X962255Y1136426D03*
X939298Y1207654D03*
X1058155Y887635D03*
X1050009Y988813D03*
X1046009D03*
X1054009D03*
X1037709Y886209D03*
X1038010Y902565D03*
X1042009Y988813D03*
X1054900Y879321D03*
X1018419Y917575D03*
X1029570Y917718D03*
X1022346Y917669D03*
X1009564Y988874D03*
X1001805Y1007522D03*
X999879Y998507D03*
X983227Y968565D03*
X965671Y982191D03*
X949671Y977921D03*
X957671D03*
X953671Y982191D03*
X949671Y991564D03*
X953671D03*
X961671D03*
X945671Y982191D03*
X1060698Y931619D03*
X1065823Y988773D03*
X1062009Y988813D03*
X1070009D03*
X1069607Y980131D03*
X1066009Y980330D03*
X1058009Y988813D03*
X1070009Y997860D03*
X1074009Y988813D03*
X1050295Y891100D03*
X1004994Y955372D03*
X1004953Y923995D03*
X1008935Y924007D03*
X1022604Y290262D03*
X989992Y290755D03*
X993992D03*
X997992D03*
X1004635Y300276D03*
X1008635D03*
X1041496D03*
X1010499Y309062D03*
X1002580Y309619D03*
X993132Y310942D03*
X1030220Y313554D03*
X1004933Y314535D03*
X1001105Y318006D03*
X1004544Y318050D03*
X1041783Y321114D03*
X998667Y322239D03*
X1021451Y322879D03*
X1026032Y322906D03*
X1003181Y323057D03*
X1013354Y323362D03*
X1013327Y327453D03*
X1003076Y332496D03*
X1013318Y333190D03*
X997921Y333654D03*
X1031377Y333671D03*
X1042948Y333696D03*
X1013313Y339909D03*
X1046674Y340031D03*
X1043106Y340230D03*
X1022845Y340944D03*
X983717Y341665D03*
X989630Y343862D03*
X1009770Y344486D03*
X997020Y345354D03*
X983956Y346652D03*
X1045966Y346808D03*
X1000420Y348954D03*
X988631Y349496D03*
X1031259Y350427D03*
X1020406Y350772D03*
X996024Y352132D03*
X981719Y352217D03*
X993026Y353813D03*
X1000420Y353954D03*
X984045Y366559D03*
X988045D03*
X992045D03*
X986373Y370467D03*
X1062098Y603600D03*
Y619600D03*
Y623600D03*
X1063642Y634190D03*
X1066931Y645389D03*
X1055885Y554555D03*
X1061693Y463600D03*
X1012188Y443421D03*
X1017619Y932122D03*
X1023319Y937922D03*
X1019519D03*
X1018919Y951522D03*
X1023519D03*
X1031219Y949922D03*
X1033370Y953994D03*
X1027719Y958822D03*
X1008759Y1023900D03*
X1005938Y1018307D03*
X1002652Y1023731D03*
X1017297Y1152491D03*
Y1127291D03*
Y1139891D03*
Y1114691D03*
Y1102091D03*
X1025448Y1011762D03*
X1024570Y1024003D03*
X1011782Y1016591D03*
X1025448Y1008262D03*
X1026009Y997860D03*
X1018009D03*
X1022009D03*
X1026009Y988813D03*
X1017297Y1177691D03*
Y1165091D03*
X1034752Y1021954D03*
X1028943Y1009354D03*
X1034752D03*
X1034009Y997860D03*
X1030009D03*
Y988813D03*
X1034009D03*
X1014767Y1035088D03*
X1018009Y980356D03*
X1021924Y980456D03*
X1018009Y988813D03*
X1022009D03*
X1048043Y1155491D03*
Y1142891D03*
X1044553Y1117691D03*
Y1130291D03*
Y1142891D03*
Y1155491D03*
X1059689Y1024954D03*
X1057212Y1040356D03*
X1059689Y1012354D03*
X1067866Y1051037D03*
X1071348Y1050503D03*
X1076868Y1047293D03*
X1076577Y1041332D03*
X1275788Y1124088D03*
X1282421Y1137129D03*
X1275050Y1157404D03*
X1272120Y1159455D03*
X1280306Y1162817D03*
Y1170767D03*
X1275965Y1187232D03*
X1280602Y1185238D03*
X1280395Y1180235D03*
X1276573Y1193019D03*
X1280573D03*
X1272573D03*
X1272541Y1201043D03*
X1276575Y1201039D03*
X1280575Y1200969D03*
X1284198Y1218754D03*
X1280694Y1208993D03*
X1266718Y1142666D03*
X1267104Y1167768D03*
X1272123D03*
X1271246Y1178240D03*
X1271256Y1185205D03*
X1262605Y1187215D03*
X1262298Y1180175D03*
X1268573Y1193019D03*
X1264573D03*
X1268571Y1201043D03*
X1263449Y1217228D03*
X1266113Y1219895D03*
X1269388Y1223170D03*
X1253424Y1138130D03*
X1254200Y1146600D03*
X1256218Y1175987D03*
X1249363Y1166065D03*
X1263873Y1148000D03*
X1249363Y1173065D03*
X1251802Y1186071D03*
X1307167Y1245696D03*
X1260800Y1191096D03*
X1255439Y1172008D03*
X1250928Y1142828D03*
X1241629Y550065D03*
X1190968Y848703D03*
X1190213Y856816D03*
X1187431Y868340D03*
X1192431Y868620D03*
X1185058Y883475D03*
X1192152Y884399D03*
X1181654Y894671D03*
X1190210Y900909D03*
X1192367Y903785D03*
X1187151Y921000D03*
X1191151Y936296D03*
X1182000Y936500D03*
X1197173Y940645D03*
X1189219Y940703D03*
X1193219D03*
X1196352Y951033D03*
X1191219Y967757D03*
X1198644Y985289D03*
X1191928Y987314D03*
X1195757Y988131D03*
X1202028Y998349D03*
X1196300Y998600D03*
X1203419Y1011161D03*
X1201800Y1019431D03*
X1252148Y1026223D03*
X1246300Y1027800D03*
X1421238Y1301712D03*
X1417711Y1301729D03*
X1410817Y1305417D03*
X1385052Y1303139D03*
X1389052D03*
X1318287Y1295381D03*
Y1291381D03*
X1480193Y1177691D03*
X1474384D03*
X1480231Y1185164D03*
X1474384D03*
X1483693Y1177691D03*
X1505130Y1180691D03*
X1480231Y1134764D03*
X1474384D03*
X1501640Y1142891D03*
X1480231Y1147364D03*
X1474384D03*
X1505130Y1142891D03*
X1483693Y1139891D03*
X1480193D03*
X1474384D03*
X1501640Y1155491D03*
X1480231Y1159964D03*
X1474384D03*
X1505130Y1155491D03*
X1483693Y1152491D03*
X1480193D03*
X1474384D03*
X1480231Y1172564D03*
X1474384D03*
X1505130Y1168091D03*
X1483693Y1165091D03*
X1480193D03*
X1474384D03*
X1501640Y1168091D03*
Y1180691D03*
X1489793Y1207737D03*
X1498197Y1209607D03*
X1492471Y1215195D03*
X1484055Y1223749D03*
X1477846Y1204932D03*
X1483308Y1214372D03*
X1479063Y1218169D03*
X1500675Y1227300D03*
X1507058Y1229402D03*
X1508356Y1220068D03*
X1507692Y1224472D03*
X1506807Y1234921D03*
X1497693Y1230407D03*
X1491425Y842425D03*
X1504938Y859711D03*
X1500353Y859855D03*
X1473489Y861354D03*
X1512712Y867418D03*
X1474883Y868206D03*
X1435082Y869475D03*
X1461113Y871389D03*
X1488138Y872839D03*
X1482387Y872940D03*
X1439891Y873821D03*
X1500638Y873839D03*
X1435043Y874694D03*
X1488138Y878339D03*
X1482566Y882154D03*
X1482195Y885807D03*
X1452641Y888033D03*
X1457218Y888764D03*
X1473433Y891043D03*
X1445367Y891888D03*
X1441223Y891957D03*
X1413500Y892000D03*
X1494954Y895264D03*
X1417081Y896000D03*
X1473387Y897425D03*
X1451286Y898549D03*
X1439103Y898564D03*
X1447261Y898571D03*
X1443231Y899006D03*
X1502158Y899479D03*
X1413500Y900000D03*
X1435745Y901500D03*
X1413500Y904000D03*
X1423190Y905295D03*
X1402187Y908270D03*
X1429059Y908579D03*
X1504208Y909740D03*
X1426085Y910281D03*
X1413733Y911137D03*
X1480343Y914776D03*
X1470925Y920575D03*
X1515179Y921094D03*
X1521085D03*
X1509274Y921226D03*
X1505337Y921240D03*
X1487240Y924453D03*
X1484824Y927324D03*
X1497063Y934000D03*
X1435516Y936000D03*
X1461888Y936055D03*
X1424897Y936777D03*
X1416802Y936845D03*
X1429907Y936998D03*
X1509500Y937000D03*
X1522209Y937846D03*
X1501812Y938397D03*
X1483324Y939324D03*
X1496072Y940201D03*
X1509500Y944138D03*
X1516500Y947500D03*
X1521500D03*
X1448137Y949440D03*
X1509500Y950500D03*
X1487240Y952012D03*
X1480414Y952214D03*
X1529128Y952978D03*
X1496072Y953981D03*
X1462000Y957000D03*
X1521085Y957340D03*
X1512161Y957541D03*
X1458202Y960288D03*
X1497075Y961000D03*
X1479441Y961941D03*
X1430839Y965546D03*
X1482237Y966028D03*
X1457937Y966712D03*
X1525583Y968500D03*
X1479196Y970000D03*
X1511000Y970500D03*
X1489500Y972500D03*
X1495500D03*
X1530767Y972981D03*
X1476500Y974000D03*
X1525005Y974323D03*
X1480414Y975064D03*
X1498973Y975443D03*
X1457352Y976277D03*
X1441088Y976409D03*
X1519863Y977637D03*
X1530594Y979952D03*
X1471096Y980330D03*
X1475096D03*
X1467096Y988813D03*
X1471296D03*
X1475096D03*
X1479096D03*
X1483096D03*
X1487096D03*
X1491096D03*
X1495096D03*
X1499096D03*
X1503096D03*
X1507096D03*
X1511096D03*
X1515096D03*
X1519096D03*
X1523096D03*
X1531096D03*
X1459519Y989432D03*
X1407265Y989465D03*
X1383162Y991829D03*
X1416618Y992307D03*
X1389192Y992568D03*
X1381519Y996280D03*
X1420740Y996766D03*
X1428864D03*
X1412698Y997590D03*
X1527096Y997860D03*
X1394885Y999941D03*
X1378938Y1000586D03*
X1428740Y1000766D03*
X1487266Y1002046D03*
X1475062Y1002453D03*
X1392031Y1004375D03*
X1373534Y1004680D03*
X1490235Y1004816D03*
X1435669Y1005366D03*
X1475062Y1008300D03*
X1412609Y1008766D03*
X1420740D03*
X1440869Y1010256D03*
X1420740Y1012266D03*
X1373534Y1012325D03*
X1513286Y1012354D03*
X1412759Y1016266D03*
X1428740D03*
X1491877Y1016827D03*
X1357765Y1019766D03*
X1361265D03*
X1428823Y1020266D03*
X1402215Y1020440D03*
X1522904Y1021256D03*
X1365314Y1021793D03*
X1456280Y1023405D03*
X1513286Y1024954D03*
X1526810Y1025090D03*
X1357265Y1026266D03*
X1435197Y1028372D03*
X1365049Y1028416D03*
X1486030Y1029427D03*
X1491877D03*
X1373874Y1032266D03*
X1384784Y1033783D03*
X1357265Y1034266D03*
X1503572Y1034538D03*
X1522099Y1035521D03*
X1373874Y1035716D03*
X1399807Y1036155D03*
X1312873Y1036543D03*
X1320549Y1037876D03*
X1385929Y1038665D03*
X1315756Y1039344D03*
X1399852Y1039779D03*
X1322773Y1040599D03*
X1521939Y1040818D03*
X1532067Y1041832D03*
X1315606Y1042825D03*
X1389762Y1043055D03*
X1531947Y1046212D03*
X1385152Y1046591D03*
X1531961Y1050849D03*
X1524953Y1051037D03*
X1517855Y1053457D03*
X1531993Y1056453D03*
X1531546Y1062769D03*
X1392086Y1092743D03*
X1501640Y1105091D03*
X1410546Y1106298D03*
X1442674Y1106365D03*
X1474384Y1109564D03*
X1480231D03*
X1439699Y1110092D03*
X1501640Y1117691D03*
X1471374Y1118654D03*
X1474384Y1122164D03*
X1480231D03*
X1712526Y1171950D03*
X1712715Y1188500D03*
X1708889Y1189221D03*
X1721660Y1193019D03*
X1725660D03*
X1719385Y1180175D03*
X1719692Y1187215D03*
X1728343Y1185205D03*
X1713239Y1176038D03*
X1724191Y1167768D03*
X1737660Y1193019D03*
X1729660D03*
X1733660D03*
X1737482Y1180235D03*
X1737689Y1185238D03*
X1733052Y1187310D03*
X1728333Y1178240D03*
X1729210Y1167768D03*
X1737393Y1170767D03*
Y1162817D03*
X1729207Y1159455D03*
X1732137Y1157404D03*
X1720960Y1148000D03*
X1711333Y1146609D03*
X1708015Y1142700D03*
X1723805Y1142666D03*
X1710511Y1138130D03*
X1739508Y1137129D03*
X1815865Y1133356D03*
X1830915Y1109146D03*
X1810310Y1104819D03*
X1800813Y1103246D03*
X1792863D03*
X1764744Y1101930D03*
X1816756Y1101145D03*
X1792847Y1099210D03*
X1764744Y1097879D03*
X1805013Y1096470D03*
X1809651Y1096426D03*
X1799012Y1095893D03*
X1824706Y1093150D03*
X1805013Y1091877D03*
X1809696Y1091832D03*
X1824706Y1089145D03*
X1816756D03*
X1795819Y1088553D03*
X1824706Y1085145D03*
X1816235Y1083970D03*
X1810346Y1082250D03*
X1801961Y1081717D03*
X1824706Y1081145D03*
X1824949Y1077145D03*
X1812296Y1075688D03*
X1810349Y1031264D03*
X1803351Y1027471D03*
X1807844Y1027248D03*
X1798844D03*
X1792844D03*
X1786844D03*
X1780844D03*
X1774844D03*
X1812538Y1026859D03*
X1807844Y1023694D03*
X1801844D03*
X1795844D03*
X1789844D03*
X1783844D03*
X1774844D03*
X1768844D03*
X1779033Y1023432D03*
X1759569Y1021944D03*
X1811468Y1021084D03*
X1780802Y1019474D03*
X1769004Y1019395D03*
X1786740Y1019237D03*
X1774863D03*
X1805188Y1019078D03*
X1799646Y1018999D03*
X1793470Y1018762D03*
X1749314Y987904D03*
X1745824Y987058D03*
X1651443Y981515D03*
X1647565Y981432D03*
X1644325Y942120D03*
X1647402Y881460D03*
X1637771Y952120D03*
X1648375Y886766D03*
X1648387Y945554D03*
X1644552Y871353D03*
X1647470Y952125D03*
X1650205Y925911D03*
X1647763Y919268D03*
X1635000Y919263D03*
X1644718Y909263D03*
G54D38*
X1822594Y1211054D03*
Y1215324D03*
X986645Y1108465D03*
X989513Y1097683D03*
G54D47*
X219881Y1254724D03*
Y1232283D03*
Y1236023D03*
X216141Y1247243D03*
X208661Y1243503D03*
X216141D03*
X204921Y1250984D03*
X208661Y1247243D03*
X201181Y1243503D03*
X212401Y1250984D03*
X201181Y1247243D03*
X212401Y1254724D03*
X204921D03*
Y1232283D03*
X212401D03*
Y1236023D03*
X204921D03*
X197440D03*
Y1232283D03*
X189960Y1236023D03*
Y1232283D03*
X182480Y1236023D03*
Y1232283D03*
X174999D03*
Y1236023D03*
X184350Y1178051D03*
X180610Y1174310D03*
X173129D03*
Y1178051D03*
X180610D03*
X176870Y1174310D03*
Y1178051D03*
X150689Y1159350D03*
X158169Y1166830D03*
X154429D03*
X150688D03*
X154429Y1170570D03*
X150688D03*
X165649Y1178050D03*
Y1174310D03*
X143208Y1151870D03*
Y1159350D03*
X146949Y1166830D03*
X146948Y1159350D03*
X150688Y1174310D03*
X184350Y1140649D03*
Y1144389D03*
Y1151870D03*
X180610Y1136909D03*
Y1148129D03*
X173129Y1144389D03*
X169389D03*
X173129Y1148129D03*
X180610Y1151870D03*
Y1144389D03*
X176870Y1151870D03*
Y1148129D03*
Y1144389D03*
X173129Y1133169D03*
X169389D03*
X176870Y1140649D03*
Y1133169D03*
Y1136909D03*
X173129Y1140649D03*
X169389D03*
X173129Y1129428D03*
X169389D03*
X180610Y1140649D03*
X154429Y1092027D03*
X161909Y1077066D03*
Y1088287D03*
Y1092027D03*
X158169D03*
X161909Y1084547D03*
X158169Y1077066D03*
X154429Y1084547D03*
X161909Y1080807D03*
X154429D03*
X158169Y1099507D03*
Y1103247D03*
Y1106988D03*
X161909Y1095767D03*
Y1106988D03*
X154429D03*
Y1095767D03*
X161909Y1103247D03*
X158169Y1095767D03*
X154429Y1103247D03*
X161909Y1099507D03*
X154429D03*
X158169Y1110728D03*
Y1114468D03*
X154429D03*
X158169Y1118208D03*
Y1121948D03*
X154429D03*
X161909Y1114468D03*
Y1118208D03*
Y1121948D03*
Y1110728D03*
X154429D03*
Y1118208D03*
X158169Y1133169D03*
Y1125688D03*
Y1129429D03*
X154429D03*
X165649Y1140649D03*
X161909Y1125688D03*
X165649Y1129429D03*
X161909D03*
X165649Y1136909D03*
X154429Y1125688D03*
Y1073326D03*
X161909D03*
X158169D03*
X154429Y1077066D03*
X158169Y1080807D03*
Y1084547D03*
Y1088287D03*
X154429D03*
X146948Y1118208D03*
Y1110728D03*
Y1121948D03*
Y1114468D03*
X143208Y1118208D03*
Y1110728D03*
Y1121948D03*
Y1114468D03*
X146948Y1103247D03*
Y1095767D03*
Y1106988D03*
Y1099507D03*
X143208Y1095767D03*
Y1103247D03*
Y1106988D03*
Y1099507D03*
X146948Y1092027D03*
Y1084547D03*
Y1080806D03*
Y1077066D03*
Y1088287D03*
X143208Y1092027D03*
Y1084547D03*
Y1088287D03*
X146948Y1144389D03*
Y1125688D03*
Y1129429D03*
X143208Y1140649D03*
Y1133169D03*
Y1125688D03*
Y1129429D03*
X139468Y1136909D03*
X146948Y1140649D03*
Y1133169D03*
X161909Y1159350D03*
X165649Y1155610D03*
X158169D03*
X150689Y1148129D03*
X154429Y1151869D03*
X158169D03*
X150689Y1144389D03*
X161909Y1155610D03*
Y1151870D03*
Y1148129D03*
Y1144389D03*
X165649Y1148129D03*
X158169Y1140649D03*
X150689D03*
X154429D03*
X150689Y1136909D03*
X154429D03*
X173129Y1155610D03*
X169389Y1151870D03*
X173129Y1159350D03*
X169389D03*
X176870D03*
X290944Y1194881D03*
Y1198621D03*
Y1202362D03*
Y1206102D03*
Y1209842D03*
Y1213582D03*
X328347Y1228543D03*
X270374Y1215452D03*
X281594Y1207972D03*
X191830Y1193011D03*
X195570Y1204232D03*
Y1193011D03*
Y1196751D03*
Y1200491D03*
X191830D03*
Y1196751D03*
Y1204232D03*
X195570Y1178051D03*
Y1185531D03*
X191830Y1174310D03*
Y1181791D03*
X195570Y1189271D03*
Y1170570D03*
X214271Y1211712D03*
Y1207972D03*
X210531D03*
X203051D03*
X206791D03*
X203051Y1200491D03*
X206791D03*
X199311D03*
X210531D03*
X214271D03*
X206791Y1193011D03*
X203051D03*
X199311D03*
X210531D03*
X214271D03*
Y1204232D03*
X210531D03*
Y1196751D03*
X214271D03*
X206791Y1204232D03*
X203051D03*
X199311D03*
Y1196751D03*
X203051D03*
X206791D03*
X210531Y1178051D03*
X214271D03*
X199311D03*
X203051D03*
X206791D03*
X210531Y1185531D03*
X214271D03*
X206791D03*
X199311D03*
X203051D03*
X214271Y1174310D03*
X206791D03*
X199311D03*
X210531Y1189271D03*
X214271D03*
X210531Y1181791D03*
X214271D03*
X199311Y1189271D03*
X203051D03*
X206791D03*
X199311Y1181791D03*
X203051D03*
X206791D03*
X210531Y1170570D03*
X214271Y1166830D03*
X203051Y1170570D03*
X199311Y1166830D03*
X206791D03*
X214271Y1215452D03*
X221752Y1211712D03*
X225492D03*
X229232Y1215452D03*
Y1211712D03*
Y1207972D03*
X218011D03*
X221751D03*
X218011Y1211712D03*
X225492Y1207972D03*
X229232Y1200491D03*
X225492D03*
X221751D03*
X218011D03*
X229232Y1193011D03*
X225492D03*
X221751D03*
X218011D03*
Y1196751D03*
X221751D03*
Y1204232D03*
X225492D03*
Y1196751D03*
X229232Y1204232D03*
Y1196751D03*
X218011Y1204232D03*
X229232Y1178051D03*
X218011D03*
X221751D03*
X225492D03*
X229232Y1185531D03*
X221751D03*
X218011D03*
X225492D03*
X229232Y1174310D03*
X221751D03*
X229232Y1189271D03*
Y1181791D03*
X218011Y1189271D03*
X221751D03*
X218011Y1181791D03*
X221751D03*
X225492Y1189271D03*
Y1181791D03*
X229232Y1166830D03*
X221752D03*
X218011Y1170570D03*
X225492D03*
X240452Y1200491D03*
X244192Y1193011D03*
X236712D03*
X240452D03*
X244192Y1196751D03*
Y1204232D03*
X240452Y1196751D03*
X236712D03*
Y1204232D03*
X240452D03*
X244192Y1178051D03*
X236712D03*
X240452D03*
X244192Y1185531D03*
X236712D03*
X240452D03*
Y1174310D03*
X244192Y1189271D03*
Y1181791D03*
X240452Y1189271D03*
X236712D03*
Y1181791D03*
X240452D03*
X244192Y1170570D03*
X236712D03*
X240452Y1166830D03*
X236712Y1211712D03*
Y1207972D03*
X244192D03*
Y1211712D03*
X240452D03*
Y1207972D03*
X244192Y1200491D03*
X236712D03*
X251673Y1211711D03*
X247932D03*
X251673Y1215452D03*
X259153D03*
X247932Y1215451D03*
X262893Y1215452D03*
X255413D03*
X259153Y1211712D03*
X262893D03*
X259153Y1207972D03*
X262893D03*
X255413D03*
Y1211712D03*
X251673Y1207972D03*
X247933D03*
X255413Y1200491D03*
X247933D03*
X251673D03*
X262893D03*
X259153D03*
Y1193011D03*
X262893D03*
X247933D03*
X255413D03*
X251673D03*
X262893Y1196751D03*
X259153D03*
X262893Y1204232D03*
X259153D03*
X255413Y1196751D03*
X251673D03*
X247933D03*
X251673Y1204232D03*
X255413D03*
X247933D03*
X262893Y1178051D03*
X259153D03*
X255413D03*
X247933D03*
X251673D03*
X262893Y1185531D03*
X259153D03*
X251673D03*
X255413D03*
X247933D03*
Y1174310D03*
X255413D03*
X259153Y1189271D03*
X262893Y1181791D03*
X259153D03*
X262893Y1174310D03*
Y1189271D03*
X255413D03*
X251673D03*
X247933D03*
X255413Y1181791D03*
X251673D03*
X247933D03*
X262893Y1170570D03*
X259153D03*
X247933Y1166830D03*
X255413D03*
X251673Y1170570D03*
X262893Y1166830D03*
X270373Y1185531D03*
Y1178051D03*
X266633Y1189271D03*
X274114Y1174310D03*
Y1181791D03*
X277854D03*
X266633Y1166830D03*
X270373D03*
Y1170570D03*
X266633D03*
X277854D03*
Y1166830D03*
X274114Y1170570D03*
Y1166830D03*
X277854Y1207972D03*
X274114Y1211712D03*
X266633Y1215452D03*
X277854D03*
X274114D03*
X277854Y1211712D03*
X270373Y1207972D03*
X266633Y1211712D03*
Y1207972D03*
X270373Y1211712D03*
X274114Y1207972D03*
X277854Y1204232D03*
Y1196751D03*
Y1200491D03*
X274114Y1193011D03*
Y1200491D03*
X266633D03*
Y1193011D03*
X277854D03*
X270373D03*
X266633Y1196751D03*
X270373Y1200491D03*
X266633Y1204232D03*
X270373D03*
X270393Y1196732D03*
X274114Y1196751D03*
Y1204232D03*
Y1178051D03*
Y1185531D03*
Y1189271D03*
X270373Y1181791D03*
X266633Y1178051D03*
Y1185531D03*
X277854Y1174310D03*
X270373D03*
X277854Y1185531D03*
Y1189271D03*
Y1178051D03*
X270373Y1189271D03*
X266633Y1181791D03*
X281594Y1200491D03*
X285334Y1204232D03*
Y1200491D03*
Y1196751D03*
X294685Y1198621D03*
X285334Y1193011D03*
X281594D03*
Y1204232D03*
Y1196751D03*
X289074Y1181791D03*
X285334Y1178051D03*
X281594Y1181791D03*
X285334Y1189271D03*
Y1174310D03*
X292814D03*
X281594D03*
Y1178051D03*
X285334Y1181791D03*
X281594Y1185531D03*
Y1189271D03*
X289074Y1185531D03*
Y1178051D03*
Y1174310D03*
X285334Y1185531D03*
X292814Y1181791D03*
X292815Y1170570D03*
X285334Y1166830D03*
Y1170570D03*
X292814Y1166830D03*
X281594D03*
Y1170570D03*
X289074D03*
Y1166830D03*
X281594Y1215452D03*
X285334Y1211712D03*
Y1215452D03*
Y1207972D03*
X281594Y1211712D03*
X294685Y1206102D03*
Y1213582D03*
Y1217322D03*
X302165Y1202362D03*
X305905D03*
X298425Y1198621D03*
X309645Y1202362D03*
X305905Y1198621D03*
X307775Y1193011D03*
X298425Y1194881D03*
Y1202362D03*
X302165Y1198621D03*
X304035Y1193011D03*
X294685Y1202362D03*
Y1194881D03*
X311515Y1185531D03*
Y1178051D03*
X307775Y1189271D03*
Y1181791D03*
Y1174310D03*
X304035Y1189271D03*
Y1181791D03*
Y1174310D03*
X311515Y1189271D03*
X307775Y1185531D03*
X311515Y1181791D03*
X307775Y1178051D03*
X311515Y1174310D03*
X304035Y1178051D03*
Y1185531D03*
X296555Y1174310D03*
X300295D03*
Y1178051D03*
Y1181791D03*
X311515Y1170570D03*
X296555D03*
X307775Y1166830D03*
X304035D03*
X307775Y1170570D03*
X311515Y1166830D03*
X300295D03*
Y1170570D03*
X304035D03*
X296555Y1166830D03*
X305905Y1228543D03*
X309645Y1236023D03*
X298425Y1228543D03*
Y1224803D03*
X309645Y1232283D03*
X302165D03*
X309645Y1239763D03*
X305905Y1236023D03*
X309645Y1224803D03*
Y1228543D03*
X305905Y1232283D03*
X298425Y1239763D03*
X305905Y1221062D03*
X302165Y1224803D03*
Y1228543D03*
X298425Y1232283D03*
Y1236023D03*
X302165Y1217322D03*
X298425Y1206102D03*
X302165Y1209842D03*
X305905Y1217322D03*
Y1209842D03*
X298425Y1213582D03*
X309645Y1221062D03*
Y1206102D03*
Y1213582D03*
X305905D03*
X309645Y1209842D03*
Y1217322D03*
X298425D03*
X302165Y1221062D03*
X298425D03*
X302165Y1206102D03*
X298425Y1209842D03*
X294685D03*
X302165Y1213582D03*
X305905Y1206102D03*
X311515Y1193011D03*
X305905Y1247243D03*
Y1243503D03*
X298425D03*
Y1247243D03*
X313385Y1239763D03*
X302165D03*
X305905D03*
X302165Y1243503D03*
Y1247243D03*
X317125Y1239763D03*
X309645Y1243503D03*
Y1247243D03*
X302165Y1236023D03*
X305905Y1224803D03*
X324606Y1213582D03*
X317125Y1209842D03*
Y1217322D03*
X324606D03*
Y1209842D03*
X317125Y1213582D03*
X313385D03*
X317125Y1221062D03*
X313385D03*
X320866Y1209842D03*
Y1217322D03*
X328347Y1213582D03*
Y1221062D03*
X315255Y1193011D03*
X324606Y1206102D03*
X320866D03*
X317125Y1202362D03*
X324606Y1198621D03*
X313385Y1202362D03*
X320866Y1198621D03*
X324606Y1202362D03*
X326416Y1193011D03*
X317125Y1198621D03*
X313385Y1206102D03*
X317125D03*
X318996Y1193011D03*
X320866Y1202362D03*
X322736Y1193011D03*
X328347Y1206102D03*
Y1198621D03*
X326476Y1189271D03*
X315255Y1185531D03*
X326476Y1181791D03*
X315255Y1178051D03*
X326476Y1174310D03*
X322736Y1189271D03*
Y1181791D03*
Y1174310D03*
Y1185531D03*
Y1178051D03*
X326476Y1185531D03*
Y1178051D03*
X318996Y1174310D03*
X315255D03*
X318996Y1178051D03*
Y1181791D03*
Y1185531D03*
Y1189271D03*
X315255D03*
Y1181791D03*
Y1170570D03*
X326476D03*
Y1166830D03*
X318996D03*
Y1170570D03*
X315255Y1166830D03*
X322736D03*
Y1170570D03*
X324606Y1247243D03*
X313385Y1243503D03*
X320866Y1239763D03*
Y1247243D03*
X313385D03*
X324606Y1239763D03*
Y1243503D03*
X317125D03*
Y1247243D03*
X320866Y1243503D03*
X328347Y1247243D03*
Y1239762D03*
X320866Y1228543D03*
X313385D03*
X317125Y1232283D03*
X324606Y1228543D03*
X313385Y1224803D03*
X317125Y1236023D03*
X324606Y1224803D03*
Y1236023D03*
Y1232283D03*
X313385Y1236023D03*
X317125Y1224803D03*
Y1228543D03*
X313385Y1232283D03*
X320866D03*
Y1224803D03*
Y1236023D03*
X313385Y1217322D03*
X324606Y1221062D03*
X320866Y1213582D03*
X313385Y1209842D03*
X320866Y1221062D03*
X242321Y1071455D03*
X249802D03*
X257282D03*
X264762D03*
X272243D03*
X279723D03*
X287203D03*
X294684D03*
X302165D03*
X309645D03*
X317125D03*
X238582Y1075196D03*
X246062D03*
X253543D03*
X261023D03*
X268503D03*
X275984D03*
X283464D03*
X290944D03*
X298425D03*
X305906D03*
X313386D03*
X320866D03*
X238582Y1078936D03*
X246062D03*
X253543D03*
X261023D03*
X268503D03*
X275984D03*
X283464D03*
X290944D03*
X298426D03*
X305906D03*
X313386D03*
X320866D03*
X324606D03*
X242322Y1082677D03*
X249803D03*
X257283D03*
X264763D03*
X272244D03*
X279724D03*
X287204D03*
X294684D03*
X302164D03*
X309644D03*
X317125D03*
X328347D03*
X242322Y1086417D03*
X249803D03*
X257283D03*
X264763D03*
X272244D03*
X279724D03*
X287204D03*
X294685D03*
X302165D03*
X309645D03*
X317126D03*
X320866D03*
X324606D03*
X238582Y1090157D03*
X242322D03*
X246062D03*
X249803D03*
X253543D03*
X257283D03*
X261023D03*
X264763D03*
X268503D03*
X272244D03*
X275984D03*
X279724D03*
X283464D03*
X287204D03*
X290943D03*
X294684D03*
X298424D03*
X302164D03*
X305904D03*
X309644D03*
X313384D03*
X317125D03*
X320866D03*
X324606D03*
X328347Y1090158D03*
X234841Y1093897D03*
X238582D03*
X242321D03*
X246062D03*
X249802D03*
X253543D03*
X257282D03*
X261023D03*
X264762D03*
X268503D03*
X272243D03*
X275984D03*
X279723D03*
X283464D03*
X287203D03*
X290944D03*
X294684D03*
X298425D03*
X302164D03*
X305905D03*
X309644D03*
X313385D03*
X317125D03*
X320866D03*
X324606D03*
X234841Y1097637D03*
X238582D03*
X242321D03*
X246062D03*
X249802D03*
X253543D03*
X257282D03*
X261023D03*
X264762D03*
X268503D03*
X272243D03*
X275984D03*
X279723D03*
X283464D03*
X287203D03*
X290944D03*
X294684D03*
X298425D03*
X302164D03*
X305905D03*
X309644D03*
X313385D03*
X317125D03*
X320866D03*
X324606D03*
X193700Y1101376D03*
X201181D03*
X208661D03*
X216141D03*
X223621D03*
X231102D03*
X238582D03*
X246062D03*
X253543D03*
X261023D03*
X268503D03*
X275984D03*
X283464D03*
X290944D03*
X298425D03*
X305905D03*
X197440Y1101377D03*
X204921D03*
X212401D03*
X219881D03*
X227362D03*
X234842D03*
X242322D03*
X249803D03*
X257283D03*
X264763D03*
X272244D03*
X279724D03*
X287204D03*
X294684D03*
X302165D03*
X309645D03*
X313385D03*
X317125D03*
X320866D03*
X324606D03*
X328347Y1101378D03*
X193700Y1105117D03*
X197440D03*
X201181D03*
X204921D03*
X208661D03*
X212401D03*
X216141D03*
X219881D03*
X223621D03*
X227362D03*
X231102D03*
X234842D03*
X238582D03*
X242322D03*
X246062D03*
X249803D03*
X253543D03*
X257283D03*
X261023D03*
X264763D03*
X268503D03*
X272244D03*
X275984D03*
X279724D03*
X283464D03*
X287204D03*
X290944D03*
X294685D03*
X298425D03*
X302165D03*
X305905D03*
X309645D03*
X313385D03*
X317126D03*
X320866D03*
X324606D03*
X305904Y1108857D03*
X193700Y1108858D03*
X197440D03*
X201181D03*
X204921D03*
X208661D03*
X219881D03*
X223622D03*
X227362D03*
X231102D03*
X234842D03*
X238582D03*
X242322D03*
X246062D03*
X249803D03*
X253543D03*
X257283D03*
X261023D03*
X264763D03*
X268503D03*
X272244D03*
X275984D03*
X279724D03*
X283464D03*
X287204D03*
X290944D03*
X294685D03*
X298425D03*
X302165D03*
X309644D03*
X313385D03*
X317125D03*
X328347Y1108859D03*
X290944Y1112598D03*
X294684D03*
X298425D03*
X302165D03*
X305905D03*
X309645D03*
X320866D03*
X324606D03*
X191830Y1114468D03*
X195570D03*
X199311D03*
X203051D03*
X206791D03*
X210531D03*
X214271D03*
X218011D03*
X221752D03*
X225492D03*
X229232D03*
X236712D03*
X240452D03*
X244192D03*
X247933D03*
X251673D03*
X255413D03*
X259153D03*
X262893D03*
X270373D03*
X274114D03*
X277854D03*
X281594D03*
X285334D03*
X290944Y1116338D03*
X294684D03*
X298425D03*
X302165D03*
X305905D03*
X309645D03*
X313385D03*
X317125D03*
X328347Y1116339D03*
X191830Y1118208D03*
X195570D03*
X199311D03*
X203051D03*
X206791D03*
X210531D03*
X214271D03*
X218011D03*
X221751D03*
X225492D03*
X229232D03*
X236712D03*
X240452D03*
X244192D03*
X247933D03*
X251673D03*
X255413D03*
X259153D03*
X262893D03*
X270373D03*
X274114D03*
X277854D03*
X281594D03*
X285334D03*
X290944Y1120078D03*
X294684D03*
X298425D03*
X302165D03*
X305905D03*
X309645D03*
X320866D03*
X324606D03*
X191830Y1121948D03*
X195570D03*
X199311D03*
X203051D03*
X206791D03*
X210531D03*
X214271D03*
X218011D03*
X221751D03*
X225492D03*
X229232D03*
X236712D03*
X240452D03*
X244192D03*
X247933D03*
X251673D03*
X255413D03*
X259153D03*
X262893D03*
X266633D03*
X270373D03*
X274114D03*
X277854D03*
X290944Y1123818D03*
X294684D03*
X298425D03*
X302165D03*
X305905D03*
X309645D03*
X313385D03*
X317125D03*
X328347Y1123819D03*
X191830Y1125688D03*
X195570D03*
X199311D03*
X203051D03*
X206791D03*
X210531D03*
X214271D03*
X218011D03*
X221751D03*
X225492D03*
X229232D03*
X236712D03*
X240452D03*
X244192D03*
X247933D03*
X251673D03*
X255413D03*
X259153D03*
X262893D03*
X266633D03*
X270373D03*
X274114D03*
X277854D03*
X290944Y1127558D03*
X294685D03*
X298425D03*
X309645D03*
X320866D03*
X324606D03*
X302165Y1127559D03*
X305905D03*
X191830Y1129429D03*
X195570D03*
X199311D03*
X203051D03*
X206791D03*
X210531D03*
X214271D03*
X218011D03*
X221751D03*
X225492D03*
X229232D03*
X236712D03*
X240452D03*
X244192D03*
X247933D03*
X251673D03*
X255413D03*
X259153D03*
X262893D03*
X266633D03*
X270373D03*
X274114D03*
X277854D03*
X290944Y1131299D03*
X294684D03*
X298425D03*
X302165D03*
X305905D03*
X309645D03*
X313384D03*
X317125D03*
X328347Y1131300D03*
X229330Y1132677D03*
X191830Y1133169D03*
X195570D03*
X199311D03*
X203051D03*
X206791D03*
X210531D03*
X214271D03*
X218011D03*
X221751D03*
X225492D03*
X240452D03*
X244192D03*
X247933D03*
X251673D03*
X255413D03*
X259153D03*
X262893D03*
X266633D03*
X270373D03*
X277854D03*
X236712Y1133464D03*
X290944Y1135039D03*
X294685D03*
X298425D03*
X302165D03*
X305905D03*
X191830Y1136909D03*
X195570D03*
X199311D03*
X203051D03*
X206791D03*
X210531D03*
X214271D03*
X218011D03*
X221751D03*
X225492D03*
X229232D03*
X236712D03*
X240452D03*
X244192D03*
X247933D03*
X251673D03*
X255413D03*
X259153D03*
X262893D03*
X266633D03*
X270373D03*
X274114D03*
X277854D03*
X281594D03*
X285334D03*
X191830Y1140649D03*
X195570D03*
X199311D03*
X203051D03*
X206791D03*
X210531D03*
X214271D03*
X218011D03*
X221751D03*
X225492D03*
X229232D03*
X236712D03*
X240452D03*
X244192D03*
X247933D03*
X251673D03*
X255413D03*
X259153D03*
X262893D03*
X266633D03*
X270373D03*
X274114D03*
X277854D03*
X281594D03*
X285334D03*
X300295D03*
X304035D03*
X307775D03*
X311515D03*
X315255D03*
X318996D03*
X322736D03*
X326476D03*
X195570Y1144389D03*
X199311D03*
X203051D03*
X206791D03*
X210531D03*
X214271D03*
X218011D03*
X221751D03*
X225492D03*
X229232D03*
X236712D03*
X240452D03*
X244192D03*
X247933D03*
X251673D03*
X255413D03*
X259153D03*
X262893D03*
X266633D03*
X270373D03*
X274114D03*
X277854D03*
X281594D03*
X285334D03*
X289074D03*
X292814D03*
X296555D03*
X300295D03*
X304035D03*
X307775D03*
X311515D03*
X315255D03*
X318996D03*
X322736D03*
X326476D03*
X191830Y1148129D03*
X199311D03*
X203051D03*
X206791D03*
X210531D03*
X214271D03*
X218011D03*
X221751D03*
X225492D03*
X229232D03*
X236712D03*
X240452D03*
X244192D03*
X247933D03*
X251673D03*
X255413D03*
X259153D03*
X262893D03*
X266633D03*
X270373D03*
X274114D03*
X277854D03*
X281594D03*
X285334D03*
X289074D03*
X292815D03*
X300295D03*
X304035D03*
X307775D03*
X311515D03*
X315255D03*
X318996D03*
X322736D03*
X326476D03*
X195570Y1151869D03*
X236712D03*
X240452D03*
X244192D03*
X247933D03*
X251673D03*
X255413D03*
X259153D03*
X262893D03*
X266633D03*
X270373D03*
X274114D03*
X281594D03*
X285334D03*
X289074D03*
X292814D03*
X296555D03*
X300295D03*
X304035D03*
X307775D03*
X311515D03*
X315255D03*
X318996D03*
X199311Y1151870D03*
X203051D03*
X206791D03*
X210531D03*
X214271D03*
X218011D03*
X221752D03*
X225492D03*
X229232D03*
X277854D03*
X322736D03*
X326476D03*
X191830Y1155610D03*
X199311D03*
X206791D03*
X214271D03*
X221751D03*
X229232D03*
X240452D03*
X247933D03*
X255413D03*
X262893D03*
X270373D03*
X274114D03*
X277854D03*
X281594D03*
X285334D03*
X289074D03*
X292815D03*
X296555D03*
X300295D03*
X304035D03*
X307775D03*
X311515D03*
X315255D03*
X318996D03*
X322736D03*
X326476D03*
X195570Y1159350D03*
X203051D03*
X210531D03*
X218011D03*
X225492D03*
X236712D03*
X244192D03*
X251673D03*
X259153D03*
X262893D03*
X266633D03*
X270373D03*
X274114D03*
X277854D03*
X281594D03*
X285334D03*
X289074D03*
X292814D03*
X296555D03*
X300295D03*
X304035D03*
X307775D03*
X311515D03*
X315255D03*
X318996D03*
X322736D03*
X326476D03*
X598424Y1191142D03*
Y1198622D03*
X598423Y1247242D03*
X598424Y1221063D03*
X598423Y1239762D03*
X598424Y1228542D03*
Y1213583D03*
X602165Y1247243D03*
X609646Y1198621D03*
Y1206102D03*
X602165Y1232283D03*
Y1236023D03*
Y1224803D03*
Y1213582D03*
X605905D03*
Y1221062D03*
X602165D03*
Y1209842D03*
X605905D03*
X602165Y1217322D03*
X605905D03*
Y1191141D03*
X602165D03*
X605905Y1198621D03*
X602165D03*
X605905Y1206102D03*
X602165D03*
X605905Y1194881D03*
X602165D03*
X605905Y1202362D03*
X602165D03*
X605905Y1187401D03*
X602165D03*
Y1183661D03*
X605905D03*
X643307Y1243503D03*
Y1239763D03*
Y1224803D03*
Y1228543D03*
Y1232283D03*
Y1236023D03*
X635827Y1243503D03*
Y1247243D03*
X628346D03*
Y1243503D03*
X624606Y1247243D03*
X639567D03*
X624606Y1239763D03*
Y1243503D03*
X628346Y1239763D03*
X632086D03*
X635827D03*
X639567D03*
Y1243503D03*
X632086D03*
Y1247243D03*
X624606Y1232283D03*
Y1236023D03*
X628346Y1224803D03*
Y1228543D03*
X635827Y1224803D03*
Y1228543D03*
X632086Y1232283D03*
Y1236023D03*
X639567Y1232283D03*
Y1236023D03*
Y1228543D03*
Y1224803D03*
X635827Y1232283D03*
Y1236023D03*
X628346Y1232283D03*
X613386Y1224803D03*
Y1228543D03*
X620866Y1224803D03*
Y1228543D03*
X609646Y1232283D03*
Y1236023D03*
X617126D03*
Y1232283D03*
X613386Y1236023D03*
Y1232283D03*
X609646Y1228543D03*
Y1224803D03*
X617126D03*
Y1228543D03*
X620866Y1232283D03*
Y1236023D03*
X605905Y1247243D03*
Y1239763D03*
Y1243503D03*
Y1228543D03*
Y1236023D03*
Y1232283D03*
Y1224803D03*
X635827Y1221062D03*
X613386Y1206102D03*
Y1187401D03*
X609646D03*
Y1183661D03*
X620866D03*
X617126D03*
X602165Y1239763D03*
X632086Y1217322D03*
Y1221062D03*
X624606Y1217322D03*
Y1221062D03*
X628346D03*
Y1217322D03*
X620866D03*
X617126D03*
Y1221062D03*
X620866D03*
X624606Y1209842D03*
X628346Y1213582D03*
X632086D03*
X628346Y1209842D03*
X632086D03*
X624606Y1213582D03*
X632086Y1191141D03*
X628346D03*
X624606Y1194881D03*
Y1202362D03*
X628346Y1198621D03*
X632086D03*
X628346Y1206102D03*
X632086D03*
X628346Y1194881D03*
X632086D03*
X624606Y1198621D03*
Y1206102D03*
X628346Y1202362D03*
X632086D03*
X624606Y1191141D03*
Y1187401D03*
X628346D03*
X620866Y1209842D03*
Y1213582D03*
X617126Y1209842D03*
Y1213582D03*
X620866Y1194881D03*
Y1202362D03*
Y1191141D03*
X617126D03*
X620866Y1198621D03*
X617126D03*
Y1194881D03*
Y1206102D03*
X620866D03*
X617126Y1202362D03*
X620866Y1187401D03*
X617126D03*
X613386Y1209842D03*
X609646D03*
Y1217322D03*
X613386D03*
Y1213582D03*
X609646D03*
Y1221062D03*
X613386D03*
X609646Y1194881D03*
X613386D03*
X609646Y1202362D03*
X613386D03*
Y1191141D03*
X609646D03*
X613386Y1198621D03*
X628346Y1236023D03*
X624606Y1228543D03*
Y1224803D03*
X632086D03*
Y1228543D03*
X620866Y1243503D03*
Y1247243D03*
X613386D03*
Y1243503D03*
X609646Y1247243D03*
X617126D03*
X609646Y1239763D03*
Y1243503D03*
X613386Y1239763D03*
X620866D03*
X617126D03*
Y1243503D03*
X613386Y1183661D03*
X602165Y1228543D03*
Y1243503D03*
X598424Y1206103D03*
X624606Y1183661D03*
X635827Y1198621D03*
Y1202362D03*
Y1206102D03*
Y1209842D03*
Y1213582D03*
Y1217322D03*
X604036Y1166830D03*
X604034Y1174310D03*
X615256D03*
X611516D03*
X607775Y1178051D03*
Y1174310D03*
X618996Y1178051D03*
Y1174310D03*
X607775Y1170570D03*
X611516D03*
X607775Y1166830D03*
X611516D03*
X615256D03*
X633957D03*
Y1170570D03*
X630216D03*
Y1166830D03*
X622736Y1170570D03*
Y1166830D03*
X633957Y1181791D03*
Y1178051D03*
Y1174310D03*
X622736Y1178050D03*
X630216Y1178051D03*
Y1174310D03*
X622736D03*
X641437Y1207972D03*
X645177D03*
X648917D03*
Y1211712D03*
X645177D03*
X648917Y1193011D03*
X652657Y1196751D03*
X641437D03*
Y1193011D03*
X648917Y1200491D03*
Y1196751D03*
Y1204232D03*
X645177D03*
X641437D03*
Y1200491D03*
X645177D03*
Y1196751D03*
Y1193011D03*
X652657D03*
X645177Y1174310D03*
Y1181791D03*
X641437Y1178051D03*
Y1185531D03*
X652657Y1178051D03*
Y1185531D03*
X648917Y1174310D03*
Y1181791D03*
X652657Y1189271D03*
X637697Y1181791D03*
X645177Y1178051D03*
X637697Y1174310D03*
Y1178051D03*
X645177Y1185531D03*
Y1166830D03*
X641437Y1170570D03*
X652657D03*
X648917Y1166830D03*
X637697Y1170570D03*
Y1166830D03*
X645177Y1170570D03*
Y1215452D03*
X648917D03*
X641437D03*
Y1211712D03*
X667618Y1170570D03*
X660138D03*
X656398Y1166830D03*
X663878D03*
X667618Y1193011D03*
X656398D03*
X660138D03*
X663878D03*
X656398Y1178051D03*
X660138D03*
X663878D03*
X667618D03*
X663878Y1185531D03*
X656398D03*
X660138D03*
X667618D03*
X663878Y1174310D03*
X656398D03*
X667618Y1189271D03*
Y1181791D03*
X656398Y1189271D03*
X660138D03*
X663878D03*
X656398Y1181791D03*
X660138D03*
X663878D03*
X686319Y1193011D03*
X671358D03*
X675098D03*
X678838D03*
X682579D03*
X671358Y1178051D03*
X675098D03*
X678838D03*
X682579D03*
X686319D03*
X678838Y1185531D03*
X671358D03*
X675098D03*
X682579D03*
X686319D03*
Y1174310D03*
X678838D03*
X671358D03*
X678838Y1181791D03*
X682579Y1189271D03*
Y1181791D03*
X686319Y1189271D03*
Y1181791D03*
X671358Y1189271D03*
X675098D03*
X678838D03*
X671358Y1181791D03*
X675098D03*
X686319Y1166830D03*
X671358D03*
X678839D03*
X675098Y1170570D03*
X682579D03*
X693799Y1193011D03*
X697539D03*
X701279D03*
X693799Y1178051D03*
X697539D03*
X701279D03*
X693799Y1185531D03*
X697539D03*
X701279D03*
X697539Y1174310D03*
Y1181791D03*
X701279D03*
Y1189271D03*
X697539D03*
X693799D03*
Y1181791D03*
X701279Y1170570D03*
X693799D03*
X697539Y1166830D03*
X716240Y1193011D03*
X705020D03*
X712500D03*
X708760D03*
Y1178051D03*
X705020D03*
X712500D03*
X716240D03*
X705020Y1185531D03*
X712500D03*
X708760D03*
X716240D03*
X712500Y1174310D03*
X705020D03*
Y1181791D03*
X708760D03*
X712500D03*
X705020Y1189271D03*
X708760D03*
X712500D03*
X716240Y1181791D03*
Y1189271D03*
X708760Y1170570D03*
X712500Y1166830D03*
X705020D03*
X716240Y1170570D03*
X719980Y1189271D03*
X723720D03*
X719980Y1174310D03*
Y1181791D03*
X723720D03*
Y1170570D03*
X719980D03*
X723720Y1166830D03*
X719980D03*
X723720Y1193011D03*
X719980D03*
X723720Y1185531D03*
Y1178051D03*
X719980D03*
Y1185531D03*
X693799Y1133464D03*
X600295Y1136909D03*
X604035D03*
X607776D03*
X626476D03*
X630216D03*
X633957D03*
X637697D03*
X656398D03*
X660138D03*
X663878D03*
X667618D03*
X671358D03*
X675098D03*
X678838D03*
X682579D03*
X686319D03*
X693799D03*
X697539D03*
X701279D03*
X705020D03*
X708760D03*
X712500D03*
X716240D03*
X719980D03*
X723720D03*
X600295Y1140649D03*
X604035D03*
X607776D03*
X611516D03*
X615256D03*
X618996D03*
X622736D03*
X626476D03*
X630216D03*
X633957D03*
X637697D03*
X641437D03*
X652657D03*
X656398D03*
X660138D03*
X663878D03*
X667618D03*
X671358D03*
X675098D03*
X678838D03*
X682579D03*
X686319D03*
X693799D03*
X697539D03*
X701279D03*
X705020D03*
X708760D03*
X712500D03*
X716240D03*
X719980D03*
X723720D03*
X600295Y1144389D03*
X604035D03*
X607776D03*
X618996D03*
X622736D03*
X626476D03*
X630216D03*
X633957D03*
X637697D03*
X641437D03*
X645177D03*
X652657D03*
X656398D03*
X660138D03*
X663878D03*
X667618D03*
X671358D03*
X675098D03*
X678838D03*
X682579D03*
X686319D03*
X693799D03*
X697539D03*
X701279D03*
X705020D03*
X708760D03*
X712500D03*
X716240D03*
X719980D03*
X723720D03*
X600295Y1148129D03*
X604035D03*
X607776D03*
X618996D03*
X622736D03*
X626476D03*
X630216D03*
X633957D03*
X637697D03*
X645177D03*
X648917D03*
X656398D03*
X660138D03*
X663878D03*
X667618D03*
X671358D03*
X675098D03*
X678838D03*
X682579D03*
X686319D03*
X693799D03*
X697539D03*
X701279D03*
X705020D03*
X708760D03*
X712500D03*
X716240D03*
X719980D03*
X723720D03*
X611516Y1151869D03*
X615256D03*
X652657D03*
X693799D03*
X697539D03*
X701279D03*
X705020D03*
X708760D03*
X712500D03*
X716240D03*
X719980D03*
X723720D03*
X600295Y1151870D03*
X604035D03*
X607776D03*
X618996D03*
X626476D03*
X630216D03*
X633957D03*
X637697D03*
X641437D03*
X645177D03*
X656398D03*
X660138D03*
X663878D03*
X667618D03*
X671358D03*
X675098D03*
X678839D03*
X682579D03*
X686319D03*
X607776Y1155610D03*
X611516D03*
X615256D03*
X618996D03*
X622736D03*
X630216D03*
X637697D03*
X645177D03*
X648917D03*
X656398D03*
X663878D03*
X671358D03*
X678838D03*
X686319D03*
X697539D03*
X705020D03*
X712500D03*
X719980D03*
X600295Y1159350D03*
X604035D03*
X607776D03*
X618996D03*
X626476D03*
X630216D03*
X633957D03*
X637697D03*
X641437D03*
X645177D03*
X652657D03*
X660138D03*
X667618D03*
X675098D03*
X682579D03*
X693799D03*
X701279D03*
X708760D03*
X716240D03*
X719980D03*
X723720D03*
X618996Y1118208D03*
Y1121948D03*
X611516Y1118208D03*
X607776D03*
X611516Y1110728D03*
X607776D03*
X611516Y1125688D03*
X607776D03*
X600295Y1088287D03*
Y1099507D03*
Y1106988D03*
X604035D03*
Y1121948D03*
X600295D03*
Y1114468D03*
X604035D03*
X641437Y1133169D03*
X637697Y1114468D03*
X641437Y1118208D03*
X637697D03*
X641437Y1121948D03*
X637697D03*
X641437Y1114468D03*
Y1125688D03*
X637697D03*
X641437Y1129429D03*
X637697D03*
X645177Y1133169D03*
X622736Y1092027D03*
Y1099507D03*
Y1103247D03*
X626476Y1106988D03*
X622736D03*
Y1095767D03*
X626476Y1103247D03*
Y1110728D03*
X622736Y1114468D03*
X630216Y1118208D03*
X626476D03*
X633957Y1114468D03*
Y1118208D03*
Y1121948D03*
X626476Y1114468D03*
X622736Y1110728D03*
X630216Y1114468D03*
X633957Y1125688D03*
X622736Y1088287D03*
X611516Y1095767D03*
X615256Y1099507D03*
X607776D03*
X615256Y1103247D03*
Y1106988D03*
X618996Y1095767D03*
X607776D03*
X615256D03*
X618996Y1103247D03*
X611516D03*
X618996Y1099507D03*
X611516D03*
X618996Y1110728D03*
X611516Y1073326D03*
X618996D03*
X615256D03*
X607776D03*
X618996Y1088287D03*
Y1092027D03*
X607775Y1077066D03*
X611516D03*
X615256Y1080807D03*
X607776D03*
X615256Y1084547D03*
X607776D03*
X615256Y1088287D03*
X611516D03*
X607776D03*
X611516Y1092027D03*
X618996Y1077066D03*
Y1084547D03*
Y1080807D03*
X615256Y1077066D03*
X611516Y1080807D03*
Y1084547D03*
X607776Y1092027D03*
X615256D03*
X618996Y1106988D03*
X643307Y1108858D03*
X639567Y1093897D03*
X635827Y1101376D03*
X639567Y1101377D03*
X635827Y1105117D03*
X639567Y1097637D03*
X635827Y1093897D03*
X639567Y1105117D03*
X643307Y1097637D03*
Y1101376D03*
Y1105117D03*
Y1093897D03*
X635827Y1097637D03*
X632086Y1093897D03*
X662008Y1101377D03*
X665748Y1101376D03*
X658268D03*
X744291Y1101377D03*
X744290Y1097637D03*
X740551D03*
X748031Y1105117D03*
X688189Y1097637D03*
X759251Y1082677D03*
X766731Y1090157D03*
X718110Y1108858D03*
X695669Y1093897D03*
X751772Y1086417D03*
X748030Y1090157D03*
X751771D03*
X744291Y1082677D03*
X748031Y1078936D03*
X751771Y1082677D03*
X783503Y1193011D03*
X776083D03*
X779823D03*
X772342D03*
X783563Y1140649D03*
Y1155610D03*
Y1148129D03*
X776083D03*
Y1151869D03*
X772342D03*
X776083Y1155610D03*
X772342Y1144389D03*
X768602Y1151869D03*
Y1144389D03*
X776083D03*
X779823Y1155610D03*
Y1148129D03*
X772342D03*
Y1155610D03*
X783563Y1151870D03*
X779823D03*
Y1144389D03*
X783563D03*
X768602Y1155610D03*
Y1148129D03*
X783563Y1170570D03*
Y1166830D03*
X776083D03*
Y1170570D03*
X772342Y1166830D03*
X768602Y1159350D03*
X776083D03*
X772342D03*
X768602Y1166830D03*
X779823D03*
Y1170570D03*
Y1159350D03*
X772342Y1170570D03*
X768602D03*
X783563Y1159350D03*
X776083Y1174310D03*
X772342D03*
X776083Y1178051D03*
Y1181791D03*
Y1185531D03*
X772342Y1181791D03*
X779823Y1185531D03*
Y1178051D03*
X783563Y1185531D03*
Y1178051D03*
X768602Y1181791D03*
Y1174310D03*
X783563Y1189271D03*
X768602Y1185531D03*
X772342Y1178051D03*
X779823Y1189271D03*
X772342Y1185531D03*
X783563Y1174310D03*
X779823D03*
X783563Y1181791D03*
X768602Y1178051D03*
X779823Y1181791D03*
X776083Y1140649D03*
X779823D03*
X744291Y1090157D03*
Y1086417D03*
X753642Y1170570D03*
Y1181791D03*
Y1174310D03*
X757382D03*
Y1178051D03*
Y1181791D03*
X764862Y1185531D03*
Y1178051D03*
X761122D03*
Y1185531D03*
X764862Y1174310D03*
X761122Y1181791D03*
X764862D03*
X761122Y1174310D03*
X759252Y1191141D03*
X757382Y1140649D03*
X761122D03*
X764862D03*
Y1155610D03*
Y1148129D03*
X753642Y1144389D03*
X757382D03*
Y1148129D03*
Y1151869D03*
Y1155610D03*
X761122Y1148129D03*
Y1155610D03*
X753642Y1151869D03*
X761122Y1144389D03*
Y1151869D03*
X753642Y1155610D03*
X764862Y1151869D03*
Y1144389D03*
Y1159350D03*
Y1170570D03*
X757382Y1166830D03*
Y1170570D03*
X761122D03*
X753642Y1166830D03*
X757382Y1159350D03*
X753642D03*
X764862Y1166830D03*
X761122D03*
Y1159350D03*
X740551Y1078936D03*
Y1090157D03*
X738681Y1155610D03*
Y1148129D03*
X749901Y1144389D03*
Y1151869D03*
X746161Y1148129D03*
X738681Y1144389D03*
X742421Y1148129D03*
Y1144389D03*
X749902Y1155610D03*
Y1148129D03*
X738681Y1166830D03*
X746161Y1170570D03*
Y1166830D03*
X738681Y1159350D03*
X749901Y1166830D03*
Y1159350D03*
X738681Y1170570D03*
X746161Y1159350D03*
X749902Y1170570D03*
X749901Y1181791D03*
Y1174310D03*
X738681D03*
Y1178051D03*
X742421Y1181791D03*
X738681Y1185531D03*
Y1189271D03*
X746161Y1185531D03*
Y1178051D03*
Y1174310D03*
X742421Y1185531D03*
Y1189271D03*
X738681Y1181791D03*
X746161D03*
X742421Y1178051D03*
X738681Y1204232D03*
Y1193011D03*
Y1196751D03*
X742421Y1193011D03*
Y1196751D03*
Y1200491D03*
X738681D03*
X742421Y1204232D03*
X738681Y1211712D03*
X742421D03*
Y1215452D03*
Y1207972D03*
X738681Y1215452D03*
Y1118208D03*
X742421D03*
X738681Y1114468D03*
X742421D03*
X738681Y1136909D03*
Y1140649D03*
X742421D03*
Y1136909D03*
X746161Y1144389D03*
Y1155610D03*
Y1151869D03*
X742421D03*
X738681D03*
X734941Y1174310D03*
X719980Y1204232D03*
X727460D03*
X731201D03*
X734941Y1193011D03*
X723720Y1204232D03*
X731201Y1200491D03*
X734941D03*
Y1204232D03*
Y1196751D03*
Y1211712D03*
X727460Y1207972D03*
X723720Y1211712D03*
Y1207972D03*
X719980Y1211712D03*
Y1207972D03*
X727460Y1211712D03*
X731201Y1207972D03*
Y1215452D03*
X734941D03*
X723720D03*
X719980D03*
X731201Y1211712D03*
X734941Y1207972D03*
Y1121948D03*
Y1118208D03*
X727460Y1121948D03*
X719980D03*
X723720D03*
X727460Y1118208D03*
X731201Y1121948D03*
Y1118208D03*
Y1114468D03*
X734941D03*
X727460D03*
X719980Y1118208D03*
Y1114468D03*
X734941Y1129429D03*
Y1125688D03*
Y1140649D03*
Y1133169D03*
Y1136909D03*
X723720Y1125688D03*
X719980D03*
X727460D03*
X731201D03*
Y1129429D03*
X734941Y1151870D03*
Y1148129D03*
Y1144389D03*
Y1155610D03*
Y1159350D03*
Y1166830D03*
Y1170570D03*
Y1181791D03*
Y1185531D03*
Y1189271D03*
Y1178051D03*
X751771Y1101377D03*
X716240Y1215452D03*
X708760D03*
X712500D03*
X705019Y1215451D03*
Y1211711D03*
X708760D03*
X705020Y1114468D03*
X712500D03*
X716240D03*
X705020Y1118208D03*
X712500D03*
X708760D03*
X716240Y1125688D03*
X712500D03*
X708760D03*
X705020D03*
X716240Y1204232D03*
X708760D03*
X712500D03*
X705020D03*
X716240Y1211712D03*
Y1207972D03*
X712500D03*
Y1211712D03*
X708760Y1207972D03*
X705020D03*
X716240Y1121948D03*
X705020D03*
X708760D03*
X712500D03*
X708760Y1114468D03*
X716240Y1118208D03*
X748031Y1093897D03*
Y1097637D03*
X693799Y1121948D03*
X697539D03*
X701279D03*
X693799Y1114468D03*
Y1118208D03*
X701279Y1114468D03*
X697539Y1118208D03*
Y1114468D03*
X701279Y1118208D03*
X693799Y1125688D03*
X697539D03*
X701279D03*
X697539Y1204232D03*
X693799D03*
X701279D03*
X693799Y1207972D03*
X697539D03*
Y1211712D03*
X701279Y1207972D03*
Y1211712D03*
X693799D03*
X740551Y1093897D03*
X751772Y1105117D03*
X682579Y1204232D03*
X678838D03*
X671358D03*
X675098D03*
X686319D03*
X682579Y1207972D03*
X675098Y1211712D03*
X678838Y1207972D03*
X675098D03*
X671358D03*
X686319D03*
Y1211712D03*
Y1215452D03*
X682579Y1211712D03*
X678839D03*
Y1215452D03*
X671358Y1211712D03*
Y1215452D03*
X675098D03*
X682579Y1118208D03*
Y1121948D03*
X671358Y1114468D03*
Y1118208D03*
X675098D03*
X678838D03*
X675098Y1121948D03*
X678838D03*
X671358D03*
X686319D03*
Y1118208D03*
Y1114468D03*
X682579D03*
X678839D03*
X675098D03*
X682579Y1125688D03*
X675098D03*
X671358D03*
X678838D03*
X686319D03*
X744290Y1093897D03*
X744291Y1105117D03*
X656398Y1204232D03*
X660138D03*
X663878D03*
X667618D03*
X663878Y1207972D03*
X660138D03*
X656398D03*
X667618D03*
Y1211712D03*
X663878D03*
X656398D03*
X660138Y1215452D03*
X656398D03*
X663878D03*
X667618D03*
X660138Y1211712D03*
X656398Y1118208D03*
Y1121948D03*
X663878Y1118208D03*
X660138D03*
Y1121948D03*
X663878D03*
X667618Y1118208D03*
Y1121948D03*
X660138Y1114468D03*
X656398D03*
X663878D03*
X667618D03*
X656398Y1125688D03*
X660138D03*
X663878D03*
X667618D03*
X740551Y1101376D03*
X751771Y1097637D03*
Y1093897D03*
X648917Y1118208D03*
Y1121948D03*
X652657Y1118208D03*
Y1121948D03*
X648917Y1114468D03*
X652657D03*
Y1125688D03*
X648917D03*
X748031Y1101376D03*
X740551Y1105117D03*
X755512Y1075196D03*
X762993D03*
X759251Y1090157D03*
X762991D03*
X676968Y1105117D03*
X684449Y1101377D03*
Y1105117D03*
X759252Y1086417D03*
X729331Y1101377D03*
X748031Y1120078D03*
X699408Y1093897D03*
X736810D03*
Y1097637D03*
X755511Y1090157D03*
X725590Y1097637D03*
X703149Y1108858D03*
X738681Y1207972D03*
X699409Y1105117D03*
X688189Y1108858D03*
X710630D03*
X748031Y1135039D03*
X684449Y1108858D03*
X744291D03*
X740551D03*
X691929D03*
X748031Y1131299D03*
Y1127558D03*
X721850Y1108858D03*
X650787D03*
X654527D03*
X658268D03*
X662008D03*
X665748D03*
X669488D03*
X673228D03*
X676968D03*
X680709D03*
X772342Y1189271D03*
X727461Y1215452D03*
X695669Y1108858D03*
X721850Y1101377D03*
X762992Y1116338D03*
X766732Y1120078D03*
X774212Y1093897D03*
X729330Y1097637D03*
X721849Y1093897D03*
X781693Y1101377D03*
X770472Y1097637D03*
X748031Y1116338D03*
X736811Y1108858D03*
X766732Y1086417D03*
X706889Y1071455D03*
X721849D03*
X759252D03*
X721850Y1105117D03*
X777953Y1093897D03*
X774212Y1101377D03*
X777953Y1105117D03*
X691929Y1101377D03*
X650787Y1101376D03*
X762992Y1131299D03*
X766732D03*
X774213Y1105117D03*
X762992Y1120078D03*
X762991Y1108857D03*
X766731Y1108858D03*
X777953Y1075196D03*
X766732Y1116338D03*
Y1123818D03*
X762992D03*
X777953Y1101377D03*
X770472D03*
Y1105117D03*
Y1093897D03*
X654527Y1105117D03*
Y1101377D03*
X781693Y1093897D03*
Y1097637D03*
X777953D03*
X774212D03*
Y1090157D03*
X781693Y1105117D03*
Y1090157D03*
X777953D03*
Y1078936D03*
X766732Y1135039D03*
X650787Y1105117D03*
X762992Y1112598D03*
X766732D03*
X781693Y1078936D03*
X762992Y1135039D03*
Y1127559D03*
Y1097637D03*
X770473Y1078936D03*
X774213Y1086417D03*
X658268Y1105117D03*
X762992Y1093897D03*
X759252Y1105117D03*
X762993Y1078936D03*
X766732Y1105117D03*
X774212Y1082677D03*
X725590Y1093897D03*
X665748Y1105117D03*
X755512Y1097637D03*
X770473Y1075196D03*
X762992Y1105117D03*
X755512Y1101376D03*
X766731Y1097637D03*
X759252Y1101377D03*
X755512Y1105117D03*
X766731Y1093897D03*
X766732Y1101377D03*
X766731Y1082677D03*
X755513Y1078936D03*
X759251Y1097637D03*
X770471Y1090157D03*
X781693Y1086417D03*
X777953D03*
X762992Y1101376D03*
X755512Y1093897D03*
X759251D03*
X781693Y1112598D03*
X770472Y1123818D03*
X676968Y1101377D03*
X777953Y1120078D03*
X781693D03*
X766732Y1127558D03*
X774212Y1123818D03*
X740551Y1075196D03*
X662008Y1105117D03*
X729331D03*
X733071Y1093897D03*
X736811Y1105117D03*
X733071Y1097637D03*
X736811Y1101377D03*
X721850Y1082677D03*
X729331Y1086417D03*
Y1082677D03*
X736811Y1086417D03*
X725590Y1075196D03*
X718110Y1101376D03*
X714369Y1093897D03*
Y1097637D03*
X706889Y1093897D03*
Y1097637D03*
X706890Y1101377D03*
Y1105117D03*
X714370D03*
Y1101377D03*
X710630Y1097637D03*
Y1093897D03*
X718110Y1097637D03*
Y1093897D03*
X710630Y1078936D03*
X706890Y1082677D03*
Y1086417D03*
Y1090157D03*
X718110Y1078936D03*
X714370Y1082677D03*
Y1086417D03*
Y1090157D03*
X710630D03*
X718110D03*
X703149Y1105117D03*
X699408Y1097637D03*
X691928Y1093897D03*
X699409Y1101377D03*
X703149Y1093897D03*
Y1097637D03*
Y1078936D03*
Y1090157D03*
Y1075196D03*
X695669Y1097637D03*
X691929Y1105117D03*
X691928Y1097637D03*
X695669Y1101376D03*
Y1105117D03*
X703149Y1101376D03*
X718110Y1075196D03*
X710630D03*
Y1105117D03*
Y1101376D03*
X718110Y1105117D03*
X733071Y1075196D03*
X736811Y1090157D03*
Y1082677D03*
X733071Y1090157D03*
Y1078936D03*
X729331Y1090157D03*
X725590D03*
X721850D03*
X725590Y1078936D03*
X721850Y1086417D03*
X688189Y1105117D03*
Y1101376D03*
X680708Y1105117D03*
Y1101376D03*
X673228Y1105117D03*
Y1101376D03*
X725590Y1105117D03*
X669488Y1101377D03*
Y1105117D03*
X733071Y1101376D03*
Y1105117D03*
X725590Y1101376D03*
X748031Y1075196D03*
X721849Y1097637D03*
X729330Y1093897D03*
X733071Y1108858D03*
X755512D03*
X759252D03*
Y1127559D03*
Y1135039D03*
X755512Y1131299D03*
Y1127558D03*
X759252Y1131299D03*
X755512Y1135039D03*
X759252Y1112598D03*
Y1120078D03*
X755512Y1116338D03*
X751772Y1108858D03*
X755512Y1123818D03*
X759252Y1116338D03*
X755512Y1120078D03*
X759252Y1123818D03*
X751771Y1131299D03*
X751772Y1127558D03*
Y1135039D03*
X751771Y1116338D03*
Y1123818D03*
Y1112598D03*
Y1120078D03*
X781693Y1127558D03*
X777953D03*
X774212Y1131299D03*
X770471D03*
X777953Y1135039D03*
X781693D03*
X770472Y1108858D03*
X774212D03*
X770472Y1116338D03*
X774212D03*
X777953Y1112598D03*
X714370Y1108858D03*
X706890D03*
X785434Y1090158D03*
Y1082677D03*
X766732Y1071455D03*
X774212D03*
X751771D03*
X785434Y1131300D03*
X729330Y1071455D03*
X785434Y1116339D03*
Y1123819D03*
Y1108859D03*
X736810Y1071455D03*
X785434Y1101378D03*
X744290Y1071455D03*
X714369D03*
X748031Y1123818D03*
X725590Y1108858D03*
X729331D03*
X748031D03*
Y1112598D03*
X699409Y1108858D03*
X1072342Y1174310D03*
Y1166830D03*
X1057381Y1151870D03*
X1064861Y1170570D03*
X1068602D03*
X1064861Y1166830D03*
X1068602D03*
X1061121Y1159350D03*
X1064862D03*
X1061122Y1166830D03*
X1057381Y1159350D03*
X1068602Y1174310D03*
X1064861D03*
X1094783D03*
Y1178051D03*
X1098523D03*
X1079822Y1174310D03*
X1087302Y1178051D03*
Y1174310D03*
X1091043Y1178051D03*
Y1174310D03*
X1076082D03*
X1079822Y1148129D03*
X1083562Y1151870D03*
X1079822Y1155610D03*
X1087302D03*
Y1159350D03*
X1083562D03*
X1091043D03*
X1061121Y1088287D03*
Y1095767D03*
Y1106988D03*
Y1099507D03*
Y1103247D03*
Y1118208D03*
Y1110728D03*
Y1121948D03*
Y1114468D03*
Y1140649D03*
X1064862D03*
X1068602D03*
X1072342D03*
X1064862Y1136909D03*
X1068602D03*
X1061121Y1133169D03*
Y1125688D03*
Y1136909D03*
X1064862Y1133169D03*
X1061121Y1129429D03*
X1076082Y1155610D03*
Y1151870D03*
Y1148129D03*
Y1144389D03*
X1072342Y1155610D03*
X1064862Y1148129D03*
X1068602Y1151869D03*
X1072342D03*
X1061121Y1144389D03*
X1064862D03*
X1076082Y1159350D03*
X1061121Y1092027D03*
Y1084547D03*
Y1080806D03*
Y1077066D03*
X1057381Y1118208D03*
Y1110728D03*
Y1121948D03*
Y1114468D03*
Y1140649D03*
Y1133169D03*
Y1125688D03*
Y1136909D03*
Y1129429D03*
Y1092027D03*
Y1084547D03*
Y1088287D03*
Y1095767D03*
Y1103247D03*
Y1106988D03*
Y1099507D03*
X1072342Y1077066D03*
X1068602D03*
X1076082D03*
X1072342Y1073326D03*
X1068602D03*
X1076082D03*
X1072342Y1099507D03*
Y1095767D03*
Y1106988D03*
Y1103247D03*
Y1121948D03*
Y1118208D03*
Y1114468D03*
Y1110728D03*
Y1129429D03*
Y1125688D03*
Y1092027D03*
Y1088287D03*
Y1084547D03*
Y1080807D03*
X1068602Y1125688D03*
Y1084547D03*
Y1080807D03*
Y1095767D03*
Y1106988D03*
Y1099507D03*
Y1103247D03*
Y1121948D03*
Y1114468D03*
Y1110728D03*
Y1118208D03*
Y1129429D03*
Y1092027D03*
Y1088287D03*
X1098523Y1140649D03*
X1094783Y1136909D03*
Y1140649D03*
X1098523Y1148129D03*
X1094783Y1151870D03*
Y1148129D03*
Y1144389D03*
X1098523D03*
Y1151870D03*
X1091043Y1140649D03*
X1079822Y1136909D03*
X1083562D03*
X1087302D03*
X1079822Y1129429D03*
X1083562Y1129428D03*
X1087302D03*
X1079822Y1140649D03*
X1083562D03*
X1087302D03*
X1091043Y1136909D03*
Y1133169D03*
X1087302Y1148129D03*
X1083562Y1144389D03*
X1087302D03*
X1091043Y1151870D03*
Y1148129D03*
Y1144389D03*
X1076082Y1092027D03*
Y1088287D03*
Y1084547D03*
Y1080807D03*
Y1106988D03*
Y1095767D03*
Y1103247D03*
Y1099507D03*
Y1114468D03*
Y1121948D03*
Y1118208D03*
Y1110728D03*
Y1133169D03*
Y1129429D03*
Y1125688D03*
Y1136909D03*
X1205117Y1213582D03*
Y1209842D03*
X1137795Y1108858D03*
X1205117Y1123818D03*
X1190157Y1108858D03*
X1205117Y1198621D03*
X1152755Y1108858D03*
X1205117Y1202362D03*
X1240589Y1193011D03*
X1240649Y1140649D03*
Y1148129D03*
Y1155610D03*
Y1151870D03*
Y1144389D03*
Y1166830D03*
Y1170570D03*
Y1159350D03*
Y1178051D03*
Y1185531D03*
Y1174310D03*
Y1181791D03*
Y1189271D03*
X1236909Y1178051D03*
Y1185531D03*
X1229428Y1181791D03*
Y1189271D03*
X1233169D03*
Y1185531D03*
Y1181791D03*
Y1178051D03*
X1229428Y1174310D03*
X1233169D03*
X1225688D03*
Y1181791D03*
Y1189271D03*
X1236909Y1181791D03*
X1225688Y1185531D03*
X1236909Y1189271D03*
X1229428Y1178051D03*
Y1185531D03*
X1236909Y1174310D03*
X1225688Y1178051D03*
X1233169Y1193011D03*
X1236909D03*
X1229428D03*
X1236909Y1140649D03*
X1233169D03*
X1225688D03*
X1229428D03*
X1236909Y1148129D03*
Y1155610D03*
X1233169Y1144389D03*
X1225688D03*
Y1151869D03*
X1229428Y1144389D03*
X1233169Y1155610D03*
X1229428Y1151869D03*
X1233169D03*
Y1148129D03*
X1236909Y1151870D03*
X1225688Y1148129D03*
X1229428D03*
X1225688Y1155610D03*
X1236909Y1144389D03*
X1229428Y1155610D03*
X1236909Y1170570D03*
Y1166830D03*
X1225688D03*
X1229428Y1159350D03*
X1233169D03*
X1225688D03*
X1229428Y1166830D03*
X1233169Y1170570D03*
Y1166830D03*
X1229428Y1170570D03*
X1225688D03*
X1236909Y1159350D03*
X1210728Y1181791D03*
X1206987D03*
X1210728Y1189271D03*
X1218208Y1185531D03*
Y1178051D03*
X1214468Y1189271D03*
X1221948Y1178051D03*
Y1185531D03*
X1206987Y1174310D03*
Y1189271D03*
X1214468Y1185531D03*
Y1181791D03*
Y1178051D03*
Y1174310D03*
X1210728D03*
X1218208Y1189271D03*
Y1174310D03*
X1221948Y1181791D03*
Y1174310D03*
X1218208Y1181791D03*
X1221948Y1189271D03*
X1208858Y1194881D03*
X1218208Y1193011D03*
X1221948Y1140649D03*
X1206988D03*
X1221948Y1155610D03*
X1210728Y1151869D03*
X1206987D03*
X1218208Y1155610D03*
Y1148129D03*
X1214468Y1155610D03*
Y1151869D03*
Y1148129D03*
Y1144389D03*
X1206987D03*
X1210728D03*
X1221948Y1148129D03*
X1218208Y1144389D03*
Y1151869D03*
X1206988Y1155610D03*
Y1148129D03*
X1210728Y1155610D03*
X1221948Y1151869D03*
Y1144389D03*
X1206987Y1159350D03*
X1210728D03*
X1214468D03*
X1210728Y1166830D03*
X1206987D03*
X1218208Y1170570D03*
X1214468D03*
Y1166830D03*
X1221948Y1170570D03*
Y1159350D03*
X1218208Y1166830D03*
Y1159350D03*
X1221948Y1166830D03*
X1210728Y1170570D03*
X1206988D03*
X1218208Y1140649D03*
X1214468D03*
X1192027Y1211712D03*
X1195767D03*
X1192027Y1215452D03*
X1199507Y1211712D03*
Y1215452D03*
Y1207972D03*
X1195767Y1215452D03*
X1192027Y1207972D03*
Y1166830D03*
Y1170570D03*
Y1181791D03*
X1199507Y1185531D03*
X1203247Y1174310D03*
Y1178051D03*
Y1185531D03*
X1192027Y1178051D03*
Y1189271D03*
X1195767D03*
X1192027Y1185531D03*
X1195767D03*
X1199507Y1181791D03*
X1195767Y1178051D03*
Y1174310D03*
X1203247Y1189271D03*
X1199507D03*
Y1174310D03*
X1195767Y1181791D03*
X1192027Y1174310D03*
X1199507Y1178051D03*
X1203247Y1181791D03*
X1195767Y1204232D03*
X1199507Y1193011D03*
X1203247D03*
X1195767Y1196751D03*
Y1193011D03*
X1192027D03*
X1199507Y1196751D03*
Y1200491D03*
Y1204232D03*
X1195767Y1200491D03*
X1192027Y1204232D03*
Y1200491D03*
Y1196751D03*
Y1136909D03*
X1195767Y1140649D03*
X1192027Y1133169D03*
Y1140649D03*
X1195767Y1136909D03*
X1192027Y1125688D03*
Y1129429D03*
X1199507Y1140649D03*
Y1136909D03*
X1203247Y1140649D03*
X1195767Y1148129D03*
X1192027Y1144389D03*
X1195767Y1155610D03*
X1192027Y1148129D03*
X1195767Y1151869D03*
X1199507D03*
X1203247D03*
Y1155610D03*
Y1144389D03*
X1192027Y1151870D03*
X1199507Y1155610D03*
X1192027D03*
X1203247Y1148129D03*
X1195767Y1144389D03*
X1199507Y1148129D03*
Y1144389D03*
X1195767Y1170570D03*
Y1159350D03*
X1203247Y1166830D03*
Y1170570D03*
Y1159350D03*
X1195767Y1166830D03*
X1199507Y1170570D03*
Y1166830D03*
Y1159350D03*
X1192027D03*
Y1118208D03*
Y1121948D03*
X1199507Y1118208D03*
X1195767D03*
Y1114468D03*
X1192027D03*
X1199507D03*
X1188287Y1181791D03*
Y1174310D03*
X1177066Y1189271D03*
X1180806D03*
X1184546Y1178051D03*
X1177066Y1174310D03*
X1184546Y1185531D03*
X1177066Y1181791D03*
X1180806D03*
X1184546Y1189271D03*
Y1174310D03*
X1177066Y1185531D03*
Y1178051D03*
X1180806Y1185531D03*
Y1178051D03*
X1184546Y1181791D03*
X1188287Y1185531D03*
Y1189271D03*
Y1178051D03*
X1184546Y1204232D03*
X1177066D03*
X1180806D03*
X1184546Y1200491D03*
X1177066Y1196751D03*
X1180806D03*
X1184546Y1193011D03*
X1188287Y1204232D03*
Y1196751D03*
X1184566Y1196732D03*
X1180806Y1200491D03*
X1177066D03*
X1188287D03*
X1177066Y1193011D03*
X1180806D03*
X1188287D03*
Y1207972D03*
X1184546Y1211712D03*
X1177066Y1207972D03*
Y1211712D03*
X1180806Y1207972D03*
Y1211712D03*
X1184546Y1207972D03*
X1188287Y1215452D03*
X1180806D03*
X1177066D03*
X1188287Y1211712D03*
Y1125688D03*
X1184546Y1136909D03*
X1177066Y1133169D03*
X1180806D03*
X1184546D03*
X1177066Y1140649D03*
X1180806D03*
X1184546Y1125688D03*
Y1129429D03*
X1177066Y1125688D03*
X1180806D03*
X1184546Y1140649D03*
X1180806Y1129429D03*
X1177066D03*
X1188287D03*
X1180806Y1136909D03*
X1177066D03*
X1188287D03*
Y1140649D03*
Y1155610D03*
Y1151869D03*
Y1148129D03*
X1177066D03*
X1180806D03*
X1184546Y1144389D03*
Y1148129D03*
Y1151869D03*
X1177066Y1155610D03*
X1184546D03*
X1180806Y1151869D03*
X1177066D03*
Y1144389D03*
X1180806D03*
X1188287D03*
X1177066Y1166830D03*
X1188287D03*
Y1159350D03*
Y1170570D03*
X1180806D03*
X1184546D03*
X1177066D03*
X1184546Y1166830D03*
X1180806D03*
X1177066Y1159350D03*
X1180806D03*
X1184546D03*
X1188287Y1118208D03*
Y1121948D03*
X1184546Y1118208D03*
X1180806Y1121948D03*
X1177066D03*
X1184546D03*
X1188287Y1114468D03*
X1177066D03*
Y1118208D03*
X1184546Y1114468D03*
X1158365Y1211712D03*
Y1207972D03*
X1173326D03*
Y1211712D03*
X1162106Y1207972D03*
X1165846D03*
X1173326Y1215452D03*
X1165846D03*
X1169586D03*
X1162105Y1215451D03*
Y1211711D03*
X1165846D03*
X1173326Y1189271D03*
X1158365Y1181791D03*
X1162106D03*
X1165846D03*
X1169586D03*
X1158365Y1189271D03*
X1162106D03*
X1165846D03*
X1169586D03*
X1173326Y1181791D03*
X1169586Y1174310D03*
X1162106D03*
X1158365Y1185531D03*
X1162106D03*
X1169586D03*
X1165846D03*
X1173326D03*
X1165846Y1178051D03*
X1158365D03*
X1162106D03*
X1169586D03*
X1173326D03*
X1162106Y1204232D03*
X1158365D03*
X1169586D03*
X1165846D03*
X1158365Y1196751D03*
X1162106D03*
X1165846D03*
X1169586D03*
X1173326Y1204232D03*
Y1196751D03*
Y1200491D03*
X1165846D03*
X1162106D03*
X1158365D03*
X1169586D03*
X1165846Y1193011D03*
X1169586D03*
X1158365D03*
X1162106D03*
X1173326D03*
X1169586Y1211712D03*
Y1207972D03*
X1162106Y1133169D03*
X1165846D03*
X1169586D03*
X1158365Y1140649D03*
X1162106D03*
X1165846D03*
X1169586D03*
X1158365Y1125688D03*
X1162106D03*
X1165846D03*
X1169586D03*
X1173326Y1133169D03*
Y1125688D03*
Y1140649D03*
X1158365Y1133169D03*
X1169586Y1129429D03*
X1165846D03*
X1162106D03*
X1158365D03*
X1173326D03*
Y1136909D03*
X1169586D03*
X1165846D03*
X1158365D03*
X1162106D03*
X1173326Y1148129D03*
X1158365D03*
X1162106D03*
X1165846D03*
X1169586D03*
X1162106Y1155610D03*
X1169586D03*
X1173326Y1151869D03*
X1158365D03*
X1162106D03*
X1169586D03*
X1165846D03*
X1173326Y1144389D03*
X1165846D03*
X1158365D03*
X1162106D03*
X1169586D03*
X1158365Y1170570D03*
X1165846D03*
X1169586Y1166830D03*
X1158365Y1159350D03*
X1162106Y1166830D03*
X1165846Y1159350D03*
X1173326D03*
Y1170570D03*
X1169586Y1121948D03*
X1165846D03*
X1162106D03*
X1158365D03*
X1173326D03*
X1162106Y1114468D03*
X1169586D03*
X1162106Y1118208D03*
X1173326Y1114468D03*
X1158365Y1118208D03*
X1173326D03*
X1165846Y1114468D03*
X1158365D03*
X1169586Y1118208D03*
X1165846D03*
X1150885Y1196751D03*
X1154625Y1204232D03*
X1150885D03*
X1154625Y1196751D03*
X1143405D03*
Y1204232D03*
Y1200491D03*
X1154625D03*
X1150885D03*
Y1193011D03*
X1154625D03*
X1143405D03*
X1150885Y1207972D03*
X1154625D03*
Y1211712D03*
X1143405Y1207972D03*
Y1211712D03*
Y1215452D03*
X1150885Y1211712D03*
X1143405Y1148129D03*
X1150885D03*
X1154625D03*
X1143405Y1155610D03*
X1154625D03*
X1143405Y1144389D03*
X1150885Y1151869D03*
X1154625D03*
Y1144389D03*
X1150885D03*
X1143405Y1151870D03*
X1154625Y1166830D03*
X1150885Y1170570D03*
X1143405Y1166830D03*
X1150885Y1159350D03*
X1143405Y1181791D03*
X1154625D03*
X1150885D03*
Y1189271D03*
X1154625D03*
X1143405D03*
Y1174310D03*
X1154625D03*
X1143405Y1178051D03*
Y1185531D03*
X1154625D03*
X1150885D03*
X1154625Y1178051D03*
X1150885D03*
Y1121948D03*
X1143405D03*
Y1118208D03*
Y1114468D03*
X1154625Y1121948D03*
Y1118208D03*
X1150885D03*
X1154625Y1114468D03*
X1150885D03*
X1154625Y1125688D03*
X1150885Y1133464D03*
X1154625Y1133169D03*
X1143503Y1132677D03*
X1143405Y1140649D03*
Y1125688D03*
X1150885Y1140649D03*
X1154625D03*
X1150885Y1125688D03*
X1154625Y1129429D03*
X1150885D03*
X1143405D03*
Y1136909D03*
X1154625D03*
X1150885D03*
X1135924Y1181791D03*
X1132184D03*
X1128444D03*
X1135924Y1189271D03*
X1132184D03*
X1128444D03*
Y1174310D03*
X1135924D03*
X1139665Y1178051D03*
X1135924D03*
X1132184D03*
X1128444D03*
X1139665Y1185531D03*
X1132184D03*
X1128444D03*
X1135924D03*
X1139665Y1196751D03*
Y1204232D03*
X1135924D03*
Y1196751D03*
X1132184D03*
X1128444D03*
Y1204232D03*
X1132184D03*
Y1200491D03*
X1128444D03*
X1135924D03*
X1139665D03*
X1128444Y1193011D03*
X1132184D03*
X1135924D03*
X1139665D03*
Y1207972D03*
X1132184Y1211712D03*
X1135924Y1207972D03*
X1132184D03*
X1128444D03*
X1139665Y1211712D03*
X1135925D03*
X1128444Y1215452D03*
Y1211712D03*
X1139665Y1125688D03*
X1128444Y1140649D03*
X1132184D03*
X1135924D03*
X1132184Y1125688D03*
X1128444D03*
X1135924D03*
Y1133169D03*
X1132184D03*
X1128444D03*
X1132184Y1129429D03*
X1128444D03*
X1135924D03*
X1139665D03*
Y1136909D03*
X1135924D03*
X1132184D03*
X1128444D03*
X1135924Y1148129D03*
X1132184D03*
X1128444D03*
X1139665D03*
X1128444Y1155610D03*
X1135924D03*
X1128444Y1144389D03*
X1135924D03*
X1132184D03*
X1139665D03*
X1135925Y1151870D03*
X1132184D03*
X1128444D03*
X1139665D03*
Y1170570D03*
Y1159350D03*
X1132184Y1170570D03*
X1135925Y1166830D03*
X1128444D03*
X1132184Y1159350D03*
X1139665Y1181791D03*
Y1189271D03*
Y1121948D03*
X1128444Y1118208D03*
X1132184D03*
X1135924D03*
X1132184Y1121948D03*
X1135924D03*
X1128444D03*
X1139665Y1118208D03*
Y1114468D03*
X1135925D03*
X1139665Y1133169D03*
Y1140649D03*
X1124704Y1204232D03*
Y1196751D03*
X1120964Y1204232D03*
X1117224D03*
X1113484D03*
X1109743D03*
Y1193011D03*
Y1196751D03*
Y1200491D03*
X1113484Y1196751D03*
X1117224D03*
X1120964D03*
X1117224Y1200491D03*
X1120964D03*
X1113484D03*
X1124704D03*
X1120964Y1193011D03*
X1117224D03*
X1113484D03*
X1124704D03*
X1113484Y1207972D03*
X1117224D03*
X1120964D03*
X1109743Y1211712D03*
Y1207972D03*
X1124704Y1211712D03*
Y1207972D03*
Y1215452D03*
X1120964D03*
Y1211712D03*
X1113484D03*
X1117224D03*
X1113484Y1155610D03*
X1109743Y1144389D03*
X1120964Y1155610D03*
X1109743Y1151869D03*
X1124704Y1144389D03*
X1113484D03*
X1117224D03*
X1120964D03*
X1113484Y1151870D03*
X1117224D03*
X1120964D03*
X1124704D03*
X1117224Y1170570D03*
X1109743D03*
X1113484Y1166830D03*
X1117224Y1159350D03*
X1120964Y1166830D03*
X1109743Y1159350D03*
X1124704Y1170570D03*
Y1159350D03*
X1109743Y1189271D03*
X1113484D03*
X1117224D03*
X1120964D03*
X1113484Y1181791D03*
X1117224D03*
X1120964D03*
X1124704Y1189271D03*
Y1181791D03*
X1109743Y1178051D03*
X1120964Y1174310D03*
X1109743Y1185531D03*
X1113484Y1174310D03*
Y1178051D03*
X1117224D03*
X1120964D03*
X1124704D03*
X1120964Y1185531D03*
X1113484D03*
X1117224D03*
X1124704D03*
X1117224Y1121948D03*
Y1118208D03*
X1120964D03*
X1109743Y1121948D03*
X1113484D03*
X1109743Y1118208D03*
X1113484D03*
X1124704Y1121948D03*
Y1118208D03*
X1120964Y1121948D03*
X1117224Y1114468D03*
X1113484D03*
X1120964D03*
X1124704D03*
X1109743D03*
Y1136909D03*
X1124704Y1125688D03*
Y1140649D03*
Y1133169D03*
X1113484D03*
X1117224D03*
X1120964D03*
X1109743Y1125688D03*
X1120964D03*
X1117224D03*
X1113484D03*
X1120964Y1140649D03*
X1117224D03*
X1113484D03*
X1109743Y1129429D03*
Y1133169D03*
X1120964Y1129429D03*
X1113484D03*
X1117224D03*
X1124704D03*
Y1136909D03*
X1113484D03*
X1117224D03*
X1120964D03*
X1109743Y1140649D03*
X1120964Y1148129D03*
X1113484D03*
X1117224D03*
X1124704D03*
X1106003Y1207972D03*
Y1211712D03*
Y1215452D03*
Y1181791D03*
Y1174310D03*
Y1200491D03*
Y1196751D03*
Y1204232D03*
Y1193011D03*
Y1125688D03*
Y1140649D03*
Y1136909D03*
Y1133169D03*
Y1129429D03*
Y1148129D03*
Y1155610D03*
Y1121948D03*
Y1118208D03*
Y1114468D03*
X1242520Y1090158D03*
X1130314Y1108858D03*
X1160235D03*
X1175196D03*
X1171455Y1071455D03*
X1205117Y1127558D03*
X1186416Y1071455D03*
X1208857D03*
X1195767Y1207972D03*
X1182676Y1108858D03*
X1205117Y1206102D03*
X1184547Y1215452D03*
X1163976Y1108858D03*
X1201377D03*
X1178935Y1071455D03*
X1197637Y1108858D03*
X1212598Y1224803D03*
Y1228543D03*
X1220078Y1224803D03*
Y1228543D03*
X1216338Y1232283D03*
Y1236023D03*
X1223818D03*
Y1232283D03*
X1216338Y1224803D03*
Y1228543D03*
X1212598Y1232283D03*
Y1236023D03*
X1223818Y1228543D03*
X1220078Y1232283D03*
Y1236023D03*
Y1243503D03*
Y1247243D03*
X1212598D03*
Y1243503D03*
X1216338Y1247243D03*
Y1243503D03*
X1223818Y1247243D03*
Y1243503D03*
X1212598Y1239763D03*
X1216338D03*
X1220078D03*
X1223818D03*
X1227558Y1228543D03*
X1235039D03*
X1238779D03*
X1231298Y1232283D03*
Y1236023D03*
X1238779Y1224803D03*
X1235039D03*
X1231298D03*
Y1228543D03*
X1227558Y1236023D03*
Y1232283D03*
X1238779D03*
X1235039D03*
Y1236023D03*
X1238779D03*
Y1239763D03*
X1235039D03*
X1238779Y1247243D03*
X1235039D03*
X1227558D03*
Y1243503D03*
X1231298Y1247243D03*
Y1243503D03*
X1235039D03*
X1238779D03*
X1227558Y1239763D03*
X1231298D03*
X1220078Y1202362D03*
X1216338D03*
X1212598Y1206102D03*
Y1198621D03*
X1223818Y1206102D03*
X1220078D03*
X1216338D03*
X1212598Y1202362D03*
X1223818D03*
Y1198621D03*
X1220078D03*
X1216338D03*
X1208858Y1206102D03*
Y1198621D03*
Y1202362D03*
X1220078Y1217322D03*
X1216338D03*
X1212598Y1213582D03*
X1216338Y1209842D03*
X1220078D03*
X1223818Y1217322D03*
X1220078Y1221062D03*
X1216338D03*
X1212598D03*
Y1217322D03*
X1216338Y1213582D03*
X1220078D03*
X1223818D03*
Y1209842D03*
X1212598D03*
X1208858Y1213582D03*
Y1217322D03*
Y1209842D03*
X1238779Y1198621D03*
X1231298Y1202362D03*
X1227558D03*
X1235039Y1206102D03*
X1238779D03*
Y1202362D03*
X1235039D03*
X1231298Y1206102D03*
X1227558D03*
X1238779Y1213582D03*
X1235039D03*
X1238779Y1221062D03*
X1235039D03*
X1231298Y1217322D03*
X1227558D03*
Y1209842D03*
X1231298D03*
X1238779Y1217322D03*
X1235039D03*
X1231298Y1221062D03*
X1238779Y1209842D03*
X1235039D03*
X1231298Y1213582D03*
X1227558D03*
X1107873Y1101376D03*
X1115354D03*
X1122834D03*
X1119094Y1101377D03*
X1126574D03*
X1111613D03*
X1137794Y1101376D03*
X1130314D03*
X1134054Y1101377D03*
X1141535D03*
X1152755Y1075196D03*
Y1090157D03*
X1156495D03*
Y1086417D03*
X1152755Y1078936D03*
X1156495Y1082677D03*
X1152755Y1101376D03*
X1156494Y1093897D03*
Y1097637D03*
X1149014D03*
Y1093897D03*
X1149015Y1101377D03*
X1152755Y1093897D03*
Y1097637D03*
X1156495Y1101377D03*
X1145275Y1101376D03*
X1167716Y1075196D03*
X1175196D03*
X1160235D03*
X1167716Y1078936D03*
X1163976Y1082677D03*
Y1086417D03*
Y1090157D03*
X1175196Y1078936D03*
X1171456Y1082677D03*
Y1086417D03*
Y1090157D03*
X1167716D03*
X1175196D03*
X1160235Y1078936D03*
Y1090157D03*
X1175196Y1101376D03*
X1167716D03*
X1171455Y1093897D03*
Y1097637D03*
X1163975Y1093897D03*
Y1097637D03*
X1163976Y1101377D03*
X1171456D03*
X1167716Y1097637D03*
Y1093897D03*
X1175196Y1097637D03*
Y1093897D03*
X1160235Y1101376D03*
Y1093897D03*
Y1097637D03*
X1182676Y1075196D03*
X1190157D03*
X1178936Y1090157D03*
X1182676Y1078936D03*
X1178936Y1082677D03*
Y1086417D03*
X1182676Y1090157D03*
X1186417D03*
Y1086417D03*
Y1082677D03*
X1190157Y1078936D03*
Y1090157D03*
Y1101376D03*
X1182676D03*
X1186416Y1093897D03*
Y1097637D03*
X1178935Y1093897D03*
Y1097637D03*
X1178936Y1101377D03*
X1186417D03*
X1182676Y1097637D03*
Y1093897D03*
X1190157D03*
Y1097637D03*
X1197637Y1075196D03*
X1205117D03*
X1197637Y1078936D03*
Y1090157D03*
X1201377D03*
Y1086417D03*
Y1082677D03*
X1205117Y1078936D03*
X1205116Y1090157D03*
X1193897Y1082677D03*
Y1086417D03*
Y1090157D03*
X1205117Y1101376D03*
X1197637D03*
X1201376Y1097637D03*
Y1093897D03*
X1197637Y1097637D03*
X1201377Y1101377D03*
X1197637Y1093897D03*
X1205117D03*
Y1097637D03*
X1193896D03*
Y1093897D03*
X1193897Y1101377D03*
X1212598Y1075196D03*
X1220079D03*
Y1078936D03*
X1212599D03*
X1223817Y1082677D03*
X1216337D03*
X1216338Y1086417D03*
X1223818D03*
X1212597Y1090157D03*
X1216337D03*
X1220077D03*
X1223817D03*
X1208857Y1082677D03*
X1208858Y1086417D03*
X1208857Y1090157D03*
X1220078Y1101376D03*
X1212598D03*
X1223817Y1093897D03*
Y1097637D03*
X1216337Y1093897D03*
Y1097637D03*
X1212598Y1093897D03*
X1220078D03*
X1212598Y1097637D03*
X1220078D03*
X1223818Y1101377D03*
X1216338D03*
X1208857Y1097637D03*
Y1093897D03*
Y1101377D03*
X1227559Y1075196D03*
X1235039D03*
X1238779Y1090157D03*
X1235039D03*
Y1078936D03*
X1227559D03*
X1231298Y1082677D03*
X1238779Y1086417D03*
X1235039D03*
X1231299D03*
X1227557Y1090157D03*
X1231298D03*
X1238779Y1078936D03*
X1231298Y1097637D03*
Y1093897D03*
X1227558Y1101377D03*
X1238779D03*
X1235039D03*
X1227558Y1093897D03*
Y1097637D03*
X1231298Y1101377D03*
X1235039Y1093897D03*
X1238779D03*
Y1097637D03*
X1235039D03*
X1107873Y1105117D03*
X1115354D03*
X1122834D03*
X1119094D03*
X1126574D03*
X1111613D03*
X1137794D03*
X1130314D03*
X1134054D03*
X1141535D03*
X1152755D03*
X1149015D03*
X1156495D03*
X1145275D03*
X1175196D03*
X1167716D03*
X1163976D03*
X1171456D03*
X1160235D03*
X1190157D03*
X1182676D03*
X1178936D03*
X1186417D03*
X1205117D03*
X1197637D03*
X1201377D03*
X1193897D03*
X1220078D03*
X1212598D03*
X1216338D03*
X1223818D03*
X1208858D03*
X1227558D03*
X1231299D03*
X1212598Y1108858D03*
X1216338D03*
Y1112598D03*
Y1120078D03*
X1212598Y1116338D03*
Y1123818D03*
X1216338Y1116338D03*
X1212598Y1120078D03*
X1216338Y1123818D03*
X1208857Y1116338D03*
Y1123818D03*
Y1112598D03*
Y1120078D03*
X1220078Y1112598D03*
Y1120078D03*
X1220077Y1108857D03*
X1223817Y1108858D03*
X1223818Y1116338D03*
X1220078D03*
X1223818Y1112598D03*
Y1123818D03*
X1220078D03*
X1223818Y1120078D03*
X1216338Y1127559D03*
X1212598Y1131299D03*
Y1127558D03*
X1216338Y1131299D03*
X1208857D03*
X1208858Y1127558D03*
X1220078Y1127559D03*
X1223818Y1127558D03*
Y1131299D03*
X1220078D03*
X1235039Y1105117D03*
X1238779D03*
X1227558Y1108858D03*
X1231298D03*
X1227558Y1116338D03*
X1231298D03*
X1235039Y1112598D03*
X1238779D03*
X1227558Y1123818D03*
X1231298D03*
X1235039Y1120078D03*
X1238779D03*
Y1127558D03*
X1235039D03*
X1231298Y1131299D03*
X1227557D03*
X1216338Y1135039D03*
X1220078D03*
X1223818D03*
X1212598D03*
X1126574Y1108858D03*
X1186417D03*
X1208858D03*
X1216338Y1071455D03*
X1201376D03*
X1193896D03*
X1156494D03*
X1242520Y1228543D03*
Y1239762D03*
Y1247243D03*
Y1221062D03*
Y1198621D03*
Y1206102D03*
Y1213582D03*
Y1101378D03*
X1231298Y1071455D03*
X1223818D03*
X1242520Y1082677D03*
Y1108859D03*
Y1116339D03*
Y1123819D03*
Y1131300D03*
X1163975Y1071455D03*
X1122834Y1108858D03*
X1149015D03*
X1178936D03*
X1205117Y1120078D03*
X1145275Y1108858D03*
X1115354D03*
X1134054D03*
X1119094D03*
X1205117Y1131299D03*
X1193897Y1108858D03*
X1205117D03*
Y1116338D03*
X1111613Y1108858D03*
X1141535D03*
X1107873D03*
X1156495D03*
X1167716D03*
X1171456D03*
X1531299Y1254724D03*
X1523819D03*
X1546259D03*
X1538779D03*
X1561220D03*
X1553740D03*
X1637893Y1170570D03*
X1634153D03*
X1637893Y1166830D03*
Y1159350D03*
X1634153D03*
Y1189271D03*
X1637893D03*
X1634153Y1174310D03*
X1630413Y1181791D03*
X1634153D03*
X1637893D03*
X1630413Y1189271D03*
Y1185531D03*
X1634153D03*
X1630413Y1178051D03*
X1634153D03*
X1637893Y1185531D03*
Y1178051D03*
X1634153Y1193011D03*
X1637893D03*
X1630413D03*
X1634153Y1140649D03*
X1637893D03*
X1630413D03*
Y1136909D03*
X1637893D03*
X1634153D03*
X1630413Y1148129D03*
X1634153D03*
X1637893D03*
X1634153Y1155610D03*
X1630413Y1151869D03*
X1637893D03*
X1634153D03*
Y1144389D03*
X1630413D03*
X1637893D03*
X1634153Y1166830D03*
X1630413Y1159350D03*
Y1170570D03*
X1619193Y1185531D03*
X1626673D03*
X1622933D03*
Y1178051D03*
X1615452D03*
X1619193D03*
X1626673D03*
X1622933Y1193011D03*
X1626673D03*
X1615452D03*
X1619193D03*
X1615452Y1140649D03*
X1619193D03*
X1622933D03*
X1626673D03*
Y1136909D03*
X1622933D03*
X1615452D03*
X1619193D03*
X1615452Y1148129D03*
X1619193D03*
X1622933D03*
X1626673D03*
X1619193Y1155610D03*
X1626673D03*
X1615452Y1151869D03*
X1619193D03*
X1626673D03*
X1622933D03*
Y1144389D03*
X1615452D03*
X1619193D03*
X1626673D03*
X1615452Y1170570D03*
X1622933D03*
X1626673Y1166830D03*
X1615452Y1159350D03*
X1619193Y1166830D03*
X1622933Y1159350D03*
X1615452Y1181791D03*
X1619193D03*
X1622933D03*
X1626673D03*
X1615452Y1189271D03*
X1619193D03*
X1622933D03*
X1626673D03*
Y1174310D03*
X1619193D03*
X1615452Y1185531D03*
X1600492Y1136909D03*
X1596752D03*
X1611712D03*
X1607972D03*
X1600492Y1148129D03*
X1596752D03*
X1607972D03*
X1611712D03*
X1600492Y1155610D03*
X1611712D03*
X1600492Y1144389D03*
X1596752D03*
X1611712Y1151869D03*
X1607972D03*
X1611712Y1144389D03*
X1607972D03*
X1600492Y1151870D03*
X1596752D03*
Y1170570D03*
Y1159350D03*
X1611712Y1166830D03*
X1607972Y1170570D03*
X1600492Y1166830D03*
X1607972Y1159350D03*
X1600492Y1181791D03*
X1611712D03*
X1607972D03*
Y1189271D03*
X1611712D03*
X1596752Y1181791D03*
X1600492Y1189271D03*
X1596752D03*
X1600492Y1174310D03*
X1611712D03*
X1600492Y1185531D03*
X1596752D03*
X1600492Y1178051D03*
X1596752D03*
X1611712Y1185531D03*
X1607972D03*
X1611712Y1178051D03*
X1607972D03*
Y1193011D03*
X1611712D03*
X1600492D03*
X1596752D03*
X1607972Y1133464D03*
X1596752Y1140649D03*
X1600492D03*
X1607972D03*
X1611712D03*
X1581791D03*
X1585531D03*
X1589271D03*
X1593011D03*
Y1136909D03*
X1589271D03*
X1585531D03*
X1581791D03*
X1593011Y1148129D03*
X1589271D03*
X1585531D03*
X1581791D03*
X1593011Y1155610D03*
X1585531D03*
Y1144389D03*
X1581791D03*
X1593011D03*
X1589271D03*
X1593012Y1151870D03*
X1589271D03*
X1585531D03*
X1581791D03*
X1589271Y1170570D03*
X1593012Y1166830D03*
X1585531D03*
X1581791Y1159350D03*
X1589271D03*
X1581791Y1170570D03*
X1593011Y1181791D03*
X1589271D03*
X1585531D03*
X1581791D03*
X1593011Y1189271D03*
X1589271D03*
X1585531D03*
X1581791D03*
X1585531Y1174310D03*
X1593011D03*
X1589271Y1185531D03*
X1585531D03*
X1581791D03*
X1593011D03*
X1581791Y1178051D03*
X1593011D03*
X1589271D03*
X1585531D03*
Y1193011D03*
X1589271D03*
X1593011D03*
X1581791D03*
X1570571D03*
X1574311D03*
X1578051D03*
X1570571Y1140649D03*
X1574311D03*
X1578051D03*
X1566830Y1136909D03*
X1578051D03*
X1574311D03*
X1570571D03*
X1566830Y1140649D03*
X1574311Y1148129D03*
X1570571D03*
X1578051D03*
X1570571Y1155610D03*
X1566830Y1151869D03*
X1578051Y1155610D03*
X1566830Y1144389D03*
X1578051D03*
X1574311D03*
X1570571D03*
X1578051Y1151870D03*
X1574311D03*
X1570571D03*
X1566830Y1159350D03*
X1578051Y1166830D03*
X1574311Y1159350D03*
X1570571Y1166830D03*
X1566830Y1170570D03*
X1574311D03*
X1578051Y1181791D03*
X1574311D03*
X1570571D03*
X1578051Y1189271D03*
X1574311D03*
X1570571D03*
X1566830D03*
Y1178051D03*
X1570571Y1174310D03*
X1566830Y1185531D03*
X1578051Y1174310D03*
X1574311Y1185531D03*
X1570571D03*
X1578051D03*
Y1178051D03*
X1574311D03*
X1570571D03*
X1566830Y1196751D03*
Y1193011D03*
X1559350D03*
Y1196751D03*
Y1200491D03*
X1555610D03*
Y1204232D03*
X1559350D03*
X1563090D03*
Y1196751D03*
Y1200491D03*
X1555610Y1193011D03*
Y1196751D03*
X1563090Y1193011D03*
X1555610Y1211712D03*
X1559350D03*
X1563090D03*
Y1207972D03*
X1559350D03*
X1555610D03*
X1563090Y1215452D03*
X1559350D03*
X1548130Y1140649D03*
X1559350Y1136909D03*
X1551870D03*
X1548130D03*
X1559350Y1140649D03*
X1555610D03*
X1551870D03*
X1563090D03*
Y1136909D03*
X1555610D03*
X1551870Y1155610D03*
Y1151870D03*
X1559350Y1144389D03*
X1551870D03*
Y1148129D03*
X1559350Y1151870D03*
X1563090Y1155610D03*
Y1148129D03*
X1555610Y1144389D03*
X1548130Y1151870D03*
Y1148129D03*
Y1144389D03*
X1559350Y1155610D03*
X1555610Y1151870D03*
X1559350Y1148129D03*
Y1170570D03*
X1551870Y1166830D03*
X1559350Y1159350D03*
X1551870D03*
X1548130Y1170570D03*
X1551870D03*
X1563090Y1166830D03*
X1548130D03*
Y1159350D03*
X1555610Y1170570D03*
X1559350Y1166830D03*
X1555610Y1159350D03*
X1559350Y1185531D03*
X1551870Y1178051D03*
Y1174310D03*
X1559350Y1178051D03*
X1551870Y1181791D03*
X1563090D03*
Y1174310D03*
X1548130D03*
Y1178051D03*
Y1181791D03*
X1555610Y1185531D03*
X1559350Y1174310D03*
Y1181791D03*
X1555610Y1178051D03*
X1544389Y1140649D03*
X1540649D03*
X1536909D03*
X1533169D03*
X1544389Y1136909D03*
X1540649D03*
X1544389Y1144389D03*
X1540649D03*
X1533169D03*
Y1148129D03*
Y1151870D03*
Y1155610D03*
X1544389Y1148129D03*
Y1155610D03*
Y1151870D03*
X1536909Y1148129D03*
X1540649Y1151870D03*
Y1148129D03*
X1536909Y1144389D03*
Y1155610D03*
X1533169Y1159350D03*
X1536909Y1166830D03*
Y1170570D03*
X1544389Y1159350D03*
Y1166830D03*
Y1170570D03*
X1540649Y1159350D03*
Y1170570D03*
X1544389Y1174310D03*
Y1178051D03*
X1540649Y1174310D03*
X1521949Y1136909D03*
X1529429Y1140649D03*
X1525689D03*
X1521949D03*
X1518208D03*
Y1136909D03*
X1521949Y1144389D03*
X1518208D03*
X1529429Y1151869D03*
X1525689D03*
X1521949Y1148129D03*
Y1151870D03*
X1518208D03*
X1529429Y1155610D03*
X1525689D03*
X1521949D03*
X1518208Y1148129D03*
Y1155610D03*
X1521949Y1159350D03*
X1518208D03*
X1529429Y1166830D03*
X1525689D03*
X1521948D03*
X1525689Y1170570D03*
X1521948D03*
X1518209Y1166830D03*
X1521948Y1174310D03*
X1518207D03*
X1527559Y1179921D03*
X1514468Y1140649D03*
Y1136909D03*
Y1144389D03*
Y1151870D03*
Y1148129D03*
Y1155610D03*
Y1159350D03*
Y1166829D03*
Y1174309D03*
X1512597Y1198622D03*
X1550000Y1221062D03*
X1553740D03*
X1557480D03*
X1516338Y1187401D03*
Y1191141D03*
Y1198621D03*
Y1206102D03*
Y1194881D03*
Y1202362D03*
Y1213582D03*
Y1209842D03*
Y1217322D03*
X1535039Y1187401D03*
X1531299D03*
X1527559D03*
X1523819D03*
X1520078D03*
X1535039Y1194881D03*
Y1202362D03*
Y1191141D03*
X1531299D03*
X1535039Y1198621D03*
X1531299D03*
Y1194881D03*
Y1206102D03*
X1535039D03*
X1531299Y1202362D03*
X1523819Y1194881D03*
X1527559D03*
X1523819Y1202362D03*
X1527559D03*
Y1191141D03*
X1523819D03*
X1527559Y1198621D03*
X1523819D03*
Y1206102D03*
X1527559D03*
X1520078Y1191141D03*
Y1198621D03*
Y1206102D03*
Y1194881D03*
Y1202362D03*
X1535039Y1217322D03*
X1531299D03*
X1535039Y1209842D03*
Y1213582D03*
X1531299Y1209842D03*
Y1213582D03*
X1527559Y1209842D03*
X1523819D03*
Y1217322D03*
X1527559D03*
Y1213582D03*
X1523819D03*
X1520078D03*
Y1209842D03*
Y1217322D03*
X1538779Y1187401D03*
Y1194881D03*
Y1202362D03*
Y1198621D03*
Y1206102D03*
Y1191141D03*
Y1217322D03*
Y1209842D03*
Y1213582D03*
X1546259Y1191141D03*
X1542519D03*
Y1198621D03*
X1546259D03*
X1542519Y1194881D03*
X1546259D03*
X1542519Y1206102D03*
X1546259D03*
X1542519Y1202362D03*
X1546259D03*
X1542519Y1209842D03*
X1546259D03*
X1516338Y1221062D03*
Y1228543D03*
Y1232283D03*
Y1236023D03*
Y1224803D03*
Y1243503D03*
X1531299Y1221062D03*
X1535039D03*
X1523819D03*
X1527559Y1224803D03*
X1520078Y1221062D03*
X1527559D03*
X1516338Y1239763D03*
X1542519Y1187401D03*
X1535039Y1183661D03*
X1531299D03*
X1527559D03*
X1523819D03*
X1527559Y1228543D03*
X1535039Y1224803D03*
Y1228543D03*
X1523819Y1232283D03*
Y1236023D03*
X1531299D03*
Y1232283D03*
X1527559Y1236023D03*
Y1232283D03*
X1523819Y1228543D03*
Y1224803D03*
X1531299D03*
Y1228543D03*
X1535039Y1232283D03*
Y1236023D03*
X1520078Y1228543D03*
Y1236023D03*
Y1232283D03*
Y1224803D03*
X1535039Y1243503D03*
Y1247243D03*
X1527559D03*
Y1243503D03*
X1523819Y1247243D03*
X1531299D03*
X1523819Y1239763D03*
Y1243503D03*
X1527559Y1239763D03*
X1535039D03*
X1531299D03*
Y1243503D03*
X1520078Y1247243D03*
Y1239763D03*
Y1243503D03*
X1546259Y1217322D03*
Y1221062D03*
X1538779D03*
X1542519D03*
Y1217322D03*
Y1213582D03*
X1546259D03*
X1538779Y1232283D03*
Y1236023D03*
X1542519Y1224803D03*
Y1228543D03*
X1546259Y1232283D03*
Y1236023D03*
X1542519Y1232283D03*
Y1236023D03*
X1538779Y1228543D03*
Y1224803D03*
X1546259D03*
Y1228543D03*
X1542519Y1247243D03*
Y1243503D03*
X1538779Y1247243D03*
Y1239763D03*
Y1243503D03*
X1542519Y1239763D03*
X1546259D03*
Y1243503D03*
Y1247243D03*
X1550000Y1224803D03*
Y1228543D03*
Y1232283D03*
Y1236023D03*
Y1243503D03*
Y1247243D03*
Y1239763D03*
X1557480Y1224803D03*
Y1228543D03*
Y1232283D03*
Y1236023D03*
X1553740Y1232283D03*
Y1236023D03*
Y1228543D03*
Y1224803D03*
X1557480Y1243503D03*
Y1239763D03*
X1553740Y1247243D03*
Y1239763D03*
Y1243503D03*
X1516338Y1247243D03*
X1512597Y1206103D03*
Y1213583D03*
Y1221063D03*
X1512596Y1239762D03*
Y1247242D03*
X1512597Y1228542D03*
Y1191142D03*
X1550000Y1206102D03*
Y1202362D03*
Y1217322D03*
Y1209842D03*
Y1198621D03*
Y1213582D03*
X1521949Y1073326D03*
X1529429D03*
Y1077066D03*
X1536909D03*
X1525689Y1080807D03*
X1533169D03*
X1525689Y1084547D03*
X1533169D03*
X1540649D03*
X1514468Y1088287D03*
X1518208D03*
X1521949Y1092027D03*
X1529429D03*
X1536909D03*
X1546259Y1093897D03*
X1553740D03*
X1521949Y1095767D03*
X1529429D03*
X1536909D03*
X1546259Y1097637D03*
X1553740D03*
X1514468Y1099507D03*
X1518208D03*
X1525689D03*
X1533169D03*
X1550000Y1101376D03*
X1557480D03*
X1525689Y1103247D03*
X1533169D03*
X1540649D03*
X1550000Y1105117D03*
X1557480D03*
X1514468Y1106988D03*
X1518208D03*
X1521949Y1110728D03*
X1525689D03*
X1533169D03*
X1536909D03*
X1514468Y1114468D03*
X1518208D03*
X1540649D03*
X1544389D03*
X1555610D03*
X1521949Y1118208D03*
X1525689D03*
X1533169D03*
X1536909D03*
X1514468Y1121948D03*
X1518208D03*
X1533169D03*
X1521949Y1125688D03*
X1525689D03*
X1641634Y1215452D03*
X1652854Y1207972D03*
X1570571Y1204232D03*
X1574311Y1211712D03*
X1578051D03*
X1570571Y1215452D03*
X1574311D03*
X1570571Y1211712D03*
X1578051Y1215452D03*
X1570571Y1207972D03*
X1574311D03*
X1578051D03*
Y1204232D03*
X1574311D03*
X1581791Y1211712D03*
Y1207972D03*
X1589271Y1211712D03*
Y1204232D03*
X1585531D03*
X1581791D03*
X1593011D03*
X1585531Y1211712D03*
Y1215452D03*
X1581791D03*
X1593012Y1211712D03*
X1585531Y1207972D03*
X1589271D03*
X1593011D03*
X1607972Y1211712D03*
X1596752D03*
X1600492Y1215452D03*
Y1211712D03*
Y1207972D03*
X1611712Y1211712D03*
Y1207972D03*
X1607972D03*
X1596752D03*
X1600492Y1204232D03*
X1596752D03*
X1607972D03*
X1611712D03*
X1622933Y1211711D03*
X1619192D03*
X1626673Y1215452D03*
X1619192Y1215451D03*
X1622933Y1215452D03*
X1615452Y1207972D03*
Y1211712D03*
X1626673Y1207972D03*
Y1211712D03*
X1622933Y1207972D03*
X1619193D03*
X1622933Y1204232D03*
X1626673D03*
X1615452D03*
X1619193D03*
X1634153Y1215452D03*
X1637893D03*
X1630413D03*
X1641633Y1207972D03*
X1630413Y1211712D03*
X1637893D03*
Y1207972D03*
X1634153Y1211712D03*
X1630413Y1207972D03*
X1634153D03*
X1641633Y1211712D03*
X1637893Y1204232D03*
X1634153D03*
X1630413D03*
X1641633D03*
X1652854Y1200491D03*
X1656594Y1204232D03*
Y1200491D03*
Y1196751D03*
X1645374Y1200491D03*
X1649114Y1193011D03*
X1652854D03*
Y1196751D03*
X1660334Y1193011D03*
X1652854Y1204232D03*
X1656594Y1193011D03*
X1645374Y1204232D03*
X1656594Y1178051D03*
X1660334Y1181791D03*
Y1189271D03*
X1652854Y1181791D03*
X1656594Y1174310D03*
Y1189271D03*
X1649114Y1185531D03*
X1652854Y1189271D03*
X1649114D03*
Y1178051D03*
X1660334Y1185531D03*
Y1178051D03*
Y1174310D03*
X1656594Y1185531D03*
X1649114Y1181791D03*
X1652854Y1174310D03*
Y1178051D03*
X1656594Y1181791D03*
X1652854Y1185531D03*
X1656594Y1166830D03*
Y1170570D03*
X1652854Y1166830D03*
Y1170570D03*
X1660334D03*
Y1166830D03*
X1649114Y1207972D03*
X1656594D03*
Y1215452D03*
X1645374Y1211712D03*
X1656594D03*
X1652854Y1215452D03*
X1649114D03*
X1645374D03*
X1652854Y1211712D03*
X1645374Y1207972D03*
X1649114Y1211712D03*
Y1204232D03*
Y1196751D03*
Y1200491D03*
X1675295Y1193011D03*
Y1181791D03*
Y1174310D03*
Y1189271D03*
X1671555D03*
X1675295Y1178051D03*
Y1185531D03*
X1667815Y1189271D03*
X1664074Y1181791D03*
X1667815D03*
Y1174310D03*
X1671555D03*
Y1178051D03*
Y1181791D03*
Y1185531D03*
X1664074Y1174310D03*
Y1189271D03*
X1667815Y1170570D03*
X1664075D03*
X1671555Y1166830D03*
Y1170570D03*
X1675295D03*
X1664074Y1166830D03*
X1667815D03*
X1690256Y1193011D03*
X1682775Y1185531D03*
X1686515Y1178051D03*
X1682775D03*
X1686515Y1185531D03*
X1679035Y1174310D03*
Y1189271D03*
Y1181791D03*
X1690256D03*
Y1185531D03*
Y1189271D03*
X1686515D03*
Y1181791D03*
X1682775Y1189271D03*
X1679035Y1185531D03*
X1682775Y1181791D03*
X1679035Y1178051D03*
X1682775Y1174310D03*
X1690256D03*
X1686515D03*
X1690256Y1178051D03*
X1682775Y1170570D03*
X1686515D03*
X1690256Y1166830D03*
Y1170570D03*
X1686515Y1166830D03*
X1679035Y1170570D03*
X1682775Y1166830D03*
X1686515Y1193011D03*
X1697676D03*
X1693996D03*
Y1174310D03*
Y1181791D03*
X1697736D03*
Y1189271D03*
X1693996D03*
X1697736Y1174310D03*
X1693996Y1185531D03*
X1697736D03*
X1693996Y1178051D03*
X1697736D03*
Y1170570D03*
Y1166830D03*
X1693996D03*
Y1170570D03*
X1697736Y1159350D03*
X1693996D03*
X1690256D03*
X1686515D03*
X1682775D03*
X1679035D03*
X1671555D03*
X1667815D03*
X1664074D03*
X1660334D03*
X1656594D03*
X1652854D03*
X1697736Y1155610D03*
X1693996D03*
X1690256D03*
X1686515D03*
X1682775D03*
X1679035D03*
X1675295D03*
X1671555D03*
X1667815D03*
X1664075D03*
X1660334D03*
X1656594D03*
X1652854D03*
X1697736Y1151870D03*
X1693996D03*
X1649114D03*
X1690256Y1151869D03*
X1686515D03*
X1682775D03*
X1679035D03*
X1675295D03*
X1671555D03*
X1667815D03*
X1664074D03*
X1660334D03*
X1656594D03*
X1652854D03*
X1697736Y1148129D03*
X1693996D03*
X1690256D03*
X1686515D03*
X1682775D03*
X1679035D03*
X1675295D03*
X1671555D03*
X1664075D03*
X1660334D03*
X1656594D03*
X1652854D03*
X1649114D03*
X1697736Y1144389D03*
X1693996D03*
X1690256D03*
X1686515D03*
X1682775D03*
X1679035D03*
X1675295D03*
X1671555D03*
X1667815D03*
X1664074D03*
X1660334D03*
X1656594D03*
X1652854D03*
X1649114D03*
X1697736Y1140649D03*
X1693996D03*
X1690256D03*
X1686515D03*
X1682775D03*
X1679035D03*
X1675295D03*
X1671555D03*
X1656594D03*
X1652854D03*
X1649114D03*
X1656594Y1136909D03*
X1652854D03*
X1649114D03*
X1677165Y1135039D03*
X1665945D03*
X1662204D03*
X1656594Y1133169D03*
X1649114D03*
X1699607Y1131300D03*
X1688385Y1131299D03*
X1684644D03*
X1680905D03*
X1677165D03*
X1673425D03*
X1669685D03*
X1665944D03*
X1662204D03*
X1649114Y1129429D03*
X1645374D03*
X1677165Y1127559D03*
X1673425D03*
X1695866Y1127558D03*
X1692126D03*
X1680905D03*
X1669685D03*
X1665945D03*
X1662204D03*
X1649114Y1125688D03*
X1645374D03*
X1641633D03*
X1637893D03*
X1634153D03*
X1630413D03*
X1626673D03*
X1622933D03*
X1619193D03*
X1615452D03*
X1611712D03*
X1607972D03*
X1600492D03*
X1596752D03*
X1593011D03*
X1589271D03*
X1585531D03*
X1581791D03*
X1578051D03*
X1574311D03*
X1570571D03*
X1566830D03*
X1563090D03*
X1699607Y1123819D03*
X1688385Y1123818D03*
X1684645D03*
X1680905D03*
X1677165D03*
X1673425D03*
X1669685D03*
X1665944D03*
X1662204D03*
X1649114Y1121948D03*
X1645374D03*
X1641633D03*
X1637893D03*
X1634153D03*
X1630413D03*
X1626673D03*
X1622933D03*
X1619193D03*
X1615452D03*
X1611712D03*
X1607972D03*
X1600492D03*
X1596752D03*
X1593011D03*
X1589271D03*
X1585531D03*
X1581791D03*
X1578051D03*
X1574311D03*
X1570571D03*
X1566830D03*
X1563090D03*
X1695866Y1120078D03*
X1692126D03*
X1680905D03*
X1677165D03*
X1673425D03*
X1669685D03*
X1665944D03*
X1662204D03*
X1656594Y1118208D03*
X1652854D03*
X1649114D03*
X1645374D03*
X1641633D03*
X1637893D03*
X1634153D03*
X1630413D03*
X1626673D03*
X1622933D03*
X1619193D03*
X1615452D03*
X1611712D03*
X1607972D03*
X1600492D03*
X1596752D03*
X1593011D03*
X1589271D03*
X1585531D03*
X1581791D03*
X1578051D03*
X1574311D03*
X1570571D03*
X1566830D03*
X1563090D03*
X1699607Y1116339D03*
X1688385Y1116338D03*
X1684645D03*
X1680905D03*
X1677165D03*
X1673425D03*
X1669685D03*
X1665944D03*
X1662204D03*
X1656594Y1114468D03*
X1652854D03*
X1649114D03*
X1645374D03*
X1641633D03*
X1637893D03*
X1634153D03*
X1630413D03*
X1626673D03*
X1622933D03*
X1619193D03*
X1615452D03*
X1611712D03*
X1607972D03*
X1600492D03*
X1596752D03*
X1593012D03*
X1581791D03*
X1578051D03*
X1574311D03*
X1570571D03*
X1566830D03*
X1563090D03*
X1695866Y1112598D03*
X1692126D03*
X1680905D03*
X1677165D03*
X1673425D03*
X1669685D03*
X1665944D03*
X1699607Y1108859D03*
X1688385Y1108858D03*
X1684645D03*
X1680904D03*
X1673425D03*
X1669685D03*
X1665945D03*
X1662204D03*
X1658464D03*
X1654724D03*
X1650984D03*
X1647244D03*
X1643504D03*
X1639763D03*
X1636023D03*
X1632283D03*
X1628543D03*
X1624803D03*
X1621063D03*
X1617322D03*
X1613582D03*
X1609842D03*
X1606102D03*
X1602362D03*
X1598622D03*
X1594882D03*
X1591141D03*
X1587401D03*
X1583661D03*
X1579921D03*
X1576181D03*
X1572441D03*
X1568700D03*
X1564960D03*
X1677164Y1108857D03*
X1695866Y1105117D03*
X1692126D03*
X1688386D03*
X1684645D03*
X1680905D03*
X1677165D03*
X1673425D03*
X1669685D03*
X1665945D03*
X1662204D03*
X1658464D03*
X1654724D03*
X1650984D03*
X1647244D03*
X1643504D03*
X1639763D03*
X1636023D03*
X1632283D03*
X1628543D03*
X1624803D03*
X1621063D03*
X1617322D03*
X1613582D03*
X1609842D03*
X1606102D03*
X1602362D03*
X1598622D03*
X1594881D03*
X1591141D03*
X1587401D03*
X1583661D03*
X1579921D03*
X1576181D03*
X1572441D03*
X1568700D03*
X1564960D03*
X1699607Y1101378D03*
X1695866Y1101377D03*
X1692126D03*
X1688385D03*
X1684645D03*
X1680905D03*
X1673425D03*
X1665944D03*
X1658464D03*
X1650984D03*
X1643504D03*
X1636023D03*
X1628543D03*
X1621063D03*
X1613582D03*
X1606102D03*
X1598622D03*
X1591141D03*
X1583661D03*
X1576181D03*
X1568700D03*
X1677165Y1101376D03*
X1669685D03*
X1662204D03*
X1654724D03*
X1647244D03*
X1639763D03*
X1632283D03*
X1624803D03*
X1617322D03*
X1609842D03*
X1602362D03*
X1594881D03*
X1587401D03*
X1579921D03*
X1572441D03*
X1564960D03*
X1695866Y1097637D03*
X1692126D03*
X1688385D03*
X1684645D03*
X1680904D03*
X1677165D03*
X1673424D03*
X1669685D03*
X1665944D03*
X1662204D03*
X1658463D03*
X1654724D03*
X1650983D03*
X1647244D03*
X1643503D03*
X1639763D03*
X1636022D03*
X1632283D03*
X1628542D03*
X1624803D03*
X1621062D03*
X1617322D03*
X1613581D03*
X1609842D03*
X1606101D03*
X1602362D03*
X1695866Y1093897D03*
X1692126D03*
X1688385D03*
X1684645D03*
X1680904D03*
X1677165D03*
X1673424D03*
X1669685D03*
X1665944D03*
X1662204D03*
X1658463D03*
X1654724D03*
X1650983D03*
X1647244D03*
X1643503D03*
X1639763D03*
X1636022D03*
X1632283D03*
X1628542D03*
X1624803D03*
X1621062D03*
X1617322D03*
X1613581D03*
X1609842D03*
X1606101D03*
X1699607Y1090158D03*
X1695866Y1090157D03*
X1692126D03*
X1688385D03*
X1684644D03*
X1680904D03*
X1677164D03*
X1673424D03*
X1669684D03*
X1665944D03*
X1662203D03*
X1658464D03*
X1654724D03*
X1650984D03*
X1647244D03*
X1643504D03*
X1639763D03*
X1636023D03*
X1632283D03*
X1628543D03*
X1624803D03*
X1621063D03*
X1617322D03*
X1695866Y1086417D03*
X1692126D03*
X1688386D03*
X1680905D03*
X1673425D03*
X1665945D03*
X1658464D03*
X1650984D03*
X1643504D03*
X1636023D03*
X1628543D03*
X1621063D03*
X1699607Y1082677D03*
X1688385D03*
X1680904D03*
X1673424D03*
X1665944D03*
X1658464D03*
X1650984D03*
X1643504D03*
X1636023D03*
X1628543D03*
X1621063D03*
X1695866Y1078936D03*
X1692126D03*
X1684646D03*
X1677166D03*
X1669686D03*
X1662204D03*
X1654724D03*
X1647244D03*
X1639763D03*
X1632283D03*
X1624803D03*
X1617322D03*
X1692126Y1075196D03*
X1684646D03*
X1677166D03*
X1669685D03*
X1662204D03*
X1654724D03*
X1647244D03*
X1639763D03*
X1632283D03*
X1624803D03*
X1617322D03*
X1688385Y1071455D03*
X1680905D03*
X1673425D03*
X1665944D03*
X1658463D03*
X1650983D03*
X1643503D03*
X1636022D03*
X1628542D03*
X1621062D03*
G54D60*
X970071Y1365652D03*
G54D55*
X1030635Y774546D03*
G54D57*
X165649Y1159350D03*
Y1151870D03*
X169389Y1155610D03*
X330800Y1174500D03*
X622736Y1151870D03*
X626476Y1155610D03*
X622736Y1159350D03*
X792277Y1173065D03*
X787887Y1174500D03*
X792382Y1191664D03*
X1079822Y1151870D03*
Y1159350D03*
X1083562Y1155610D03*
X1536909Y1151870D03*
Y1159350D03*
X1540649Y1155610D03*
G54D62*
X1074650Y1070006D03*
G54D51*
X743337Y374862D03*
G54D39*
X1729488Y1452717D03*
Y1462953D03*
Y1468071D03*
Y1478308D03*
X1720826Y1479095D03*
X1729488Y1483426D03*
X1720826Y1489331D03*
X1729488Y1493662D03*
X1720826Y1494449D03*
X1729488Y1498780D03*
X1720826Y1504685D03*
X1729488Y1509016D03*
X1720826Y1509804D03*
X1729488Y1514134D03*
X1556260Y1565315D03*
X1729488D03*
X1556260Y1570434D03*
X1729488D03*
X1720826Y1576339D03*
X1556260Y1580670D03*
X1729488D03*
X1720826Y1581457D03*
X1556260Y1585788D03*
X1729488D03*
X1720826Y1591693D03*
X1383032Y1596024D03*
X1556260D03*
X1729488D03*
X1720826Y1596811D03*
X1383032Y1601142D03*
X1556260D03*
X1729488D03*
X1374370Y1607048D03*
X1547598D03*
X1720826D03*
X1383032Y1611378D03*
X1556260D03*
X1729488D03*
X1374370Y1612166D03*
X1547598D03*
X1720826D03*
X1383032Y1616496D03*
X1556260D03*
X1729488D03*
X1305079Y1622402D03*
X1322402D03*
X1339725D03*
X1357047D03*
X1374370D03*
X1478307D03*
X1495630D03*
X1512953D03*
X1530275D03*
X1547598D03*
X1651535D03*
X1668858D03*
X1686181D03*
X1703503D03*
X1720826D03*
X473662D03*
X456339D03*
X490985D03*
X534292Y1585788D03*
Y1580670D03*
X508307Y1622402D03*
X534292Y1601142D03*
X525630Y1607048D03*
Y1612166D03*
X534292Y1611378D03*
Y1616496D03*
X525630Y1622402D03*
X534292Y1596024D03*
Y1570434D03*
Y1565315D03*
X361063Y1493662D03*
Y1498780D03*
X283110Y1622402D03*
X317756D03*
X300433D03*
X335078D03*
X361063Y1585788D03*
X352401Y1607048D03*
Y1612166D03*
Y1622402D03*
X361063Y1462953D03*
Y1468071D03*
Y1478308D03*
Y1483426D03*
Y1580670D03*
X707520Y1462953D03*
Y1468071D03*
Y1478308D03*
Y1483426D03*
Y1493662D03*
Y1498780D03*
Y1509016D03*
Y1514134D03*
Y1565315D03*
Y1570434D03*
X698858Y1576339D03*
Y1581457D03*
X707520Y1580670D03*
Y1585788D03*
X698858Y1591693D03*
Y1596811D03*
X707520Y1596024D03*
Y1601142D03*
X698858Y1607048D03*
Y1612166D03*
X707520Y1611378D03*
Y1616496D03*
X698858Y1622402D03*
X681535D03*
X664213D03*
X646890D03*
X629567D03*
X187835Y1452717D03*
X179173Y1489331D03*
Y1494449D03*
X187835Y1493662D03*
Y1498780D03*
Y1580670D03*
Y1585788D03*
X179173Y1591693D03*
Y1596811D03*
Y1607048D03*
Y1612166D03*
Y1622402D03*
X161850D03*
X144528D03*
X127205D03*
X109882D03*
X1209803Y1452717D03*
Y1462953D03*
Y1468071D03*
Y1478308D03*
Y1483426D03*
Y1493662D03*
Y1498780D03*
Y1509016D03*
Y1514134D03*
Y1565315D03*
Y1570434D03*
Y1580670D03*
Y1585788D03*
X1201141Y1591693D03*
Y1596811D03*
X1209803Y1596024D03*
Y1601142D03*
X1201141Y1607048D03*
Y1612166D03*
X1209803Y1611378D03*
Y1616496D03*
X1201141Y1622402D03*
X1183818D03*
X1166496D03*
X1149173D03*
X1131850D03*
G54D56*
X515504Y701351D03*
G54D53*
X909360Y230906D03*
G54D50*
X640522Y630650D03*
X1657510Y374862D03*
X1554695Y630650D03*
X1200423Y374862D03*
X1097608Y630650D03*
X286250Y374862D03*
X183435Y630650D03*
G54D45*
X197440Y1250984D03*
X193700Y1247243D03*
Y1243503D03*
X189960Y1250984D03*
X186220Y1247243D03*
Y1243503D03*
X197440Y1254724D03*
X189960D03*
X178740Y1247243D03*
X182480Y1250984D03*
X174999D03*
X178740Y1243503D03*
X182480Y1254724D03*
X174999D03*
X242321Y1075196D03*
X249802D03*
X257282D03*
X264762D03*
X272243D03*
X279723D03*
X287203D03*
X294684D03*
X302164D03*
X309644D03*
X317124D03*
X242321Y1078936D03*
X249802D03*
X257282D03*
X264762D03*
X272243D03*
X279723D03*
X287203D03*
X294684D03*
X302164D03*
X309644D03*
X317124D03*
X238581Y1082676D03*
X253542D03*
X268502D03*
X283463D03*
X298424D03*
X320866D03*
X324606D03*
X246061Y1082677D03*
X261022D03*
X275982D03*
X290943D03*
X305904D03*
X313384D03*
X238581Y1086416D03*
X253542D03*
X268502D03*
X283463D03*
X298424D03*
X246061Y1086417D03*
X261022D03*
X275982D03*
X290943D03*
X305904D03*
X313384D03*
X320866Y1108858D03*
X324606D03*
X313385Y1112598D03*
X317125D03*
X320866Y1116338D03*
X324606D03*
X313385Y1120078D03*
X317125D03*
X320866Y1123818D03*
X324606D03*
X313385Y1127558D03*
X317125D03*
X320866Y1131299D03*
X324606D03*
X770472Y1112598D03*
X759251Y1075196D03*
X736810Y1078936D03*
X744290Y1075196D03*
X721849Y1078936D03*
X725589Y1086416D03*
Y1082676D03*
X729330Y1078936D03*
X733069Y1086417D03*
Y1082677D03*
X729330Y1075196D03*
X706889Y1078936D03*
X710629Y1086416D03*
Y1082676D03*
X714369Y1078936D03*
X718109Y1082677D03*
Y1086417D03*
X703148D03*
Y1082677D03*
X714369Y1075196D03*
X706889D03*
X736810D03*
X721849D03*
X770472Y1135039D03*
X774212D03*
X777953Y1131299D03*
X781693D03*
X774212Y1127558D03*
X770472D03*
X777953Y1123818D03*
X781693D03*
X774212Y1120078D03*
X770472D03*
X777953Y1116338D03*
X781693D03*
X774212Y1112598D03*
X777953Y1108858D03*
X781693D03*
X751771Y1075196D03*
X774211Y1078936D03*
X770471Y1086417D03*
Y1082677D03*
X777953Y1082676D03*
X781693D03*
X755511D03*
X774211Y1075196D03*
X755511Y1086416D03*
X762991Y1082677D03*
X759251Y1078936D03*
X766731D03*
X762991Y1086417D03*
X748030D03*
X751771Y1078936D03*
X740550Y1086416D03*
X766731Y1075196D03*
X740550Y1082676D03*
X748030Y1082677D03*
X744290Y1078936D03*
X1156494Y1075196D03*
X1152754Y1086416D03*
Y1082676D03*
X1156494Y1078936D03*
X1163975Y1075196D03*
X1171455D03*
X1163975Y1078936D03*
X1167715Y1086416D03*
Y1082676D03*
X1171455Y1078936D03*
X1175195Y1082677D03*
Y1086417D03*
X1160234D03*
Y1082677D03*
X1178935Y1075196D03*
X1186416D03*
X1178935Y1078936D03*
X1182675Y1086416D03*
Y1082676D03*
X1186416Y1078936D03*
X1190155Y1086417D03*
Y1082677D03*
X1201376Y1075196D03*
X1193896D03*
X1201376Y1078936D03*
X1197636Y1086416D03*
Y1082676D03*
X1205116Y1082677D03*
Y1086417D03*
X1193896Y1078936D03*
X1216337Y1075196D03*
X1223817D03*
X1208857D03*
X1212597Y1082676D03*
Y1086416D03*
X1216337Y1078936D03*
X1223817D03*
X1220077Y1086417D03*
Y1082677D03*
X1208857Y1078936D03*
X1231297Y1075196D03*
Y1078936D03*
X1227557Y1086417D03*
Y1082677D03*
X1235039Y1082676D03*
X1238779D03*
X1235039Y1123818D03*
X1238779D03*
X1231298Y1120078D03*
X1227558D03*
X1235039Y1116338D03*
X1238779D03*
X1227558Y1112598D03*
X1231298D03*
X1235039Y1108858D03*
X1238779D03*
X1235039Y1131299D03*
X1238779D03*
X1231298Y1127558D03*
X1227558D03*
X1695866Y1131299D03*
X1692126D03*
X1688385Y1127558D03*
X1684645D03*
X1695866Y1123818D03*
X1692126D03*
X1688385Y1120078D03*
X1684645D03*
X1695866Y1116338D03*
X1692126D03*
X1688385Y1112598D03*
X1684645D03*
X1695866Y1108858D03*
X1692126D03*
X1684644Y1086417D03*
X1677164D03*
X1662203D03*
X1647242D03*
X1632282D03*
X1617321D03*
X1669684Y1086416D03*
X1654723D03*
X1639762D03*
X1624802D03*
X1684644Y1082677D03*
X1677164D03*
X1662203D03*
X1647242D03*
X1632282D03*
X1617321D03*
X1695866Y1082676D03*
X1692126D03*
X1669684D03*
X1654723D03*
X1639762D03*
X1624802D03*
X1688384Y1078936D03*
X1680904D03*
X1673424D03*
X1665944D03*
X1658463D03*
X1650983D03*
X1643503D03*
X1636022D03*
X1628542D03*
X1621062D03*
X1688384Y1075196D03*
X1680904D03*
X1673424D03*
X1665944D03*
X1658463D03*
X1650983D03*
X1643503D03*
X1636022D03*
X1628542D03*
X1621062D03*
G54D52*
X57933Y66811D03*
X160295D03*
X262657D03*
X365019D03*
X515020D03*
X617382D03*
X719744D03*
X822106D03*
X972106D03*
X1074468D03*
X1176830D03*
X1279192D03*
X1429193D03*
X1531555D03*
X1633917D03*
X1736279D03*
G54D49*
X736447Y630650D03*
X1650620D03*
X1561585Y374862D03*
X1193533Y630650D03*
X1104498Y374862D03*
X279360Y630650D03*
X190325Y374862D03*
G54D48*
X1817323Y56693D03*
G54D43*
X7982Y1527335D03*
X559070Y686509D03*
X561570Y694509D03*
X559070Y702509D03*
X561570Y710509D03*
X460950Y326485D03*
X463950Y334359D03*
X460950Y342233D03*
X463950Y350107D03*
X937000Y313983D03*
X66856Y105949D03*
X138290Y428160D03*
X148692Y421047D03*
X138290Y413987D03*
X140690Y399813D03*
X148692Y435221D03*
X138290Y442333D03*
X169218Y105949D03*
X205680Y399782D03*
X212980Y406868D03*
Y392695D03*
Y435215D03*
X205680Y442302D03*
Y413955D03*
Y428128D03*
X212980Y421041D03*
X271580Y105949D03*
X373942D03*
X533092Y127096D03*
Y112923D03*
X543494Y134209D03*
Y120035D03*
X635454Y127096D03*
Y112923D03*
X645856Y134209D03*
Y120035D03*
X748218Y134209D03*
X737816Y127096D03*
X748218Y120035D03*
X737816Y112923D03*
X721092Y469037D03*
X840178Y127096D03*
Y112923D03*
X850580Y134209D03*
Y120035D03*
X990178Y127096D03*
Y112923D03*
X1000580Y134209D03*
Y120035D03*
X1092540Y112923D03*
Y127096D03*
X1102942Y134209D03*
Y120035D03*
X1178178Y469037D03*
X1205304Y134209D03*
X1194902Y127096D03*
X1205304Y120035D03*
X1194902Y112923D03*
X1209184Y461917D03*
X1297264Y127096D03*
Y112923D03*
X1307666Y134209D03*
Y120035D03*
X1302896Y342096D03*
X1438116Y105949D03*
X1509550Y442333D03*
Y413987D03*
Y428160D03*
X1511950Y399813D03*
X1519952Y435221D03*
Y421047D03*
X1540478Y105949D03*
X1576940Y442302D03*
Y413955D03*
Y428128D03*
Y399782D03*
X1584240Y435215D03*
Y421041D03*
Y406868D03*
Y392695D03*
X1642840Y105949D03*
X1745202D03*
X138290Y471087D03*
X148692Y478199D03*
X212980Y471081D03*
X205680Y478168D03*
X721092Y483210D03*
X713792Y476124D03*
X1178178Y483210D03*
X1170878Y476124D03*
X1519952Y478199D03*
X1509550Y471087D03*
X1576940Y478168D03*
X1584240Y471081D03*
X138290Y529394D03*
X148692Y522333D03*
X138290Y515221D03*
X148692Y492373D03*
X138290Y485260D03*
X205680Y492341D03*
X212980Y485254D03*
Y529388D03*
X205680Y536475D03*
Y522302D03*
X212980Y515215D03*
X713792Y490297D03*
Y612817D03*
Y598644D03*
Y584471D03*
Y570297D03*
Y534431D03*
Y520258D03*
X721092Y605730D03*
Y591557D03*
Y577384D03*
Y563210D03*
Y527344D03*
Y513171D03*
X1170878Y612817D03*
Y598644D03*
Y584471D03*
Y570297D03*
Y534431D03*
Y520258D03*
Y490297D03*
X1178178Y577384D03*
Y563210D03*
Y527344D03*
Y513171D03*
Y605730D03*
Y591557D03*
X1509550Y529394D03*
Y515221D03*
Y485260D03*
X1519952Y522333D03*
Y492373D03*
X1576940Y492341D03*
Y536475D03*
Y522302D03*
X1584240Y529388D03*
Y515215D03*
Y485254D03*
X1754906Y822634D03*
X778080Y605699D03*
X788482Y476118D03*
X778080Y563179D03*
Y527313D03*
Y513139D03*
Y591525D03*
Y577352D03*
X788482Y570291D03*
Y534425D03*
Y520252D03*
Y490291D03*
Y612811D03*
Y598638D03*
Y584465D03*
X1245568Y476118D03*
Y490291D03*
X1235166Y513139D03*
X1245568Y520252D03*
X1235166Y527313D03*
X1245568Y534425D03*
X1235166Y563179D03*
X1245568Y570291D03*
X1235166Y577352D03*
X1245568Y584465D03*
X1235166Y591525D03*
X1245568Y598638D03*
X1235166Y605699D03*
X1245568Y612811D03*
G54D61*
X849441Y1367717D03*
G54D44*
X213969Y1460153D03*
Y1449153D03*
X227249Y1460153D03*
Y1449153D03*
G54D41*
X1817323Y1567323D03*
G54D42*
X217907Y1428752D03*
X415203Y1497818D03*
X397267Y1516347D03*
X385091Y1299153D03*
X454385Y1303545D03*
X1015659Y681354D03*
X486837Y703006D03*
X940997Y333613D03*
X76005Y127096D03*
Y112923D03*
X86407Y134209D03*
Y120035D03*
X178367Y127096D03*
Y112923D03*
X188769Y134209D03*
Y120035D03*
X280729Y112923D03*
X264005Y469037D03*
X280729Y127096D03*
X291131Y134209D03*
Y120035D03*
X295011Y461917D03*
X393493Y134209D03*
X383091Y127096D03*
X393493Y120035D03*
X383091Y112923D03*
X523943Y105949D03*
X595377Y413987D03*
Y428160D03*
X597777Y399813D03*
X595377Y442333D03*
X626305Y105949D03*
X605779Y435221D03*
Y421047D03*
X670067Y392695D03*
X662767Y442302D03*
X670067Y435215D03*
X662767Y413955D03*
X670067Y421041D03*
X662767Y428128D03*
Y399782D03*
X670067Y406868D03*
X728667Y105949D03*
X752097Y461917D03*
X831029Y105949D03*
X981029D03*
X1083391D03*
X1119853Y399782D03*
Y442302D03*
Y428128D03*
Y413955D03*
X1127153Y435215D03*
Y421041D03*
Y406868D03*
Y392695D03*
X1185753Y105949D03*
X1288115D03*
X1366535Y353200D03*
Y337452D03*
X1363535Y345326D03*
Y329578D03*
X1447265Y127096D03*
Y112923D03*
X1457667Y134209D03*
Y120035D03*
X1549627Y127096D03*
X1560029Y134209D03*
X1549627Y112923D03*
X1560029Y120035D03*
X1651989Y127096D03*
Y112923D03*
X1635265Y469037D03*
X1662391Y134209D03*
Y120035D03*
X1666271Y461919D03*
X1754351Y127096D03*
Y112923D03*
X1764753Y120035D03*
Y134209D03*
X256705Y476124D03*
X264005Y483210D03*
X331395Y476118D03*
X605779Y478199D03*
X595377Y471087D03*
X662767Y478168D03*
X670067Y471081D03*
X1119853Y478168D03*
X1127153Y471081D03*
X1627965Y476124D03*
X1635265Y483210D03*
X1702655Y476118D03*
X264005Y513171D03*
X256705Y520258D03*
Y490297D03*
Y612817D03*
X264005Y605730D03*
X256705Y598644D03*
X264005Y591557D03*
Y577384D03*
X256705Y584471D03*
X264005Y563210D03*
X256705Y570297D03*
Y534431D03*
X264005Y527344D03*
X320993Y513139D03*
Y591525D03*
Y605699D03*
Y577352D03*
Y563179D03*
Y527313D03*
X331395Y490291D03*
Y612811D03*
Y598638D03*
Y584465D03*
Y570291D03*
Y534425D03*
Y520252D03*
X595377Y529394D03*
Y515221D03*
Y485260D03*
X605779Y522333D03*
Y492373D03*
X670067Y485254D03*
X662767Y492341D03*
Y536475D03*
X670067Y529388D03*
X662767Y522302D03*
X670067Y515215D03*
X1119853Y536475D03*
Y522302D03*
Y492341D03*
X1127153Y529388D03*
Y515215D03*
Y485254D03*
X1627965Y584471D03*
Y570297D03*
Y534431D03*
Y520258D03*
Y490297D03*
Y612817D03*
Y598644D03*
X1635265Y563210D03*
Y527344D03*
Y513171D03*
Y605730D03*
Y591557D03*
Y577384D03*
X1692253Y591525D03*
Y605699D03*
Y577352D03*
Y563179D03*
Y527313D03*
Y513139D03*
X1702655Y534425D03*
Y520252D03*
Y490291D03*
Y612811D03*
Y598638D03*
Y584465D03*
Y570291D03*
X1052463Y442333D03*
Y413987D03*
Y428160D03*
X1054863Y399813D03*
X1062865Y435221D03*
Y421047D03*
Y478199D03*
X1052463Y471087D03*
Y485260D03*
Y529394D03*
Y515221D03*
X1062865Y522333D03*
Y492373D03*
G54D46*
X770472Y1490945D03*
G54D40*
X1796847Y1517889D03*
X26789Y1373669D03*
X1809883Y120792D03*
X184851Y334492D03*
G54D54*
X792973Y81595D03*
X28819Y81575D03*
X942973Y81595D03*
X1250060D03*
X690611D03*
X233543Y81575D03*
X1502441D03*
X1147697Y81595D03*
X1045335D03*
X588248Y81594D03*
X131181Y81575D03*
X335906D03*
X1604784Y81595D03*
X1400060D03*
X1707146D03*
X485886D03*
G54D59*
X810038Y1066535D03*
X1724212D03*
G54D58*
X573818D03*
X1487991D03*
%LPD*%
G75*
G36*
G01X67049Y829218D02*
X67549Y829718D01*
X75549D01*
X77049Y828218D01*
Y816718D01*
X76049Y815718D01*
X68049D01*
X67049Y816718D01*
Y829218D01*
G37*
G36*
G01X338966Y554861D02*
G03I-608J0D01*
G37*
G36*
G01X374112Y517954D02*
G03I-608J0D01*
G37*
G36*
G01X423481Y309966D02*
G03I-608J0D01*
G37*
G36*
G01X420563Y306966D02*
G03I-608J0D01*
G37*
G36*
G01X415607D02*
G03I-608J0D01*
G37*
G36*
G01X435682Y372533D02*
X446211Y383063D01*
G02X446436Y383103I141J-142D01*
G01X446834Y382921D01*
X446898Y382813D01*
X446893Y382751D01*
G03X446889Y382641I1498J-110D01*
G03X447440Y381478I1503J0D01*
G01X447476Y381449D01*
X447515Y381365D01*
X447505Y380957D01*
X447463Y380876D01*
X447426Y380848D01*
G03X446889Y380089I897J-1204D01*
G01X446881Y380066D01*
X446856Y380024D01*
X441176Y374344D01*
G03X440794Y373420I924J-923D01*
G01Y370973D01*
G02X440735Y370832I-200J1D01*
G01X437168Y367265D01*
G02X437027Y367206I-142J141D01*
G01X422307D01*
G02X422157Y367275I1J200D01*
G01X421930Y367534D01*
X421905Y367616D01*
X421911Y367660D01*
G03X421924Y367859I-1489J197D01*
G03X418920I-1502J0D01*
G03X418933Y367660I1502J-2D01*
G01X418939Y367616D01*
X418914Y367534D01*
X418687Y367275D01*
G02X418537Y367206I-151J131D01*
G01X416656D01*
G03X415732Y366824I-1J-1306D01*
G01X411988Y363080D01*
G03X411606Y362156I924J-923D01*
G01Y358475D01*
G02X411482Y358290I-200J0D01*
G01X411425Y358267D01*
X411308Y358290D01*
X410140Y359458D01*
G02X410082Y359599I142J141D01*
G01Y366432D01*
G02X410140Y366573I200J0D01*
G01X410556Y366990D01*
G02X410708Y367048I141J-142D01*
G01X411048Y367030D01*
X411123Y366992D01*
X411150Y366958D01*
G03X412318Y366401I1168J946D01*
G03X413820Y367903I0J1502D01*
G03X413263Y369071I-1503J0D01*
G01X413229Y369098D01*
X413191Y369173D01*
X413173Y369513D01*
G02X413231Y369665I200J11D01*
G01X415016Y371449D01*
G02X415157Y371508I142J-141D01*
G01X429471D01*
G02X429636Y371420I-1J-200D01*
G01X429851Y371106D01*
X429862Y371010D01*
X429844Y370963D01*
G03X429722Y370309I1680J-652D01*
G03X431524Y368506I1803J0D01*
G01X434924D01*
G03X436726Y370309I0J1802D01*
G03X435776Y371898I-1803J1D01*
G01X435734Y371920D01*
X435679Y371998D01*
X435625Y372362D01*
G02X435682Y372533I198J29D01*
G37*
G36*
G01X426449Y1326953D02*
X427210D01*
G02X427277Y1326941I-1J-200D01*
G01X430931Y1325634D01*
X431000Y1325554D01*
X431010Y1325501D01*
G03X432485Y1324282I1475J283D01*
G01X432486D01*
G03X433446Y1324630I-1J1502D01*
G01X433487Y1324664D01*
X433592Y1324682D01*
X433832Y1324596D01*
G02X433849Y1324589I-68J-188D01*
G01X434003Y1324518D01*
G02X434119Y1324336I-84J-182D01*
G01Y1314419D01*
G02X434060Y1314277I-200J0D01*
G01X433718Y1313935D01*
G02X433560Y1313877I-142J141D01*
G01X433211Y1313906D01*
X433135Y1313949D01*
X433109Y1313986D01*
G03X431885Y1314617I-1224J-872D01*
G03X430387Y1313226I0J-1502D01*
G02X430324Y1313095I-199J15D01*
G01X430125Y1312910D01*
G02X429988Y1312856I-137J146D01*
G01X429198D01*
G02X429056Y1312915I0J200D01*
G01X423394Y1318577D01*
X423365Y1318605D01*
X423335Y1318679D01*
Y1323839D01*
G02X423394Y1323981I200J0D01*
G01X426307Y1326894D01*
G02X426449Y1326953I142J-141D01*
G37*
G36*
G01X418133Y1372585D02*
X421913D01*
G02X422055Y1372526I0J-200D01*
G01X422642Y1371939D01*
G02X422701Y1371797I-141J-142D01*
G01Y1363335D01*
G03X422760Y1363193I200J0D01*
G01X423665Y1362288D01*
G03X423807Y1362229I142J141D01*
G01X427904D01*
G02X428046Y1362170I0J-200D01*
G01X428951Y1361265D01*
G02X429010Y1361123I-141J-142D01*
G01Y1355064D01*
G02X428951Y1354922I-200J0D01*
G01X427961Y1353932D01*
G02X427819Y1353873I-142J141D01*
G01X417156D01*
G02X417014Y1353932I0J200D01*
G01X415313Y1355633D01*
G02X415254Y1355775I141J142D01*
G01Y1360156D01*
G02X415313Y1360298I200J0D01*
G01X417355Y1362340D01*
G03X417414Y1362482I-141J142D01*
G01Y1370990D01*
X417428Y1371025D01*
G03X417531Y1371572I-1399J547D01*
G03X417495Y1371899I-1503J0D01*
G01X417484Y1371949D01*
X417512Y1372047D01*
X417991Y1372526D01*
G02X418133Y1372585I142J-141D01*
G37*
G36*
G01X431355Y306966D02*
G03I-608J0D01*
G37*
G36*
G01X428437Y309966D02*
G03I-608J0D01*
G37*
G36*
G01X436311Y306966D02*
G03I-608J0D01*
G37*
G36*
G01X436310Y367813D02*
G03I-608J0D01*
G37*
G36*
G01X431354D02*
G03I-608J0D01*
G37*
G36*
G01X459062Y324007D02*
G03I-608J0D01*
G37*
G36*
G01Y328963D02*
G03I-608J0D01*
G37*
G36*
G01Y339755D02*
G03I-608J0D01*
G37*
G36*
G01X462062Y336837D02*
G03I-608J0D01*
G37*
G36*
G01Y331881D02*
G03I-608J0D01*
G37*
G36*
G01X459062Y344711D02*
G03I-608J0D01*
G37*
G36*
G01X462062Y347629D02*
G03I-608J0D01*
G37*
G36*
G01Y352585D02*
G03I-608J0D01*
G37*
G36*
G01X483850Y366481D02*
G03I-608J0D01*
G37*
G36*
G01X484192Y375840D02*
G03I-608J0D01*
G37*
G36*
G01X484344Y371266D02*
G03I-608J0D01*
G37*
G36*
G01X484149Y380306D02*
G03I-608J0D01*
G37*
G36*
G01X479974Y480377D02*
Y529295D01*
G02X480097Y529480I200J1D01*
G01X480154Y529503D01*
X480271Y529480D01*
X481450Y528301D01*
X481477Y528196D01*
X481462Y528143D01*
G03X481403Y527726I1444J-417D01*
G03X482905Y526224I1502J0D01*
G03X483117Y526239I0J1502D01*
G01X483161Y526245D01*
X483243Y526221D01*
X483505Y525994D01*
G02X483574Y525843I-131J-151D01*
G01Y465824D01*
G02X483515Y465683I-200J1D01*
G01X481848Y464015D01*
G02X481630Y463972I-141J142D01*
G01X481573Y463996D01*
X481506Y464095D01*
Y478220D01*
G03X481124Y479144I-1306J1D01*
G01X480032Y480236D01*
G02X479974Y480377I142J141D01*
G37*
G36*
G01X481704Y536004D02*
Y543001D01*
G02X481796Y543170I200J1D01*
G01X482124Y543379D01*
X482225Y543386D01*
X482272Y543364D01*
G03X482905Y543224I633J1361D01*
G03X483117Y543239I0J1502D01*
G01X483161Y543245D01*
X483243Y543221D01*
X483505Y542994D01*
G02X483574Y542843I-131J-151D01*
G01Y536121D01*
G02X483502Y535967I-200J0D01*
G01X483232Y535742D01*
X483146Y535719D01*
X483103Y535727D01*
G03X482836Y535751I-267J-1478D01*
G03X482258Y535635I1J-1502D01*
G01X482210Y535615D01*
X482112Y535625D01*
X481793Y535838D01*
G02X481704Y536004I111J166D01*
G37*
G36*
G01X480176Y575954D02*
Y576473D01*
G02X480300Y576658I200J0D01*
G01X480357Y576681D01*
X480474Y576658D01*
X483515Y573617D01*
G02X483574Y573476I-141J-142D01*
G01Y550609D01*
G02X483505Y550458I-200J0D01*
G01X483243Y550231D01*
X483161Y550207D01*
X483117Y550213D01*
G03X482905Y550228I-212J-1487D01*
G03X482272Y550088I0J-1501D01*
G01X482225Y550066D01*
X482124Y550073D01*
X481796Y550282D01*
G02X481704Y550451I108J168D01*
G01Y573803D01*
G03X481321Y574727I-1306J0D01*
G01X480235Y575813D01*
G02X480176Y575954I141J142D01*
G37*
G36*
G01X504730Y720765D02*
X517984D01*
G02X518126Y720706I0J-200D01*
G01X519073Y719759D01*
G02X519132Y719617I-141J-142D01*
G01Y715068D01*
G02X519073Y714926I-200J0D01*
G01X503395Y699248D01*
G02X503242Y699190I-141J142D01*
G01X502901Y699210D01*
X502825Y699250D01*
X502798Y699284D01*
G03X501618Y699857I-1180J-929D01*
G03X501044Y699743I0J-1502D01*
G01X501001Y699725D01*
X500910Y699731D01*
X500555Y699930D01*
X500503Y700005D01*
X500496Y700051D01*
G03X499012Y701321I-1484J-232D01*
G03Y698317I0J-1502D01*
G03X499586Y698431I0J1502D01*
G01X499629Y698449D01*
X499720Y698443D01*
X500075Y698244D01*
X500127Y698169D01*
X500134Y698123D01*
G03X501618Y696853I1484J232D01*
G03X502039Y696913I1J1502D01*
G01X502085Y696927D01*
X502177Y696910D01*
X502471Y696689D01*
G02X502551Y696529I-120J-160D01*
G01Y674756D01*
G02X502492Y674614I-200J0D01*
G01X501697Y673819D01*
G02X501555Y673760I-142J141D01*
G01X493354D01*
G02X493212Y673819I0J200D01*
G01X490288Y676743D01*
G02X490229Y676885I141J142D01*
G01Y713684D01*
G02X490288Y713826I200J0D01*
G01X497168Y720706D01*
G02X497310Y720765I142J-141D01*
G01X500934D01*
G02X501071Y720711I0J-200D01*
G01X501299Y720498D01*
X501331Y720430D01*
X501333Y720392D01*
G03X504331I1499J99D01*
G01X504333Y720430D01*
X504365Y720498D01*
X504593Y720711D01*
G02X504730Y720765I137J-146D01*
G37*
G36*
G01X521488Y704864D02*
X527509D01*
G02X527651Y704805I0J-200D01*
G01X527942Y704514D01*
G02X528001Y704372I-141J-142D01*
G01Y694482D01*
G02X527942Y694340I-200J0D01*
G01X527574Y693972D01*
G02X527432Y693913I-142J141D01*
G01X517562D01*
G02X517420Y693972I0J200D01*
G01X517067Y694325D01*
G02X517008Y694467I141J142D01*
G01Y695264D01*
X517017Y695292D01*
G03Y696222I-1532J465D01*
G01X517008Y696250D01*
Y700800D01*
X517019Y700831D01*
G03X517106Y701351I-1515J521D01*
G03X517019Y701871I-1602J-1D01*
G01X517008Y701902D01*
Y703474D01*
G02X517067Y703616I200J0D01*
G01X518256Y704805D01*
G02X518398Y704864I142J-141D01*
G01X520780D01*
X520800Y704860D01*
G03X521134Y704824I338J1566D01*
G03X521468Y704860I-4J1602D01*
G01X521488Y704864D01*
G37*
G36*
G01X542252Y389047D02*
G03I-608J0D01*
G37*
G36*
G01X554339Y388487D02*
G03I-608J0D01*
G37*
G36*
G01X571242Y375453D02*
G03I-608J0D01*
G37*
G36*
G01X582095Y336676D02*
G03I-608J0D01*
G37*
G36*
G01X590786Y309760D02*
G03I-608J0D01*
G37*
G36*
G01X686620Y339795D02*
G03I-608J0D01*
G37*
G36*
G01X876854Y302754D02*
G03I-608J0D01*
G37*
G36*
G01X1800363Y971160D02*
X1800863Y971660D01*
X1808863D01*
X1810363Y970160D01*
Y958660D01*
X1809363Y957660D01*
X1801363D01*
X1800363Y958660D01*
Y971160D01*
G37*
%LPC*%
G75*
G36*
G01X499918Y707481D02*
G02X499212Y708755I796J1274D01*
G02X502216I1502J0D01*
G02X501503Y707477I-1502J0D01*
G03X501501Y706798I210J-340D01*
G02X502207Y705524I-796J-1274D01*
G02X499203I-1502J0D01*
G02X499916Y706802I1502J0D01*
G03X499918Y707481I-210J340D01*
G37*
G54D37*
X417305Y1359169D03*
X503311Y715652D03*
%LPD*%
G75*
G54D10*
G01X1223431Y377912D02*
X1221283Y375764D01*
X1217354D01*
X1207722Y366132D01*
Y328547D01*
X1224529Y311740D01*
X1229028D01*
G01D02*
X1232352Y308416D01*
X1237204D01*
X1241205Y304415D01*
Y303962D01*
G01X1223431Y381912D02*
Y377912D01*
G01X1326489Y356945D02*
X1325263Y358171D01*
X1320605D01*
X1314891Y352457D01*
X1312360D01*
X1308012Y348109D01*
G01X1486030Y1016827D02*
X1480399Y1022458D01*
X1468817D01*
X1467367Y1021008D01*
X1461646D01*
X1459128Y1018490D01*
Y1017754D01*
X1453407Y1012033D01*
Y1000104D01*
X1437157Y983854D01*
Y980280D01*
X1420699Y963822D01*
Y958452D01*
X3704Y5374D03*
X3017Y24773D03*
Y44773D03*
Y64773D03*
Y84773D03*
Y104773D03*
Y124773D03*
Y144773D03*
Y164773D03*
Y184773D03*
Y204773D03*
Y224773D03*
Y244773D03*
Y264773D03*
Y284773D03*
Y304773D03*
X3221Y324773D03*
X3035Y978036D03*
Y998036D03*
Y1018036D03*
Y1038036D03*
Y1058036D03*
Y1078036D03*
Y1098036D03*
Y1118036D03*
Y1138036D03*
Y1158036D03*
Y1178036D03*
Y1198036D03*
Y1238036D03*
Y1258036D03*
Y1278036D03*
Y1298036D03*
Y1318036D03*
Y1338036D03*
Y1358036D03*
Y1378036D03*
Y1398036D03*
Y1418036D03*
Y1438036D03*
Y1458036D03*
Y1478036D03*
Y1498036D03*
Y1538036D03*
Y1558036D03*
Y1578036D03*
X3017Y1639466D03*
X15972Y3000D03*
X20408Y51296D03*
Y55296D03*
X14751Y62381D03*
X12601Y92110D03*
X9364Y107501D03*
X16728Y107910D03*
X12652Y116894D03*
X19184Y144728D03*
X15184D03*
X13615Y153263D03*
X10966Y155873D03*
Y152873D03*
X12709Y175777D03*
X15139Y198883D03*
X15520Y195176D03*
X18320D03*
X13020D03*
X10520D03*
X15139Y201683D03*
X12880Y203393D03*
X10380D03*
X19068Y206838D03*
X16568D03*
X18564Y238589D03*
X9745Y245784D03*
X19075Y278429D03*
X10971Y333342D03*
X17964Y349298D03*
Y369298D03*
Y389298D03*
Y409298D03*
Y429298D03*
Y449298D03*
Y469298D03*
Y489298D03*
Y509298D03*
Y529298D03*
Y549298D03*
Y569298D03*
Y589298D03*
Y609298D03*
Y629298D03*
Y649298D03*
Y669298D03*
Y689298D03*
Y709298D03*
Y729298D03*
Y749298D03*
Y769298D03*
Y789298D03*
Y809298D03*
Y829298D03*
Y849298D03*
Y869298D03*
Y889298D03*
Y909298D03*
Y929298D03*
X9554Y961954D03*
X17964Y949298D03*
X6161Y1075991D03*
X6108Y1070611D03*
Y1065318D03*
X6059Y1091964D03*
X6055Y1086546D03*
X6053Y1081305D03*
X14252Y1121333D03*
X11552D03*
X16752D03*
X8952D03*
X14152Y1111633D03*
X11452D03*
X8852D03*
X16652D03*
X14252Y1130333D03*
X16752D03*
X14306Y1138705D03*
X16806D03*
X20079Y1429347D03*
X13606Y1476707D03*
X6690Y1496782D03*
X19365Y1494298D03*
X8042Y1522199D03*
X12327Y1519202D03*
X7922Y1532494D03*
X11995Y1535134D03*
X6567Y1554215D03*
X14375Y1553121D03*
X18409Y1554202D03*
X12000Y1644980D03*
X26956Y4469D03*
X28317Y24773D03*
Y44773D03*
X24316Y67527D03*
Y63527D03*
Y59527D03*
X35638Y53597D03*
X22439Y106495D03*
X35688Y111255D03*
Y114655D03*
X28388Y121742D03*
X35688Y125428D03*
X28388Y132515D03*
Y118342D03*
X35688Y128828D03*
X23184Y144728D03*
X28388Y135915D03*
X29201Y151651D03*
X26201D03*
X20709Y175777D03*
X34520Y213539D03*
X21530Y236121D03*
X27966Y238689D03*
X28740Y247292D03*
X21449Y253198D03*
X28740Y267292D03*
X21386Y273198D03*
X23479Y295619D03*
X35650Y487982D03*
Y478982D03*
Y483982D03*
Y499982D03*
X25819Y531726D03*
Y536726D03*
Y527726D03*
Y540726D03*
Y544726D03*
X32452Y581222D03*
X29652D03*
X35252D03*
Y591215D03*
X29652D03*
X32452D03*
X34254Y611091D03*
X29451Y633560D03*
X27686Y625311D03*
X36692Y641817D03*
X30369Y663048D03*
X27625Y663094D03*
X25818Y682139D03*
X27854Y671553D03*
X30414Y671508D03*
X28818Y682139D03*
X26596Y874520D03*
X26844Y920354D03*
X24132Y958151D03*
X25371Y980696D03*
X27934Y1204311D03*
X30934D03*
X30410Y1218497D03*
Y1220997D03*
X27934Y1215511D03*
X30934D03*
X34314Y1215403D03*
X27934Y1212711D03*
Y1209911D03*
Y1207111D03*
X30934Y1212711D03*
Y1209911D03*
Y1207111D03*
X30410Y1234797D03*
Y1232297D03*
Y1227897D03*
Y1225397D03*
Y1241697D03*
Y1239197D03*
X22284Y1464612D03*
X21544Y1479662D03*
X33536Y1467485D03*
X21544Y1489648D03*
X25674Y1486291D03*
X32195Y1511279D03*
X32079Y1525641D03*
Y1521641D03*
Y1517641D03*
X35237Y1532096D03*
X31237D03*
X35850Y1556096D03*
X32000Y1644980D03*
X46450Y82984D03*
Y77784D03*
Y75184D03*
Y80384D03*
X48364Y92473D03*
X46450Y85584D03*
X46240Y109410D03*
X45988Y102323D03*
X37988D03*
X42690Y451466D03*
X48596Y458466D03*
X39643Y555194D03*
X36843D03*
X49839Y546830D03*
X39643Y563194D03*
X36843D03*
X39643Y571194D03*
X36843D03*
X42192Y641817D03*
X51449Y822718D03*
X47949D03*
X49265Y886660D03*
X52922Y900295D03*
X47916Y947622D03*
X50366Y1086981D03*
Y1082388D03*
X38200Y1089721D03*
X44365Y1086404D03*
X38216Y1093757D03*
X44960Y1190619D03*
X49500Y1199066D03*
X49638Y1203884D03*
X51197Y1218206D03*
X39452Y1250932D03*
X40996Y1467703D03*
X44195Y1511279D03*
X48195D03*
X40195D03*
X48079Y1525641D03*
Y1529641D03*
Y1521641D03*
X39237Y1532096D03*
X52048Y1556062D03*
X52000Y1644980D03*
X55638Y53597D03*
X56098Y109410D03*
Y116496D03*
X55964Y103037D03*
X64098Y102323D03*
Y109410D03*
Y116496D03*
X56098Y123583D03*
X64098D03*
Y130670D03*
Y137756D03*
X65189Y228961D03*
Y231461D03*
Y223661D03*
Y226461D03*
X68896Y226141D03*
X69139Y236611D03*
X68841Y248891D03*
X58279Y293796D03*
X66293Y285690D03*
X68793D03*
X66293Y288190D03*
X68793D03*
X60779Y293796D03*
X61759Y437508D03*
X57759D03*
X54936Y449352D03*
X59522Y448874D03*
X68497Y450201D03*
X66224Y473045D03*
X58224D03*
X53643Y472905D03*
X66371Y482134D03*
Y484634D03*
X59670Y500086D03*
X64550Y504699D03*
X62050D03*
X59550D03*
X68236Y519458D03*
X61752Y516979D03*
X64252D03*
X59252D03*
X60233Y521804D03*
X68202Y522129D03*
X64495Y527449D03*
X60233Y524304D03*
X56540Y531378D03*
Y528878D03*
X61695Y527449D03*
X68202Y527129D03*
Y524629D03*
Y529629D03*
X67622Y572842D03*
X64408Y572975D03*
X62789Y608311D03*
X66510Y628242D03*
X55318Y629362D03*
X53129Y627948D03*
X64692Y642184D03*
X55307Y688473D03*
X60849Y826818D03*
X64649D03*
X58949Y821018D03*
X68649Y827218D03*
X64849Y840418D03*
X60249D03*
X67316Y865869D03*
X64632Y901500D03*
X57178Y981386D03*
X55049Y1082343D03*
X55004Y1086937D03*
X58981Y1105100D03*
X56381D03*
X61581D03*
X64281D03*
X61681Y1114800D03*
X56481D03*
X59081D03*
X64381D03*
X57218Y1123867D03*
X55397Y1133688D03*
X57897D03*
X58250Y1220896D03*
X65940Y1209382D03*
X58250Y1227796D03*
Y1230296D03*
Y1237196D03*
Y1234696D03*
Y1223396D03*
X57185Y1480808D03*
X57144Y1491047D03*
X56114Y1556061D03*
X68743Y1583498D03*
X60554Y1612002D03*
X66291Y1633801D03*
X74432Y5374D03*
X73745Y24773D03*
Y44773D03*
X73381Y94017D03*
X69381D03*
X73110Y101701D03*
X73509Y110445D03*
X78501D03*
X73509Y115401D03*
X78501D03*
X83911Y117557D03*
X80660Y103783D03*
X73509Y129574D03*
Y124618D03*
X78501Y129574D03*
Y124618D03*
X83911Y122513D03*
Y131731D03*
Y136687D03*
X71422Y151540D03*
X75072Y191941D03*
X81572Y184619D03*
X74939Y188727D03*
X83552Y206760D03*
X73158Y229286D03*
X76851Y222212D03*
X71696Y226141D03*
X76851Y224712D03*
X74139Y236611D03*
X71639D03*
X73158Y231786D03*
X71341Y248891D03*
X73841D03*
X76766Y256535D03*
X84766D03*
X71593Y285690D03*
Y288190D03*
X75819Y290755D03*
X79819D03*
X83819D03*
X71826Y480705D03*
X74326D03*
X69816Y475946D03*
Y478446D03*
X75736Y519458D03*
X73236D03*
X70736D03*
X71995Y532749D03*
X74795D03*
X75777Y585507D03*
X71184D03*
X71730Y579475D03*
X71228Y590145D03*
X75822Y590190D03*
X75684Y605443D03*
X83684D03*
X81740Y636250D03*
X69670Y633205D03*
Y636005D03*
X81740Y633450D03*
X69670Y638805D03*
X81740Y639050D03*
X78129Y656900D03*
X72314Y680207D03*
Y683407D03*
X82714Y674707D03*
X74414Y681907D03*
X72149Y827318D03*
X74349Y824718D03*
Y821918D03*
X72549Y838818D03*
X87000Y1597855D03*
X76005Y1580680D03*
X82433Y1580590D03*
X74291Y1633801D03*
X72000Y1644980D03*
X93334Y3000D03*
X88080Y103603D03*
X88903Y117557D03*
Y122513D03*
Y131731D03*
X87002Y146461D03*
X88903Y136687D03*
X85904Y152367D03*
X87604Y180572D03*
X92287Y180527D03*
X96010Y192421D03*
X92242Y185121D03*
X87604Y185165D03*
X85796Y279208D03*
X89900Y281307D03*
X94390Y293645D03*
Y290845D03*
Y288345D03*
X91890Y293645D03*
Y290845D03*
Y288345D03*
X95943Y377953D03*
X90257Y445506D03*
X93456Y649838D03*
X89432Y668293D03*
X92134D03*
X85614Y674707D03*
X87714Y684607D03*
X88875Y840940D03*
X100058Y977651D03*
X99836Y980330D03*
X85706Y998507D03*
X101025Y1009655D03*
X86291Y1633801D03*
X92000Y1644980D03*
X113334Y3000D03*
X119582Y102249D03*
X107364Y113394D03*
Y110394D03*
X111582Y102249D03*
X110013Y110784D03*
X115582Y102249D03*
X110152Y130898D03*
X117607Y133298D03*
X111754Y134579D03*
X107540Y172665D03*
Y180665D03*
X117501Y198883D03*
X115382Y195176D03*
X112882D03*
X117882D03*
X117501Y201683D03*
X115242Y203393D03*
X112742D03*
X107572Y200864D03*
Y212864D03*
Y216864D03*
Y221864D03*
X109329Y252371D03*
X112474Y716315D03*
X114397Y727974D03*
X107641Y865224D03*
X102355Y874267D03*
X102947Y877196D03*
X102320Y891043D03*
X103972Y977609D03*
X103836Y980330D03*
X111275Y1008262D03*
X114770Y1009354D03*
X115836Y997860D03*
X103825Y1009655D03*
X111275Y1011762D03*
X114770Y1016827D03*
Y1029427D03*
X110970Y1030672D03*
X101970D03*
X104970D03*
X107970D03*
X108971Y1109564D03*
X103124D03*
Y1122164D03*
X108971D03*
X103124Y1134764D03*
X108971D03*
X103124Y1147364D03*
X108971D03*
X103124Y1172564D03*
X108971D03*
X103124Y1159964D03*
X108971D03*
X103861Y1182703D03*
X116330Y1491490D03*
Y1496221D03*
Y1506845D03*
Y1500952D03*
Y1511576D03*
Y1516307D03*
X107669Y1563544D03*
Y1558813D03*
Y1568275D03*
Y1594253D03*
X116330Y1593853D03*
X107669Y1589522D03*
Y1609607D03*
X116330Y1609207D03*
X107669Y1598984D03*
X116330Y1598584D03*
Y1603315D03*
X107669Y1604876D03*
X116330Y1613938D03*
Y1618669D03*
X107669Y1614338D03*
X112000Y1644980D03*
X129318Y4469D03*
X130679Y24773D03*
Y44773D03*
X124606Y106495D03*
X125599Y109172D03*
X122599D03*
X130750Y132515D03*
Y121742D03*
Y118342D03*
X126246Y141228D03*
X124340Y146012D03*
X130750Y135915D03*
X129134Y150847D03*
X120682Y195176D03*
X118930Y206838D03*
X121430D03*
X131102Y247292D03*
X130328Y238689D03*
X123892Y236121D03*
X120926Y238589D03*
X123811Y253198D03*
X125125Y362403D03*
X118122Y747565D03*
X122887Y888000D03*
X124079Y1009354D03*
X119836Y997860D03*
X131836D03*
X127836D03*
X123836D03*
X120579Y1009354D03*
X120617Y1029427D03*
Y1016827D03*
X130380Y1105091D03*
X124880D03*
X133653Y1496221D03*
X124992Y1487159D03*
Y1491890D03*
Y1496621D03*
X133653Y1491490D03*
Y1506845D03*
Y1500952D03*
Y1511576D03*
X124992Y1511976D03*
Y1507245D03*
Y1502514D03*
X133653Y1516307D03*
X124992Y1589522D03*
Y1594253D03*
X133653Y1593853D03*
X124992Y1609607D03*
Y1604876D03*
Y1598984D03*
X133653Y1609207D03*
Y1598584D03*
Y1603315D03*
X124992Y1614338D03*
X133653Y1613938D03*
Y1618669D03*
X132000Y1644980D03*
X138000Y53597D03*
X148812Y80384D03*
Y82984D03*
Y75184D03*
Y77784D03*
Y85584D03*
X148602Y109410D03*
X148350Y102323D03*
X140350D03*
X138050Y111255D03*
Y114655D03*
Y128828D03*
Y125428D03*
X136882Y213539D03*
X146196Y390223D03*
X143186Y402291D03*
X138194Y397335D03*
X143186D03*
X146196Y395179D03*
Y404396D03*
Y409352D03*
X138194Y402291D03*
X140786Y416465D03*
Y411509D03*
X135794Y416465D03*
Y411509D03*
X146196Y418569D03*
Y423525D03*
X140786Y425682D03*
X135794D03*
X140786Y430638D03*
X135794D03*
X146196Y432743D03*
Y437699D03*
X140786Y439855D03*
X135794D03*
X140786Y444811D03*
X135794D03*
X136604Y450750D03*
X135794Y468609D03*
X140786D03*
X135794Y473565D03*
X140786D03*
X146196Y489895D03*
X135794Y487738D03*
X140786D03*
X146196Y480677D03*
Y475721D03*
X135794Y482782D03*
X140786D03*
X146196Y494851D03*
X135794Y512743D03*
X140786D03*
X135794Y517699D03*
X140786D03*
X146196Y519855D03*
X135794Y526916D03*
X140786Y531872D03*
X135794D03*
X146196Y524811D03*
Y538984D03*
Y534028D03*
X140786Y526916D03*
X140703Y536382D03*
X145670Y597580D03*
X147893Y599588D03*
X147155Y589556D03*
X147094Y592354D03*
X145609Y594668D03*
X147896Y596095D03*
X147925Y615600D03*
X147893Y607588D03*
X139836Y997860D03*
X147836D03*
X143836D03*
X135836D03*
X142026Y1012354D03*
X136526D03*
X142026Y1024954D03*
X136526D03*
X142315Y1487159D03*
Y1491890D03*
Y1496621D03*
Y1507245D03*
Y1502514D03*
Y1511976D03*
Y1589522D03*
Y1594253D03*
Y1609607D03*
Y1604876D03*
Y1598984D03*
Y1614338D03*
X158000Y53597D03*
X151366Y92849D03*
X158460Y116496D03*
X158326Y103037D03*
X158460Y109410D03*
X166460Y116496D03*
Y109410D03*
Y102323D03*
X158460Y123583D03*
X166460D03*
Y130670D03*
Y137756D03*
X167551Y223661D03*
X163141Y293796D03*
X166528Y312392D03*
X151188Y423525D03*
Y418569D03*
Y432743D03*
Y437699D03*
Y489895D03*
Y480677D03*
Y475721D03*
Y494851D03*
Y519855D03*
Y524811D03*
X152386Y634946D03*
X151836Y997860D03*
X159836D03*
X159637Y1496621D03*
X150976Y1491490D03*
Y1496221D03*
X159637Y1487159D03*
Y1491890D03*
X150976Y1500952D03*
Y1511576D03*
X159637Y1507245D03*
Y1502514D03*
Y1511976D03*
X150976Y1506845D03*
Y1516307D03*
Y1593853D03*
X159637Y1589522D03*
Y1594253D03*
X150976Y1609207D03*
Y1598584D03*
Y1603315D03*
X159637Y1609607D03*
Y1604876D03*
Y1598984D03*
X150976Y1613938D03*
Y1618669D03*
X159637Y1614338D03*
X152000Y1644980D03*
X176794Y5374D03*
X176107Y24773D03*
Y44773D03*
X179743Y94017D03*
X175743D03*
X171743D03*
X175472Y101701D03*
X175871Y110445D03*
X180863Y115401D03*
Y110445D03*
X175871Y115401D03*
X180863Y129574D03*
Y124618D03*
X175871Y129574D03*
Y124618D03*
X173784Y151540D03*
X177434Y191941D03*
X177301Y188727D03*
X175520Y229286D03*
X179213Y224712D03*
Y222212D03*
X171258Y226141D03*
X167551Y231461D03*
Y228961D03*
Y226461D03*
X174058Y226141D03*
X174001Y236611D03*
X176501D03*
X175520Y231786D03*
X171501Y236611D03*
X176203Y248891D03*
X173703D03*
X171203D03*
X179128Y256535D03*
X173955Y285690D03*
Y288190D03*
X171155Y285690D03*
X168655Y288190D03*
X171155D03*
X168655Y285690D03*
X182181Y290755D03*
X178181D03*
X177369Y389154D03*
Y396240D03*
Y403327D03*
Y410413D03*
Y417500D03*
Y424587D03*
Y431673D03*
Y438760D03*
Y445847D03*
Y467539D03*
Y474626D03*
Y488799D03*
Y481713D03*
Y495886D03*
Y511673D03*
Y518760D03*
Y525847D03*
Y532933D03*
Y540020D03*
Y547106D03*
X176650Y602197D03*
X177114Y595108D03*
X168299Y1491490D03*
Y1496221D03*
X176960Y1491891D03*
Y1487160D03*
Y1496622D03*
Y1507246D03*
Y1502515D03*
X168299Y1506845D03*
Y1500952D03*
Y1511576D03*
X176960Y1511977D03*
X168299Y1516307D03*
Y1593853D03*
X176960Y1594253D03*
Y1589522D03*
X168299Y1609207D03*
Y1598584D03*
Y1603315D03*
X176960Y1609607D03*
Y1598984D03*
Y1604876D03*
X168299Y1613938D03*
Y1618669D03*
X176960Y1614338D03*
X172000Y1644980D03*
X195697Y3000D03*
X188820Y80140D03*
Y84140D03*
Y76140D03*
X183752Y94017D03*
X186273Y117557D03*
X191265D03*
X183022Y103783D03*
X194189Y103621D03*
X186273Y131731D03*
Y122513D03*
X191265D03*
Y131731D03*
X189364Y146461D03*
X186273Y136687D03*
X191265D03*
X188266Y152367D03*
X194649Y180527D03*
X189966Y180572D03*
X198372Y192421D03*
X189966Y185165D03*
X194604Y185121D03*
X183934Y184619D03*
X185914Y206760D03*
X187128Y256535D03*
X188158Y279208D03*
X192262Y281307D03*
X196752Y293645D03*
Y290845D03*
Y288345D03*
X194252Y293645D03*
Y290845D03*
Y288345D03*
X186181Y290755D03*
X191988Y389154D03*
X185169D03*
Y396240D03*
X186448Y404911D03*
X190518Y396240D03*
X194603Y422864D03*
X186589Y426299D03*
X185402Y412571D03*
X195295Y414823D03*
X194673Y429832D03*
X194278Y436447D03*
X186900Y445847D03*
X196313Y447953D03*
X185169Y467539D03*
X195480D03*
X185169Y474626D03*
X194222Y472772D03*
X194956Y487711D03*
X195069Y479104D03*
X185430Y480828D03*
X187380Y498834D03*
X195480Y495886D03*
X190829Y516841D03*
X194080Y510565D03*
X185169Y518760D03*
Y511673D03*
Y525847D03*
X185654Y552872D03*
X185776Y550123D03*
X185099Y562443D03*
X186867Y560675D03*
X187408Y572334D03*
X185640Y574102D03*
X194063Y577716D03*
X191125Y602400D03*
Y598400D03*
Y594400D03*
Y606400D03*
Y614400D03*
X193723Y656942D03*
X185622Y1465513D03*
Y1460782D03*
Y1480868D03*
Y1476137D03*
Y1470244D03*
Y1485599D03*
X192000Y1644980D03*
X211262Y60922D03*
X206398Y55513D03*
X208463Y96472D03*
X203591Y91951D03*
X202195Y117261D03*
X209726Y113394D03*
Y110394D03*
X213944Y102249D03*
X212375Y110784D03*
X211969Y133298D03*
X214116Y134579D03*
X209902Y172665D03*
Y180665D03*
X215244Y195176D03*
X209934Y200864D03*
X215104Y203393D03*
X209934Y212864D03*
Y216864D03*
Y221864D03*
X211691Y252371D03*
X215380Y389153D03*
X210580D03*
X203280Y389154D03*
X215380Y396240D03*
X208080Y403327D03*
X215380Y403326D03*
X210580D03*
X208080Y410413D03*
X210580D03*
X215380D03*
X203280Y396240D03*
Y403327D03*
Y410413D03*
X208080Y396240D03*
X210580D03*
X208080Y417500D03*
X215380Y417499D03*
X210580D03*
X208080Y424586D03*
X210580D03*
X215380D03*
X203280Y417500D03*
Y424586D03*
X208080Y431673D03*
Y438760D03*
X210580D03*
X215380D03*
Y431673D03*
X210580D03*
X203280D03*
Y438760D03*
Y445847D03*
X208080D03*
X215380Y467539D03*
X210580D03*
X203280D03*
X208080Y474626D03*
X210580D03*
X215380D03*
X203280D03*
X215380Y488799D03*
X203280D03*
X208080D03*
X210580D03*
X203280Y481713D03*
X210580Y481712D03*
X208080D03*
X215380D03*
X208080Y495886D03*
X203280D03*
X215380Y518760D03*
X210580D03*
X208080D03*
X210580Y511673D03*
X215380D03*
X203280D03*
Y518760D03*
X210580Y532933D03*
X208080D03*
Y540020D03*
Y525846D03*
X210580D03*
X215380D03*
Y532933D03*
X203280Y525847D03*
Y532933D03*
Y540020D03*
Y547106D03*
Y554193D03*
X204674Y551683D03*
X212460Y560500D03*
X203740Y567914D03*
Y565414D03*
Y570414D03*
Y572914D03*
X203280Y602205D03*
Y595118D03*
X209429Y625300D03*
X213296Y1438215D03*
X215697Y3000D03*
X231681Y4469D03*
X221944Y102249D03*
X224961Y109172D03*
X226968Y106495D03*
X217944Y102249D03*
X227961Y109172D03*
X219969Y133298D03*
X228608Y141228D03*
X226702Y146012D03*
X231496Y150847D03*
X220244Y195176D03*
X219863Y198883D03*
X217744Y195176D03*
X223044D03*
X223792Y206838D03*
X219863Y201683D03*
X221292Y206838D03*
X217604Y203393D03*
X226254Y236121D03*
X223288Y238589D03*
X226173Y253198D03*
X228760Y316122D03*
X228267Y392718D03*
Y408718D03*
Y400718D03*
Y404718D03*
Y412718D03*
X223925Y543925D03*
X221693Y594982D03*
X222289Y590895D03*
X217945Y1423924D03*
X217799Y1433684D03*
X222253Y1438483D03*
X229260Y1469587D03*
X218171Y1474460D03*
X224176Y1492816D03*
X223235Y1506770D03*
X222908Y1502028D03*
X226957Y1510442D03*
X216342Y1515642D03*
X217519Y1537172D03*
X233042Y24773D03*
Y44773D03*
X240363Y53597D03*
X242712Y102323D03*
X240412Y114655D03*
Y111255D03*
X233112Y132515D03*
Y121742D03*
X240412Y125428D03*
X233112Y118342D03*
X240412Y128828D03*
X233112Y135915D03*
X239244Y213539D03*
X232690Y238689D03*
X233464Y247292D03*
X247333Y599506D03*
X243078Y636486D03*
X246583Y665140D03*
X241850Y678462D03*
X247600Y848500D03*
X232675Y1466801D03*
X240466Y1503857D03*
X243268Y1501903D03*
X237700Y1531600D03*
X260363Y53597D03*
X251174Y77784D03*
Y80384D03*
Y82984D03*
Y75184D03*
Y85584D03*
X253728Y92849D03*
X260688Y103037D03*
X250964Y109410D03*
X250712Y102323D03*
X260822Y116496D03*
Y109410D03*
Y123583D03*
X263003Y293796D03*
X265011Y403307D03*
X255000Y427017D03*
X254692Y431029D03*
X253758Y435029D03*
X254678Y449873D03*
X261605Y465492D03*
Y472579D03*
X259105D03*
X254305D03*
X261605Y486752D03*
X254305D03*
X259105Y479666D03*
X261605D03*
X254305D03*
X259105Y486752D03*
X254305Y493839D03*
X259105D03*
X261605Y516713D03*
X259105D03*
Y523800D03*
X261605D03*
X254305D03*
Y516713D03*
X261605Y509626D03*
Y530886D03*
X259105D03*
Y537973D03*
X254305Y530886D03*
Y537973D03*
Y566752D03*
X261605Y559665D03*
Y566752D03*
X259105D03*
X261605Y588012D03*
X259105Y588013D03*
X254305Y573839D03*
X261605D03*
X259105D03*
X261605Y580926D03*
X259105D03*
X254305D03*
Y588013D03*
X259105Y602186D03*
X254305D03*
Y595099D03*
X259105D03*
X261605D03*
Y602185D03*
X254305Y609272D03*
X259105D03*
X261605D03*
X259105Y616359D03*
X254305D03*
X248984Y638125D03*
X258867Y680499D03*
X251802Y824128D03*
X248042Y1532900D03*
X279156Y5374D03*
X278469Y24773D03*
Y44773D03*
X274105Y94017D03*
X278105D03*
X277834Y101701D03*
X268822Y116496D03*
Y109410D03*
X278233Y115401D03*
Y110445D03*
X268822Y102323D03*
Y130670D03*
Y123583D03*
X278233Y129574D03*
Y124618D03*
X268822Y137756D03*
X276146Y151540D03*
X279796Y191941D03*
X279663Y188727D03*
X269913Y228961D03*
Y226461D03*
X276420Y226141D03*
X269913Y223661D03*
X277882Y229286D03*
X273620Y226141D03*
X269913Y231461D03*
X276363Y236611D03*
X278863D03*
X277882Y231786D03*
X273863Y236611D03*
X276065Y248891D03*
X273565D03*
X278565D03*
X276317Y288190D03*
X273517Y285690D03*
X271017Y288190D03*
X273517D03*
X271017Y285690D03*
X265503Y293796D03*
X276317Y285690D03*
X274425Y390500D03*
X265011Y410394D03*
X265945Y440098D03*
Y437598D03*
Y435098D03*
Y432598D03*
Y430098D03*
X266405Y451319D03*
Y458406D03*
X274205Y466027D03*
X266405Y465492D03*
X266229Y462264D03*
X274347Y475262D03*
X266405Y472579D03*
X274347Y489435D03*
Y482666D03*
X266405Y479665D03*
Y486752D03*
Y493839D03*
X274163Y495088D03*
X266405Y523799D03*
Y516713D03*
Y509626D03*
X274205D03*
X274820Y522134D03*
X274898Y514608D03*
X266405Y530886D03*
Y537973D03*
X275463Y529136D03*
X275302Y535677D03*
X266405Y566752D03*
Y559665D03*
X274586Y565574D03*
X274205Y559665D03*
X266405Y580926D03*
Y588012D03*
Y573839D03*
X274233Y574338D03*
X266405Y602185D03*
Y595099D03*
Y609272D03*
Y616358D03*
X274332D03*
X269700Y884600D03*
X269900Y914200D03*
X270100Y946500D03*
X272000Y1644980D03*
X294959Y11097D03*
X286129Y36971D03*
X291182Y84140D03*
Y80140D03*
Y76140D03*
X282105Y94017D03*
X286114D03*
X288635Y117557D03*
X283225Y115401D03*
Y110445D03*
X285384Y103783D03*
X296551Y103621D03*
X293627Y117557D03*
X288635Y131731D03*
Y122513D03*
X283225Y129574D03*
Y124618D03*
X293627Y122513D03*
Y131731D03*
X291726Y146461D03*
X293627Y136687D03*
X288635D03*
X290628Y152367D03*
X292328Y180572D03*
Y185165D03*
X286296Y184619D03*
X288276Y206760D03*
X281575Y224712D03*
Y222212D03*
X281490Y256535D03*
X289490D03*
X290520Y279208D03*
X294624Y281307D03*
X296614Y293645D03*
Y290845D03*
Y288345D03*
X284543Y290755D03*
X280543D03*
X288543D03*
X284075Y381500D03*
X292500Y410394D03*
Y403307D03*
X284295Y430760D03*
X284316Y433570D03*
X284132Y437072D03*
X284173Y439963D03*
X284417Y443180D03*
X284437Y454744D03*
X284379Y452018D03*
X292316Y458406D03*
X284482Y460250D03*
X284516Y465492D03*
X282247Y470136D03*
X292316Y465492D03*
X284516Y472579D03*
X292316D03*
X284516Y479665D03*
Y486752D03*
X292316Y479665D03*
Y486752D03*
Y493839D03*
X284516D03*
X292316Y523799D03*
Y516713D03*
Y509626D03*
X284516Y516713D03*
Y509626D03*
X292316Y537973D03*
Y530886D03*
X283377Y532756D03*
X283456Y525483D03*
X280976Y537973D03*
X284516Y559665D03*
Y566752D03*
X292316Y559665D03*
Y566752D03*
X284366Y579978D03*
X292316Y573839D03*
Y588012D03*
Y580925D03*
X284516Y573839D03*
X292316Y595099D03*
Y602185D03*
X284580Y608117D03*
X289558Y1506845D03*
Y1511576D03*
Y1516307D03*
X280897Y1563544D03*
Y1558813D03*
Y1574167D03*
Y1568275D03*
Y1578898D03*
Y1583629D03*
Y1609607D03*
X289558Y1609207D03*
X280897Y1604876D03*
Y1614338D03*
X289558Y1613938D03*
Y1618669D03*
X292000Y1644980D03*
X298059Y3000D03*
X309106Y37543D03*
X308760Y55513D03*
X310882Y96613D03*
X305953Y91951D03*
X312088Y113394D03*
X304557Y117261D03*
X297011Y180527D03*
X312264Y172665D03*
Y180665D03*
X299759Y190285D03*
X296966Y185121D03*
X312296Y212864D03*
Y200864D03*
Y221864D03*
Y216864D03*
X299114Y290845D03*
Y288345D03*
Y293645D03*
X302966Y324139D03*
X310013Y316731D03*
X306812Y342319D03*
X301943Y332017D03*
X301158Y380307D03*
X309258Y389912D03*
Y393924D03*
Y385912D03*
X301308Y395346D03*
X301393Y400039D03*
X309258Y401924D03*
X298507Y445908D03*
X298220Y1507245D03*
Y1502514D03*
X306881Y1506845D03*
Y1511576D03*
X298220Y1511976D03*
X306881Y1516307D03*
X298220Y1609607D03*
Y1604876D03*
X306881Y1609207D03*
X298220Y1614338D03*
X306881Y1613938D03*
Y1618669D03*
X312000Y1644980D03*
X318059Y3000D03*
X313624Y60922D03*
X324306Y102249D03*
X320306D03*
X327323Y109172D03*
X316306Y102249D03*
X314737Y110784D03*
X314854Y130898D03*
X322331Y133298D03*
X329064Y146012D03*
X316478Y134579D03*
X322225Y198883D03*
X322606Y195176D03*
X325406D03*
X320106D03*
X317606D03*
X323654Y206838D03*
X319966Y203393D03*
X322225Y201683D03*
X317466Y203393D03*
X326154Y206838D03*
X325650Y238589D03*
X328616Y236121D03*
X328535Y253198D03*
X314053Y252371D03*
X323882Y303839D03*
X319857Y321649D03*
X315904Y336324D03*
X321549Y448115D03*
X323489Y471484D03*
Y466528D03*
X328899Y473640D03*
Y487813D03*
X323489Y480701D03*
X328899Y478596D03*
X318497Y485657D03*
X323489D03*
X328899Y492769D03*
X323489Y515617D03*
X328899Y517774D03*
X318497Y510661D03*
X323489D03*
X318497Y515617D03*
X328899Y522730D03*
X318497Y524835D03*
X328899Y536903D03*
Y531947D03*
X323489Y529791D03*
Y524835D03*
X318497Y529791D03*
X327456Y550065D03*
X324291Y556775D03*
X328899Y572769D03*
X318497Y565657D03*
Y560701D03*
X328899Y567813D03*
X323489Y565657D03*
Y560701D03*
X318497Y579830D03*
X323489Y574874D03*
X318497D03*
X323489Y579830D03*
X328899Y581987D03*
X323489Y589047D03*
X318497D03*
X328899Y586943D03*
X318497Y594003D03*
X328899Y596160D03*
X323489Y594003D03*
Y603221D03*
X318497D03*
X328899Y601116D03*
Y610333D03*
X323489Y608177D03*
X318497D03*
X328899Y615289D03*
X324204Y1511576D03*
X315543Y1507245D03*
Y1502514D03*
Y1511976D03*
X324204Y1506845D03*
Y1516307D03*
X315543Y1609607D03*
Y1604876D03*
X324204Y1609207D03*
X315543Y1614338D03*
X324204Y1613938D03*
Y1618669D03*
X334043Y4469D03*
X330905Y11806D03*
X335404Y24773D03*
X330905Y23806D03*
Y31806D03*
X335404Y44773D03*
X342725Y53597D03*
X329330Y106495D03*
X345074Y102323D03*
X330323Y109172D03*
X342774Y111255D03*
Y114655D03*
X335474Y118342D03*
Y132515D03*
X342774Y125428D03*
X335474Y121742D03*
X342774Y128828D03*
X330970Y141228D03*
X335474Y135915D03*
X333858Y150847D03*
X341606Y213539D03*
X335052Y238689D03*
X335826Y247292D03*
X345050Y458334D03*
X333891Y473640D03*
Y487813D03*
Y478596D03*
Y492769D03*
Y522730D03*
Y517774D03*
Y531947D03*
Y536903D03*
X338358Y554861D03*
X333891Y572769D03*
Y567813D03*
Y586943D03*
Y581987D03*
Y596160D03*
Y601116D03*
Y610333D03*
Y615289D03*
X337564Y1018294D03*
X332865Y1511976D03*
X341527Y1506845D03*
Y1511576D03*
X332865Y1507245D03*
Y1502514D03*
X341527Y1516307D03*
Y1609207D03*
X332865Y1609607D03*
Y1604876D03*
X341527Y1613938D03*
Y1618669D03*
X332865Y1614338D03*
X332000Y1644980D03*
X353536Y82984D03*
Y80384D03*
Y77784D03*
Y75184D03*
X356090Y92849D03*
X353536Y85584D03*
X353074Y102323D03*
X353326Y109410D03*
X356423Y301288D03*
X348375Y322284D03*
X348968Y333138D03*
X348737Y375386D03*
X354486Y377173D03*
X358491D03*
X357173Y392183D03*
X357218Y396866D03*
X361234Y402867D03*
X358042Y442518D03*
Y439718D03*
X347450Y447486D03*
X353670Y488618D03*
Y491118D03*
Y493618D03*
X359278Y491870D03*
X356778D03*
X353670Y496118D03*
X358096Y867459D03*
X358086Y884616D03*
X357962Y898800D03*
X358024Y912085D03*
X358085Y923327D03*
X350188Y1507246D03*
Y1502515D03*
Y1511977D03*
X358850Y1511576D03*
Y1506845D03*
Y1516307D03*
X350188Y1604876D03*
Y1609607D03*
Y1614338D03*
X352000Y1644980D03*
X362725Y53597D03*
X376467Y94017D03*
X363050Y103037D03*
X363184Y116496D03*
Y109410D03*
X371184Y116496D03*
Y109410D03*
Y102323D03*
X363184Y123583D03*
X371184Y130670D03*
Y123583D03*
Y137756D03*
X372275Y226461D03*
X375982Y226141D03*
X372275Y228961D03*
Y231461D03*
Y223661D03*
X378782Y226141D03*
X376225Y236611D03*
X375927Y248891D03*
X365365Y293796D03*
X367865D03*
X373379Y288190D03*
X375879Y285690D03*
X373379D03*
X375879Y288190D03*
X368057Y354184D03*
X364933Y374232D03*
X373264Y370010D03*
X361767Y392228D03*
X376992Y395248D03*
X368587Y409016D03*
X364551Y409032D03*
X361811Y396866D03*
X375919Y449118D03*
Y446318D03*
X364954Y450091D03*
X367919Y449118D03*
Y446318D03*
X376099Y458309D03*
Y454309D03*
X367564Y452740D03*
X376099Y462309D03*
X369282Y468088D03*
Y465288D03*
X366443Y472189D03*
X365332Y490070D03*
Y487570D03*
X361887Y493758D03*
Y496258D03*
X373504Y517954D03*
X376881Y518564D03*
X372300Y750000D03*
X377020Y782535D03*
X373101Y779608D03*
X376300Y779800D03*
X365850Y773950D03*
X368491Y815092D03*
X368273Y928100D03*
X375040Y932959D03*
X371424Y937185D03*
X367944Y946082D03*
X370214Y959812D03*
Y967812D03*
X372000Y1644980D03*
X388059Y3000D03*
X381518Y5374D03*
X388487Y24069D03*
X380831Y24773D03*
Y44773D03*
X393544Y76140D03*
Y84140D03*
Y80140D03*
X384467Y94017D03*
X388476D03*
X380467D03*
X380196Y101701D03*
X390997Y117557D03*
X385587Y115401D03*
X380595D03*
X385587Y110445D03*
X380595D03*
X387746Y103783D03*
X390997Y131731D03*
Y122513D03*
X385587Y129574D03*
X380595D03*
X385587Y124618D03*
X380595D03*
X390997Y136687D03*
X382158Y191941D03*
X388658Y184619D03*
X382025Y188727D03*
X390638Y206760D03*
X380244Y229286D03*
X383937Y222212D03*
Y224712D03*
X381225Y236611D03*
X378725D03*
X380244Y231786D03*
X378427Y248891D03*
X380927D03*
X391852Y256535D03*
X383852D03*
X392882Y279208D03*
X378679Y285690D03*
Y288190D03*
X386905Y290755D03*
X382905D03*
X390905D03*
X392387Y337599D03*
Y342555D03*
X389237Y371070D03*
X385237Y370976D03*
X381237Y371076D03*
X396373Y407104D03*
X392444Y401949D03*
X393893Y413611D03*
X393833Y423944D03*
X385584Y450041D03*
Y452841D03*
Y455641D03*
X393837Y466409D03*
X393823Y487382D03*
X393652Y482382D03*
X393746Y478382D03*
X388593Y664232D03*
X386350Y693559D03*
X391478Y690675D03*
X379800Y778000D03*
X387692Y790056D03*
X393547D03*
X386614Y868286D03*
X391614Y938651D03*
X385512Y955356D03*
X390150Y955312D03*
Y959905D03*
X385467Y959950D03*
X381377Y1003008D03*
X381045Y1009444D03*
X387587Y1296675D03*
X387644Y1302089D03*
X391284Y1307238D03*
X389458Y1365466D03*
X389188Y1369033D03*
X388600Y1395500D03*
X389985Y1405762D03*
X394000Y1508100D03*
X382017Y1555700D03*
Y1547700D03*
Y1551700D03*
X392000Y1644980D03*
X408059Y3000D03*
X408493Y117577D03*
X395989Y117557D03*
X398913Y103621D03*
X395989Y131731D03*
Y122513D03*
Y136687D03*
X399373Y180527D03*
X394690Y180572D03*
X403096Y192421D03*
X394690Y185165D03*
X399328Y185121D03*
X396986Y281307D03*
X398976Y293645D03*
X401476D03*
Y288345D03*
Y290845D03*
X398976Y288345D03*
Y290845D03*
X409484Y314921D03*
X397374Y344439D03*
X410688Y344736D03*
X400993Y331589D03*
Y335589D03*
X411007Y356743D03*
X394237Y370899D03*
X396373Y409904D03*
X409268Y408240D03*
X406843Y399161D03*
Y401661D03*
Y396661D03*
X394944Y398949D03*
X399518Y402642D03*
X402018D03*
X396633Y423944D03*
X409386Y420393D03*
X396693Y413611D03*
X399193D03*
X401693D03*
X401633Y423944D03*
X399133D03*
X395577Y455641D03*
Y450041D03*
Y452841D03*
X397315Y479560D03*
X405603Y668060D03*
X408103D03*
X403103D03*
X400603D03*
Y678060D03*
X405603D03*
X408103D03*
X403103D03*
X409284Y741316D03*
X400900Y755400D03*
X400914Y762675D03*
X408300Y755487D03*
X400900Y770100D03*
X407965Y770196D03*
X408400Y795200D03*
Y792200D03*
X406600Y789000D03*
X402376Y842677D03*
X399876D03*
X402376Y850677D03*
X399876D03*
X406967Y878764D03*
X406415Y874840D03*
X407193Y883566D03*
X401121Y936686D03*
X409121Y939186D03*
X401121D03*
X409121Y936686D03*
X396182Y955858D03*
X402682Y948536D03*
X402815Y951750D03*
X404176Y977684D03*
Y975084D03*
Y969984D03*
Y972484D03*
X406954Y982970D03*
X409554D03*
X404354D03*
X399285Y1081599D03*
X398915Y1097278D03*
X396415D03*
X409231Y1123101D03*
X406105Y1139435D03*
X410131Y1129301D03*
X407631D03*
X409231Y1125801D03*
X406105Y1131935D03*
Y1134435D03*
Y1136935D03*
Y1141935D03*
Y1146935D03*
Y1144435D03*
X403263Y1152684D03*
X408961Y1162384D03*
Y1164884D03*
Y1167384D03*
Y1169884D03*
Y1172384D03*
X403263Y1160834D03*
X408961Y1174884D03*
X406319Y1186709D03*
Y1184209D03*
Y1181709D03*
Y1179209D03*
X404004Y1192621D03*
Y1190121D03*
X397063Y1221428D03*
X401063D03*
X405063D03*
X409063D03*
X397063Y1233428D03*
Y1229428D03*
Y1225428D03*
X401063Y1237428D03*
Y1233428D03*
Y1229428D03*
Y1225428D03*
X405063Y1237428D03*
Y1233428D03*
Y1229428D03*
Y1225428D03*
X409063Y1237428D03*
Y1233428D03*
Y1229428D03*
Y1225428D03*
X401063Y1241428D03*
X405063Y1245428D03*
Y1241428D03*
X409063Y1245428D03*
Y1241428D03*
X397695Y1287071D03*
X399716Y1295198D03*
X408937Y1351568D03*
X395959Y1352153D03*
X403981Y1351568D03*
X403029Y1379716D03*
X403111Y1384920D03*
X408212Y1379695D03*
X394657Y1377875D03*
X403111Y1390103D03*
X408212Y1390083D03*
X410152Y1410928D03*
X398112Y1403741D03*
X401711Y1419771D03*
X406667D03*
X401990Y1446807D03*
X399731Y1442755D03*
X407469Y1495035D03*
X407854Y1492118D03*
X406377Y1499142D03*
X397245Y1511640D03*
X404053Y1513673D03*
X397220Y1521207D03*
X400911Y1537902D03*
X407048D03*
X400911Y1544424D03*
X407048Y1549936D03*
X400911D03*
X409461Y1569560D03*
X405461D03*
X420050Y33425D03*
X426147Y151540D03*
X414626Y180665D03*
Y172665D03*
X414658Y212864D03*
Y200864D03*
Y216864D03*
Y221864D03*
X422873Y309966D03*
X419955Y306966D03*
X414999D03*
X411984Y314921D03*
X421231Y338523D03*
Y331255D03*
Y345776D03*
X413432Y346797D03*
X426138Y355079D03*
X416318Y367903D03*
X424479Y367859D03*
X418876Y401661D03*
Y396661D03*
X411768Y408240D03*
X414268D03*
X418876Y399161D03*
X411847Y424240D03*
X414386Y420393D03*
X411886D03*
X411847Y426740D03*
X415453Y455039D03*
X418754Y468607D03*
X411754Y474513D03*
X424731Y508152D03*
Y513452D03*
Y515952D03*
X414275Y508217D03*
Y510717D03*
Y515717D03*
Y513217D03*
X424731Y510952D03*
X419040Y533690D03*
Y528390D03*
Y530990D03*
Y536290D03*
Y538890D03*
X423266Y631438D03*
X420266D03*
X417666D03*
X420266Y637038D03*
Y634238D03*
X417666Y637038D03*
Y634238D03*
X423266Y637038D03*
Y634238D03*
X418226Y653288D03*
X423266Y642638D03*
X420266D03*
X417666D03*
X423266Y639838D03*
X420266D03*
X418226Y646480D03*
Y648980D03*
X417666Y639838D03*
X418226Y655788D03*
X410603Y668060D03*
Y678060D03*
X424993Y728291D03*
X415700Y755400D03*
X415696Y762466D03*
X415700Y770200D03*
X426300Y797400D03*
X422430Y834800D03*
X424649Y842644D03*
X422149D03*
Y850644D03*
X424649D03*
X422149Y858644D03*
X424649D03*
X425759Y869921D03*
Y872721D03*
Y875521D03*
Y867121D03*
X422379Y867229D03*
X425759Y878321D03*
X411214Y892109D03*
X425121Y936686D03*
Y939186D03*
X417121Y936686D03*
Y939186D03*
X411960Y962261D03*
X414560D03*
X417160D03*
X411276Y978109D03*
X416476D03*
X413876D03*
X417677Y1052215D03*
X425175Y1098767D03*
X417171Y1098887D03*
X419987Y1098518D03*
X420782Y1105552D03*
X419731Y1123101D03*
X417231D03*
X422631Y1125801D03*
X425131Y1129301D03*
X422631D03*
X420131D03*
X417631D03*
X415131D03*
X412631D03*
X420131Y1125801D03*
X417631D03*
X425131D03*
X422495Y1152713D03*
Y1155213D03*
X412095Y1152713D03*
Y1155213D03*
X411461Y1162384D03*
Y1164884D03*
Y1167384D03*
Y1169884D03*
Y1172384D03*
X420619Y1179421D03*
Y1181921D03*
Y1184421D03*
Y1186921D03*
X411461Y1174884D03*
X422934Y1192621D03*
Y1190121D03*
X417469Y1192621D03*
Y1190121D03*
X413063Y1221428D03*
X417063D03*
X421063D03*
X425063D03*
X413063Y1237428D03*
Y1233428D03*
Y1229428D03*
Y1225428D03*
X417063Y1237428D03*
Y1233428D03*
Y1229428D03*
Y1225428D03*
X421063Y1237428D03*
Y1233428D03*
Y1229428D03*
Y1225428D03*
X425063Y1237428D03*
Y1233428D03*
Y1229428D03*
Y1225428D03*
X413063Y1245428D03*
Y1241428D03*
X417063Y1245428D03*
Y1241428D03*
X421063Y1245428D03*
Y1241428D03*
X425063Y1245428D03*
Y1241428D03*
X411174Y1282776D03*
X418537Y1300197D03*
X423741Y1300115D03*
X413354Y1300197D03*
X425582Y1291743D03*
X423762Y1305298D03*
X413374D03*
X418558Y1310523D03*
X413395Y1310481D03*
X423721Y1310523D03*
X414280Y1362561D03*
X425855Y1360495D03*
X425912Y1357141D03*
X413437Y1379736D03*
Y1384899D03*
X425283Y1373958D03*
X418610Y1371590D03*
X413395Y1390062D03*
X411147Y1474993D03*
X419818Y1474945D03*
X415241Y1492990D03*
X415095Y1502750D03*
X411353Y1519440D03*
X419467Y1519706D03*
X420279Y1525978D03*
X410626Y1525991D03*
X413012Y1537902D03*
Y1544098D03*
X426196Y1534087D03*
X413012Y1549936D03*
X421616Y1549885D03*
X413461Y1569560D03*
X412000Y1644980D03*
X428059Y3000D03*
X441727Y146461D03*
X440629Y152367D03*
X435703Y306966D03*
X430747D03*
X427829Y309966D03*
X428459Y331255D03*
X435793D03*
X428500Y345776D03*
X435793Y345738D03*
X430439Y358115D03*
X435702Y367813D03*
X430746D03*
X433724Y433975D03*
X432310Y436164D03*
X427782Y464026D03*
X429673Y461607D03*
X442704Y506427D03*
X427693Y506520D03*
X438396Y511493D03*
X438353Y508685D03*
X427693Y509020D03*
X432700Y516277D03*
X435834Y509580D03*
X428740Y533690D03*
X442704Y533790D03*
X428740Y528390D03*
Y530990D03*
X442704Y528490D03*
Y531090D03*
X428740Y536290D03*
X431804Y536682D03*
X428740Y538890D03*
X431804Y539182D03*
X442704Y536390D03*
X439804Y536682D03*
X442704Y538990D03*
X439804Y539182D03*
X436369Y622883D03*
X441832Y626193D03*
X441612Y631011D03*
X429210Y784833D03*
X428759Y869921D03*
Y867121D03*
Y872721D03*
Y875521D03*
Y878321D03*
X432332Y892049D03*
Y897649D03*
Y894849D03*
Y900449D03*
X432678Y1016186D03*
X429878D03*
X427078D03*
X427052Y1019384D03*
X429852D03*
X432652D03*
X433206Y1055498D03*
X430706D03*
Y1057998D03*
X433206D03*
Y1060498D03*
Y1062998D03*
X430706D03*
Y1060498D03*
X441359Y1123101D03*
X438233Y1139435D03*
X441359Y1125801D03*
X439759Y1129301D03*
X442259D03*
X429331Y1136935D03*
Y1134435D03*
Y1139435D03*
Y1131935D03*
X435733D03*
Y1134435D03*
Y1136935D03*
Y1139435D03*
X438233Y1131935D03*
Y1134435D03*
Y1136935D03*
X429348Y1129092D03*
X432838Y1128821D03*
X429331Y1141935D03*
X435733D03*
Y1146935D03*
Y1144435D03*
X438233Y1141935D03*
Y1146935D03*
Y1144435D03*
X437231Y1154902D03*
Y1152402D03*
X429331Y1146935D03*
Y1144435D03*
X436789Y1167384D03*
Y1164884D03*
Y1162384D03*
Y1172384D03*
Y1169884D03*
X439289Y1167384D03*
Y1164884D03*
Y1162384D03*
X427231D03*
X429731D03*
Y1164884D03*
Y1167384D03*
Y1169884D03*
Y1172384D03*
X427231D03*
Y1169884D03*
Y1167384D03*
Y1164884D03*
X439289Y1172384D03*
Y1169884D03*
X437132Y1158266D03*
X433249Y1186709D03*
Y1184209D03*
Y1181709D03*
Y1179209D03*
X429731Y1174884D03*
X427231D03*
X436789D03*
X439289D03*
X430934Y1190121D03*
Y1192621D03*
X429063Y1221428D03*
X433063D03*
X429063Y1237428D03*
Y1233428D03*
Y1229428D03*
Y1225428D03*
X433063Y1237428D03*
Y1233428D03*
Y1229428D03*
Y1225428D03*
X429063Y1245428D03*
Y1241428D03*
X433063Y1245428D03*
Y1241428D03*
X437991Y1286544D03*
X440896Y1311366D03*
X431867Y1315696D03*
X432485Y1325784D03*
X429530Y1325051D03*
X436002Y1382252D03*
X437675Y1550158D03*
X430657Y1563562D03*
X429784Y1548222D03*
X432000Y1644980D03*
X448059Y3000D03*
X458454Y328963D03*
Y324007D03*
Y339755D03*
Y344711D03*
X453463Y370694D03*
X448092Y375770D03*
X450852Y372054D03*
X455885Y367702D03*
X448323Y379643D03*
X446179Y447101D03*
X453544Y461961D03*
X451144Y472809D03*
X443094Y491251D03*
X459645Y509486D03*
X452404Y533690D03*
Y528390D03*
Y530990D03*
X455104Y536582D03*
X452404Y536290D03*
X455104Y539082D03*
X452404Y538890D03*
X447279Y633881D03*
X448726Y653288D03*
Y646480D03*
Y648980D03*
X456469Y638302D03*
X448726Y655788D03*
X447836Y711199D03*
X448999Y994483D03*
X456210Y1004680D03*
X452319Y1000828D03*
X449731Y1000855D03*
X453710Y1018825D03*
X443091Y1022766D03*
Y1030266D03*
X450063Y1043140D03*
X452091Y1039880D03*
X449767Y1047047D03*
X450244Y1090268D03*
X457303Y1098767D03*
X452115Y1098518D03*
X446863Y1098428D03*
X450244Y1093068D03*
X452910Y1105552D03*
X449359Y1123101D03*
X451859D03*
X457259Y1129301D03*
X449759Y1125801D03*
X452259D03*
X444759Y1129301D03*
X447259D03*
X449759D03*
X452259D03*
X454759Y1125801D03*
X457259D03*
X454759Y1129301D03*
X443223Y1155213D03*
Y1152713D03*
X452623D03*
Y1155213D03*
X457559Y1169884D03*
Y1167384D03*
Y1164884D03*
Y1162384D03*
X455059D03*
Y1164884D03*
Y1167384D03*
Y1169884D03*
Y1172384D03*
X457559D03*
X455059Y1174884D03*
X457559D03*
X447549Y1179421D03*
Y1181921D03*
Y1184421D03*
Y1186921D03*
X449864Y1190121D03*
Y1192621D03*
X454120Y1269498D03*
X456213Y1286776D03*
X451889Y1301067D03*
X451304Y1293045D03*
X456832Y1299121D03*
X451889Y1306023D03*
X454125Y1487159D03*
Y1558813D03*
Y1574167D03*
Y1604876D03*
X452000Y1644980D03*
X468059Y3000D03*
X474307Y102249D03*
X464738Y110784D03*
X462089Y113394D03*
X470307Y102249D03*
X466307D03*
X472332Y133298D03*
X464332D03*
X466479Y134579D03*
X470107Y195176D03*
X467607D03*
X472607D03*
X472226Y198883D03*
X475407Y195176D03*
X473655Y206838D03*
X467467Y203393D03*
X469967D03*
X472226Y201683D03*
X464054Y252371D03*
X461454Y336837D03*
Y331881D03*
Y347629D03*
Y352585D03*
X466375Y366365D03*
X470389Y389553D03*
X473658Y467215D03*
X471048Y464566D03*
X468558Y491669D03*
Y503669D03*
Y507669D03*
Y499669D03*
Y512669D03*
X463104Y536582D03*
X468850Y537507D03*
X463104Y539082D03*
X461849Y668016D03*
X459349D03*
X466849D03*
X469349D03*
X464349D03*
X469349Y678016D03*
X466849D03*
X459349D03*
X461849D03*
X464349D03*
X462242Y809792D03*
X459245Y807152D03*
X473654Y821234D03*
X475032Y843252D03*
X472399Y839566D03*
X474678Y857919D03*
X463134Y859203D03*
X460455Y867050D03*
X475046Y885952D03*
X467494Y924532D03*
X469495Y1011303D03*
Y1023303D03*
Y1017303D03*
X462427Y1030218D03*
X464385Y1038534D03*
X460277Y1090268D03*
Y1093068D03*
X474818Y1123101D03*
X469192Y1131935D03*
X474818Y1125801D03*
X473218Y1129301D03*
X461459Y1136935D03*
Y1134435D03*
Y1139435D03*
Y1131935D03*
X471692Y1139435D03*
Y1136935D03*
Y1134435D03*
Y1131935D03*
X469192Y1139435D03*
Y1136935D03*
Y1134435D03*
X471692Y1146935D03*
Y1141935D03*
X469192Y1144435D03*
Y1146935D03*
Y1141935D03*
X471692Y1144435D03*
X461459D03*
X462687Y1152684D03*
X468850D03*
X461459Y1141935D03*
Y1146935D03*
X462687Y1160834D03*
X474548Y1172384D03*
Y1169884D03*
Y1167384D03*
Y1164884D03*
Y1162384D03*
X468850Y1160834D03*
X474548Y1174884D03*
X463216Y1254164D03*
X461613Y1286776D03*
X462786Y1609207D03*
X471448Y1604876D03*
X472000Y1644980D03*
X484043Y4469D03*
X485404Y24773D03*
Y44773D03*
X480324Y109172D03*
X477324D03*
X479331Y106495D03*
X485475Y118342D03*
Y121742D03*
Y132515D03*
X479065Y146012D03*
X480971Y141228D03*
X485475Y135915D03*
X483859Y150847D03*
X476155Y206838D03*
X491607Y213539D03*
X485827Y247292D03*
X478617Y236121D03*
X475651Y238589D03*
X485053Y238689D03*
X478536Y253198D03*
X483242Y366481D03*
X483584Y375840D03*
X483736Y371266D03*
X483541Y380306D03*
X481724Y391589D03*
Y387089D03*
X488438Y425464D03*
X482532Y418464D03*
X482484Y444517D03*
X482193Y472784D03*
Y468784D03*
Y476784D03*
X492736Y478982D03*
X482737Y537215D03*
X482905Y527726D03*
Y552726D03*
Y540726D03*
X486738Y581222D03*
X489538D03*
Y591215D03*
X486738D03*
X491340Y611091D03*
X485005Y659771D03*
X491324Y667293D03*
X485303Y681841D03*
X484341Y700528D03*
Y705484D03*
X486246Y804497D03*
X485824Y819787D03*
X481593Y826387D03*
X491453Y834546D03*
X491527Y843206D03*
X479700Y847600D03*
X488469Y857013D03*
X481943Y924633D03*
X488388Y938903D03*
X490143Y989521D03*
X481495Y1011303D03*
X475495D03*
X481495Y1023303D03*
Y1017303D03*
X475495Y1023303D03*
X476148Y1057998D03*
Y1055498D03*
X478648D03*
Y1057998D03*
X476148Y1060498D03*
Y1062998D03*
X478648D03*
Y1060498D03*
X490762Y1098767D03*
X485574Y1098518D03*
X480322Y1098428D03*
X486369Y1105552D03*
X485318Y1123101D03*
X482818D03*
X490718Y1129301D03*
X483218Y1125801D03*
X485718D03*
X475718Y1129301D03*
X478218D03*
X480718D03*
X483218D03*
X485718D03*
X488218Y1125801D03*
X490718D03*
X488218Y1129301D03*
X477682Y1152713D03*
Y1155213D03*
X488082D03*
Y1152713D03*
X477048Y1172384D03*
Y1169884D03*
Y1167384D03*
Y1164884D03*
Y1162384D03*
X479521Y1179209D03*
Y1181709D03*
Y1184209D03*
Y1186709D03*
X477048Y1174884D03*
X490671Y1192621D03*
Y1190121D03*
X477206Y1192621D03*
Y1190121D03*
X484800Y1302000D03*
X488771Y1604876D03*
X480109Y1609207D03*
X492725Y53597D03*
X503537Y77784D03*
Y75184D03*
Y80384D03*
Y82984D03*
X506091Y92849D03*
X503537Y85584D03*
X503075Y102323D03*
X503327Y109410D03*
X495075Y102323D03*
X492775Y114655D03*
Y111255D03*
Y128828D03*
Y125428D03*
X497424Y354559D03*
X492317Y376252D03*
X493485Y439903D03*
X503682Y455466D03*
X497776Y448466D03*
X492736Y487982D03*
Y483982D03*
Y499982D03*
X506925Y546830D03*
X493929Y555194D03*
X496729D03*
X493929Y563194D03*
X496729D03*
X493929Y571194D03*
X496729D03*
X492338Y581222D03*
Y591215D03*
X499278Y641817D03*
X493778D03*
X494632Y654622D03*
X498284Y681453D03*
Y678953D03*
X501618Y698355D03*
X507546Y738539D03*
X505673Y767961D03*
X500717D03*
X491655Y829173D03*
X492799Y846488D03*
X497467Y833027D03*
X506566Y1000766D03*
Y1004766D03*
Y1016266D03*
Y1030766D03*
X505981Y1052487D03*
X506946Y1123101D03*
Y1125801D03*
X505346Y1129301D03*
X507846D03*
X503820Y1139435D03*
Y1136935D03*
Y1134435D03*
Y1131935D03*
X501320Y1139435D03*
Y1136935D03*
Y1134435D03*
Y1131935D03*
X494918Y1136935D03*
Y1134435D03*
Y1139435D03*
Y1131935D03*
X498727Y1128759D03*
X495236Y1129094D03*
X503820Y1144435D03*
Y1146935D03*
Y1141935D03*
X501320Y1144435D03*
Y1146935D03*
Y1141935D03*
X494918Y1146935D03*
Y1144435D03*
Y1141935D03*
X502562Y1152713D03*
Y1155213D03*
X502376Y1172384D03*
Y1169884D03*
Y1167384D03*
Y1164884D03*
Y1162384D03*
X504876Y1172384D03*
Y1169884D03*
Y1167384D03*
Y1164884D03*
Y1162384D03*
X492818D03*
Y1164884D03*
Y1167384D03*
Y1169884D03*
Y1172384D03*
X495318D03*
Y1169884D03*
Y1167384D03*
Y1164884D03*
Y1162384D03*
X502562Y1158200D03*
X506451Y1179209D03*
Y1181709D03*
Y1184209D03*
Y1186709D03*
X504876Y1174884D03*
X493821Y1186921D03*
Y1184421D03*
Y1181921D03*
Y1179421D03*
X492818Y1174884D03*
X495318D03*
X502376D03*
X504136Y1190121D03*
Y1192621D03*
X496136Y1190121D03*
Y1192621D03*
X506562Y1222194D03*
X502562D03*
X498562D03*
X494562D03*
X506562Y1226194D03*
Y1230194D03*
Y1234194D03*
Y1238194D03*
X502562Y1226194D03*
Y1230194D03*
Y1234194D03*
Y1238194D03*
X498562Y1226194D03*
Y1230194D03*
Y1234194D03*
Y1238194D03*
X494562Y1226194D03*
Y1230194D03*
Y1234194D03*
Y1238194D03*
Y1246194D03*
Y1242194D03*
X506562D03*
Y1246194D03*
X502562Y1242194D03*
Y1246194D03*
X498562Y1242194D03*
Y1246194D03*
X506093Y1604876D03*
X497432Y1609207D03*
X492000Y1644980D03*
X512725Y53597D03*
X513051Y103037D03*
X513185Y116496D03*
Y109410D03*
X521185Y116496D03*
Y109410D03*
Y102323D03*
X513185Y123583D03*
X521185Y130670D03*
Y123583D03*
Y137756D03*
X522276Y223661D03*
Y226461D03*
Y228961D03*
Y231461D03*
X517866Y293796D03*
X515366D03*
X523380Y285690D03*
Y288190D03*
X520845Y434508D03*
X516845D03*
X512845D03*
X514608Y445874D03*
X510022Y446352D03*
X523705Y444269D03*
X523583Y447201D03*
X508729Y469905D03*
X521310Y470045D03*
X513310D03*
X523457Y482134D03*
Y484634D03*
X521636Y504699D03*
X516636D03*
X519136D03*
X516756Y500086D03*
X517319Y521804D03*
X516338Y516979D03*
X521338D03*
X518838D03*
X513626Y528578D03*
Y531378D03*
X518781Y527449D03*
X517319Y524304D03*
X521581Y527449D03*
X521494Y572975D03*
X524770Y605637D03*
X520770Y605443D03*
X516770D03*
X523596Y628242D03*
X512404Y629362D03*
X510215Y627948D03*
X521778Y642184D03*
X521868Y666577D03*
X518812Y662874D03*
X511990Y686365D03*
X521540Y686319D03*
X518001Y694940D03*
X522410Y694881D03*
X518067Y699378D03*
X518530Y703584D03*
X522628Y703884D03*
X512530Y718301D03*
X514531Y716398D03*
X508237Y723585D03*
X512502Y738539D03*
X516953Y738575D03*
X521909D03*
X520159Y758832D03*
X517194Y773232D03*
X514682Y834590D03*
X511741Y846649D03*
X521572Y901500D03*
X519792Y1031271D03*
X515831Y1090568D03*
X517702Y1098518D03*
X512450Y1098428D03*
X515831Y1093068D03*
X522890Y1098767D03*
X518497Y1105552D03*
X514946Y1123101D03*
X517446D03*
X522846Y1129301D03*
X515346Y1125801D03*
X517846D03*
X510346Y1129301D03*
X512846D03*
X515346D03*
X517846D03*
X520346Y1125801D03*
X522846D03*
X520346Y1129301D03*
X518210Y1155213D03*
Y1152713D03*
X508810D03*
Y1155213D03*
X520646Y1169884D03*
Y1167384D03*
Y1164884D03*
Y1162384D03*
X523146D03*
Y1164884D03*
Y1167384D03*
Y1169884D03*
Y1172384D03*
X520646D03*
X520751Y1186921D03*
Y1184421D03*
Y1181921D03*
Y1179421D03*
X523146Y1174884D03*
X520646D03*
X523066Y1190121D03*
Y1192621D03*
X522562Y1222194D03*
X518562D03*
X514562D03*
X510562D03*
X522562Y1226194D03*
X518562D03*
Y1230194D03*
Y1234194D03*
X514562Y1226194D03*
Y1230194D03*
Y1234194D03*
Y1238194D03*
X510562Y1226194D03*
Y1230194D03*
Y1234194D03*
Y1238194D03*
X514562Y1242194D03*
Y1246194D03*
X510562Y1242194D03*
Y1246194D03*
X517374Y1287222D03*
X514363Y1287370D03*
X520548Y1287181D03*
X514755Y1609207D03*
X512000Y1644980D03*
X531518Y5374D03*
X530831Y24773D03*
Y44773D03*
X526468Y94017D03*
X530197Y101701D03*
X534468Y94017D03*
X538477D03*
X530468D03*
X530596Y115401D03*
X535588Y110445D03*
Y115401D03*
X530596Y110445D03*
X537747Y103783D03*
X530596Y124618D03*
Y129574D03*
X535588Y124618D03*
Y129574D03*
X528509Y151540D03*
X538659Y184619D03*
X532159Y191941D03*
X532026Y188727D03*
X530245Y229286D03*
X528783Y226141D03*
X525983D03*
X533938Y222212D03*
Y224712D03*
X526226Y236611D03*
X531226D03*
X528726D03*
X530245Y231786D03*
X528428Y248891D03*
X530928D03*
X533853Y256535D03*
X525928Y248891D03*
X525880Y285690D03*
X528680D03*
X525880Y288190D03*
X528680D03*
X532906Y290755D03*
X536906D03*
X540906D03*
X524206Y354119D03*
X533027Y351836D03*
X530215Y364422D03*
X535142Y397552D03*
X526902Y478446D03*
Y475946D03*
X531412Y480705D03*
X528612D03*
X532936Y519544D03*
X525288Y522129D03*
X527936Y519544D03*
X525436D03*
X530436D03*
X525288Y524629D03*
Y527129D03*
Y529929D03*
X529481Y532849D03*
X532281D03*
X524708Y572842D03*
X532863Y585507D03*
X528270D03*
X528816Y579475D03*
X532908Y590190D03*
X528314Y590145D03*
X532770Y605443D03*
X538826Y633450D03*
X526756Y636005D03*
Y633205D03*
X538826Y636250D03*
Y639050D03*
X526756Y638805D03*
X524653Y643595D03*
X533486Y664052D03*
X538442D03*
X524941Y661387D03*
X530796D03*
X534940Y684489D03*
X539111Y681459D03*
X526956Y694959D03*
X526951Y699443D03*
X535387Y712617D03*
X526933Y703820D03*
X532628Y720776D03*
X526276Y721339D03*
X539763Y734097D03*
X534807D03*
X531763Y739097D03*
X526807D03*
X532450Y767474D03*
X542275Y760782D03*
X532278Y762736D03*
X527046Y1131935D03*
Y1139435D03*
Y1134435D03*
Y1136935D03*
X528274Y1152684D03*
X527046Y1146935D03*
Y1144435D03*
Y1141935D03*
X528274Y1160834D03*
X532000Y1644980D03*
X550421Y3000D03*
X543545Y84140D03*
Y80140D03*
Y76140D03*
X540998Y117557D03*
X545990D03*
X548914Y103621D03*
X545990Y122513D03*
Y131731D03*
X540998Y122513D03*
Y131731D03*
X544089Y146461D03*
X545990Y136687D03*
X540998D03*
X542991Y152367D03*
X549374Y180527D03*
X544691Y180572D03*
X553097Y192421D03*
X549329Y185121D03*
X544691Y185165D03*
X540639Y206760D03*
X541853Y256535D03*
X542883Y279208D03*
X546987Y281307D03*
X551477Y288345D03*
Y290845D03*
X548977Y288345D03*
Y290845D03*
Y293645D03*
X551477D03*
X541644Y389047D03*
X553731Y388487D03*
X541706Y381723D03*
X552905Y430829D03*
X540770Y605443D03*
X550274Y658676D03*
X556574Y684031D03*
Y700031D03*
Y688987D03*
Y716031D03*
Y704987D03*
Y720987D03*
X552384Y762892D03*
X552188Y766577D03*
X546241Y843149D03*
X542793Y998507D03*
X557681Y1035088D03*
X552000Y1644980D03*
X570421Y3000D03*
X566287Y60922D03*
X561123Y55513D03*
X563224Y96813D03*
X558316Y91951D03*
X556920Y117261D03*
X567100Y110784D03*
X564451Y113394D03*
X572669Y102249D03*
X568669D03*
X567290Y130898D03*
X568841Y134579D03*
X564627Y180665D03*
Y172665D03*
X569969Y195176D03*
X572469D03*
X572329Y203393D03*
X574588Y201683D03*
X564659Y212864D03*
Y200864D03*
X569829Y203393D03*
X564659Y221864D03*
Y216864D03*
X566416Y252371D03*
X570634Y375453D03*
X559074Y696987D03*
Y692031D03*
Y712987D03*
Y708031D03*
X561886Y728138D03*
X559625Y739609D03*
X557813Y747814D03*
X570578Y749800D03*
X570695Y767052D03*
X564276Y776701D03*
X568990Y844721D03*
X559295Y874267D03*
X559887Y877196D03*
X559260Y891043D03*
X560923Y980443D03*
X556923Y980523D03*
X565451Y1035102D03*
X559057Y1030563D03*
X562057D03*
X569520Y1102091D03*
X560211D03*
X566020D03*
X569520Y1114691D03*
X566020D03*
X560211D03*
X566020Y1127291D03*
X560211D03*
X569520D03*
X565600Y1530800D03*
X569349Y1541947D03*
X560635Y1543531D03*
X566800Y1541800D03*
X586405Y4469D03*
X587766Y24773D03*
Y44773D03*
X576669Y102249D03*
X582686Y109172D03*
X579686D03*
X581693Y106495D03*
X574694Y133298D03*
X587837Y118342D03*
Y121742D03*
Y132515D03*
X581427Y146012D03*
X583333Y141228D03*
X587837Y135915D03*
X586221Y150847D03*
X574969Y195176D03*
X577769D03*
X574588Y198883D03*
X578517Y206838D03*
X576017D03*
X587415Y238689D03*
X588189Y247292D03*
X580979Y236121D03*
X578013Y238589D03*
X580898Y253198D03*
X581487Y336676D03*
X573805Y728301D03*
X574620Y772724D03*
X588345Y798030D03*
X588377Y807536D03*
X588272Y804601D03*
X588231Y801520D03*
X577501Y829069D03*
X588001Y829624D03*
X579827Y888000D03*
X585703Y941307D03*
X587689Y1505724D03*
X583661Y1529142D03*
X573784Y1530646D03*
X575332Y1523740D03*
X583800Y1518000D03*
X583740Y1520640D03*
X587858Y1517942D03*
X577645Y1540982D03*
X580700Y1544100D03*
X595087Y53597D03*
X597437Y102323D03*
X595137Y111255D03*
Y114655D03*
Y125428D03*
Y128828D03*
X593969Y213539D03*
X590178Y309760D03*
X603282Y390223D03*
X600272Y397335D03*
X603282Y395179D03*
Y404396D03*
Y409352D03*
X595280Y402291D03*
X600272D03*
X595280Y397335D03*
X592880Y416465D03*
Y411509D03*
X603282Y418569D03*
Y423525D03*
X597872Y425682D03*
X592880D03*
X597872Y416465D03*
Y411509D03*
X603282Y432743D03*
Y437699D03*
X597872Y439855D03*
X592880D03*
X597872Y430638D03*
X592880D03*
X597872Y444811D03*
X592880D03*
X593690Y450750D03*
X592880Y468609D03*
X597872D03*
X592880Y473565D03*
X597872D03*
X603282Y489895D03*
X592880Y487738D03*
X597872D03*
X603282Y480677D03*
Y475721D03*
X592880Y482782D03*
X597872D03*
X603282Y494851D03*
X592880Y517699D03*
X597872D03*
X603282Y519855D03*
X597872Y512743D03*
X592880D03*
Y526916D03*
X597872Y531872D03*
X592880D03*
X603282Y524811D03*
Y538984D03*
Y534028D03*
X597872Y526916D03*
X597789Y536382D03*
X602756Y597580D03*
X604979Y599588D03*
X604241Y589556D03*
X604180Y592354D03*
X602695Y594668D03*
X604982Y596095D03*
X605011Y615600D03*
X604979Y607588D03*
X589203Y941407D03*
X591403Y938807D03*
Y936007D03*
X590957Y1105091D03*
Y1117691D03*
X592978Y1514812D03*
X591858Y1523542D03*
X598800Y1546400D03*
X615087Y53597D03*
X605899Y80384D03*
Y82984D03*
Y77784D03*
Y75184D03*
X608453Y92849D03*
X605899Y85584D03*
X615413Y103037D03*
X605437Y102323D03*
X605689Y109410D03*
X615547Y116496D03*
Y109410D03*
Y123583D03*
X620228Y293796D03*
X608274Y418569D03*
Y423525D03*
Y432743D03*
Y437699D03*
Y489895D03*
Y480677D03*
Y475721D03*
Y494851D03*
Y519855D03*
Y524811D03*
X609472Y634946D03*
X618878Y1011914D03*
X612000Y1644980D03*
X633248Y44884D03*
X636830Y94017D03*
X628830D03*
X632830D03*
X632559Y101701D03*
X632958Y110445D03*
X623547Y109410D03*
Y116496D03*
X632958Y115401D03*
X623547Y102323D03*
X632958Y124618D03*
X623547Y123583D03*
Y130670D03*
X632958Y129574D03*
X623547Y137756D03*
X630871Y151540D03*
X634521Y191941D03*
X634388Y188727D03*
X624638Y231461D03*
X636300Y222212D03*
Y224712D03*
X632607Y229286D03*
X624638Y223661D03*
X631145Y226141D03*
X624638Y226461D03*
X628345Y226141D03*
X624638Y228961D03*
X633588Y236611D03*
X631088D03*
X632607Y231786D03*
X628588Y236611D03*
X630790Y248891D03*
X633290D03*
X628290D03*
X636215Y256535D03*
X631042Y288190D03*
Y285690D03*
X625742Y288190D03*
X628242Y285690D03*
X625742D03*
X628242Y288190D03*
X635268Y290755D03*
X634455Y389154D03*
Y396240D03*
Y403327D03*
Y410413D03*
Y417500D03*
Y424587D03*
Y431673D03*
Y438760D03*
Y445847D03*
Y467539D03*
Y474626D03*
Y488799D03*
Y481713D03*
Y495886D03*
Y511673D03*
Y518760D03*
Y525847D03*
Y532933D03*
Y540020D03*
Y547106D03*
X633736Y602197D03*
X634200Y595108D03*
X627354Y1574167D03*
X636015Y1578498D03*
X627354Y1578898D03*
X636015Y1593853D03*
X627354Y1594253D03*
X636015Y1583229D03*
X627354Y1583629D03*
Y1589522D03*
X636015Y1587960D03*
X627354Y1604876D03*
X636015Y1603315D03*
Y1598584D03*
X627354Y1598984D03*
X636015Y1609207D03*
X627354Y1609607D03*
X636015Y1618669D03*
Y1613938D03*
X627354Y1614338D03*
X632000Y1644980D03*
X645907Y76140D03*
Y84140D03*
Y80140D03*
X640839Y94017D03*
X643360Y117557D03*
X637950Y110445D03*
Y115401D03*
X648352Y117557D03*
X651276Y103621D03*
X640109Y103783D03*
X643360Y122513D03*
Y131731D03*
X637950Y124618D03*
Y129574D03*
X648352Y122513D03*
Y131731D03*
X646451Y146461D03*
X643360Y136687D03*
X648352D03*
X645353Y152367D03*
X647053Y180572D03*
X651736Y180527D03*
X651691Y185121D03*
X647053Y185165D03*
X641021Y184619D03*
X643001Y206760D03*
X644215Y256535D03*
X645245Y279208D03*
X649349Y281307D03*
X651339Y290845D03*
Y293645D03*
X653839D03*
X639268Y290755D03*
X643268D03*
X653839Y288345D03*
Y290845D03*
X651339Y288345D03*
X642255Y389154D03*
X649074D03*
X642255Y396240D03*
X643534Y404911D03*
X647604Y396240D03*
X642488Y412571D03*
X652381Y414823D03*
X651689Y422864D03*
X643675Y426299D03*
X651759Y429832D03*
X651364Y436447D03*
X653399Y447953D03*
X643986Y445847D03*
X642255Y467539D03*
X652566D03*
X642255Y474626D03*
X651308Y472772D03*
X652042Y487711D03*
X652155Y479104D03*
X642516Y480828D03*
X644466Y498834D03*
X652566Y495886D03*
X647915Y516841D03*
X651166Y510565D03*
X642255Y518760D03*
Y511673D03*
Y525847D03*
X642862Y550123D03*
X642740Y552872D03*
X644494Y572334D03*
X642185Y562443D03*
X643953Y560675D03*
X642726Y574102D03*
X651149Y577716D03*
X648211Y602400D03*
Y598400D03*
Y594400D03*
Y606400D03*
Y614400D03*
X647361Y653161D03*
X648352Y645467D03*
X650958Y677843D03*
X653338Y1578498D03*
X644677Y1578898D03*
Y1574167D03*
X653338Y1587960D03*
Y1593853D03*
X644677Y1594253D03*
Y1589522D03*
X653338Y1583229D03*
X644677Y1583629D03*
X653338Y1609207D03*
X644677Y1598984D03*
Y1604876D03*
Y1609607D03*
X653338Y1603315D03*
Y1598584D03*
Y1613938D03*
X644677Y1614338D03*
X653338Y1618669D03*
X652000Y1644980D03*
X668649Y60922D03*
X666209Y57297D03*
X665423Y96853D03*
X660678Y91951D03*
X659282Y117261D03*
X666813Y113394D03*
X669462Y110784D03*
X669056Y133298D03*
X666989Y172665D03*
Y180665D03*
X655459Y192421D03*
X667021Y200864D03*
Y212864D03*
Y221864D03*
Y216864D03*
X668778Y252371D03*
X660366Y389154D03*
X667666Y389153D03*
X660366Y403327D03*
Y410413D03*
X665166Y396240D03*
X667666D03*
X665166Y403327D03*
X667666Y403326D03*
X665166Y410413D03*
X667666D03*
X660366Y396240D03*
X667666Y417499D03*
X665166Y424586D03*
X667666D03*
X660366Y417500D03*
Y424586D03*
X665166Y417500D03*
Y431673D03*
Y438760D03*
X667666D03*
Y431673D03*
X660366D03*
Y438760D03*
X665166Y445847D03*
X660366D03*
X667666Y467539D03*
X660366D03*
X665166Y474626D03*
X667666D03*
X660366D03*
Y488799D03*
X665166D03*
X667666D03*
Y481712D03*
X665166D03*
X660366Y481713D03*
X665166Y495886D03*
X660366D03*
X667666Y518760D03*
X665166D03*
X667666Y511673D03*
X660366D03*
Y518760D03*
X667666Y532933D03*
X665166D03*
Y540020D03*
Y525846D03*
X667666D03*
X660366Y525847D03*
Y532933D03*
Y540020D03*
Y554193D03*
Y547106D03*
X661760Y551683D03*
X660826Y570414D03*
Y567914D03*
Y565414D03*
X669546Y560500D03*
X660826Y575414D03*
Y572914D03*
X658233Y646449D03*
X658064Y650119D03*
X655752Y668885D03*
X661776Y662981D03*
X656157Y691851D03*
X661768Y705043D03*
X662000Y1578898D03*
Y1574167D03*
Y1594253D03*
Y1589522D03*
Y1583629D03*
Y1598984D03*
Y1604876D03*
Y1609607D03*
Y1614338D03*
X679031Y102249D03*
X682048Y109172D03*
X685048D03*
X684055Y106495D03*
X677056Y133298D03*
X671203Y134579D03*
X683789Y146012D03*
X685695Y141228D03*
X672331Y195176D03*
X674831D03*
X677331D03*
X676950Y198883D03*
X680131Y195176D03*
X672191Y203393D03*
X676950Y201683D03*
X674691Y203393D03*
X678379Y206838D03*
X680879D03*
X680375Y238589D03*
X683341Y236121D03*
X683260Y253198D03*
X686012Y339795D03*
X685353Y392718D03*
X672466Y389153D03*
Y410413D03*
X685353Y408718D03*
Y400718D03*
Y404718D03*
X672466Y396240D03*
Y403326D03*
Y424586D03*
Y417499D03*
X685353Y412718D03*
X672466Y438760D03*
Y431673D03*
Y467539D03*
Y474626D03*
Y488799D03*
Y481712D03*
Y518760D03*
Y511673D03*
Y525846D03*
Y532933D03*
X681011Y543925D03*
X679322Y1578898D03*
Y1574167D03*
X670661Y1578498D03*
X679322Y1583629D03*
X670661Y1587960D03*
Y1593853D03*
Y1583229D03*
X679322Y1594253D03*
Y1589522D03*
Y1604876D03*
Y1609607D03*
X670661Y1603315D03*
Y1598584D03*
Y1609207D03*
X679322Y1598984D03*
Y1614338D03*
X670661Y1618669D03*
Y1613938D03*
X672000Y1644980D03*
X690073Y44662D03*
X697387Y53619D03*
X699799Y102323D03*
X697499Y114655D03*
Y111255D03*
X690199Y132515D03*
X697499Y125428D03*
Y128828D03*
X690199Y121742D03*
Y118342D03*
Y135915D03*
X688583Y150847D03*
X696331Y213539D03*
X689777Y238689D03*
X690551Y247292D03*
X700164Y636842D03*
X698936Y678462D03*
X702691Y766471D03*
Y753471D03*
X702677Y771159D03*
X696645Y1574167D03*
Y1578898D03*
X687984Y1578498D03*
Y1583229D03*
X696645Y1589522D03*
Y1594253D03*
X687984Y1587960D03*
Y1593853D03*
X696645Y1583629D03*
Y1598984D03*
Y1609607D03*
X687984Y1603315D03*
Y1598584D03*
Y1609207D03*
X696645Y1604876D03*
X687984Y1613938D03*
X696645Y1614338D03*
X687984Y1618669D03*
X692000Y1644980D03*
X717387Y53619D03*
X708261Y82984D03*
Y80384D03*
Y77784D03*
Y75184D03*
X710815Y92849D03*
X708261Y85584D03*
X717775Y103037D03*
X707799Y102323D03*
X708051Y109410D03*
X717909Y116496D03*
Y109410D03*
Y123583D03*
X713162Y434493D03*
X711764Y449873D03*
X718691Y465492D03*
Y472579D03*
X716191D03*
X711391D03*
X716191Y479666D03*
X718691D03*
X711391D03*
Y486752D03*
X716191D03*
X718691D03*
X711391Y493839D03*
X716191D03*
Y516713D03*
Y523800D03*
X718691D03*
X711391D03*
Y516713D03*
X718691D03*
Y509626D03*
Y530886D03*
X716191D03*
Y537973D03*
X711391Y530886D03*
Y537973D03*
Y566752D03*
X718691Y559665D03*
Y566752D03*
X716191D03*
X711391Y573839D03*
X718691D03*
X716191D03*
X711391Y588013D03*
X718691Y588012D03*
X716191Y588013D03*
X718691Y580926D03*
X716191D03*
X711391D03*
X716191Y602186D03*
X711391D03*
X718691Y602185D03*
Y595099D03*
X711391D03*
X716191D03*
X711391Y609272D03*
X716191D03*
X718691D03*
X716191Y616359D03*
X711391D03*
X706070Y638125D03*
X716656Y646429D03*
X703669Y665140D03*
X716350Y699477D03*
X703604Y699653D03*
X704446Y760611D03*
X712000Y1644980D03*
X735192Y94017D03*
X731192D03*
X734921Y101701D03*
X725909Y102323D03*
Y116496D03*
Y109410D03*
Y130670D03*
Y123583D03*
Y137756D03*
X733233Y151540D03*
X736750Y188727D03*
X727000Y228961D03*
X730707Y226141D03*
X727000Y226461D03*
X733507Y226141D03*
X727000Y223661D03*
X734969Y229286D03*
X727000Y231461D03*
X733450Y236611D03*
X730950D03*
X734969Y231786D03*
X733152Y248891D03*
X730652D03*
X733404Y285690D03*
X720090Y293796D03*
X722590D03*
X728104Y288190D03*
X730604Y285690D03*
X728104D03*
X730604Y288190D03*
X733404D03*
X731511Y390500D03*
X734606Y379562D03*
X722097Y410394D03*
Y403307D03*
X723031Y440098D03*
Y437598D03*
Y435098D03*
Y432598D03*
Y430098D03*
X723491Y458406D03*
Y451319D03*
Y465492D03*
X731291Y466027D03*
X723315Y462264D03*
X723491Y472579D03*
X731433Y475262D03*
Y489435D03*
Y482666D03*
X723491Y479665D03*
Y486752D03*
Y493839D03*
X731249Y495088D03*
X723491Y523799D03*
Y516713D03*
Y509626D03*
X731984Y514608D03*
X731906Y522134D03*
X731291Y509626D03*
X723491Y530886D03*
Y537973D03*
X732549Y529136D03*
X732388Y535677D03*
X723491Y566752D03*
Y559665D03*
X731291D03*
X731672Y565574D03*
X723491Y573839D03*
Y588012D03*
Y580926D03*
X731319Y574338D03*
X723491Y595099D03*
Y602185D03*
Y609272D03*
Y616358D03*
X731418D03*
X734819Y646429D03*
X721218Y742131D03*
X725318Y890354D03*
X720373Y940310D03*
X724547Y958287D03*
X732000Y1644980D03*
X736242Y5374D03*
X735555Y24773D03*
Y44773D03*
X748269Y84140D03*
Y76140D03*
Y80140D03*
X743201Y94017D03*
X739192D03*
X750714Y117557D03*
X745722D03*
X740312Y115401D03*
Y110445D03*
X735320D03*
Y115401D03*
X742471Y103783D03*
X745722Y131731D03*
Y122513D03*
X740312Y129574D03*
Y124618D03*
X735320D03*
Y129574D03*
X750714Y131731D03*
Y122513D03*
Y136687D03*
X745722D03*
X748813Y146461D03*
X747715Y152367D03*
X749415Y180572D03*
Y185165D03*
X743383Y184619D03*
X736883Y191941D03*
X745363Y206760D03*
X738662Y224712D03*
Y222212D03*
X735950Y236611D03*
X735652Y248891D03*
X738577Y256535D03*
X746577D03*
X747607Y279208D03*
X751711Y281307D03*
X741630Y290755D03*
X737630D03*
X745630D03*
X741161Y381500D03*
X749586Y410394D03*
Y403307D03*
X741259Y439963D03*
X741381Y430760D03*
X741402Y433570D03*
X741218Y437072D03*
X741503Y443180D03*
X741523Y454744D03*
X741465Y452018D03*
X749402Y458406D03*
X741602Y465492D03*
X741568Y460250D03*
X739333Y470136D03*
X749402Y465492D03*
X741602Y472579D03*
X749402D03*
X741072Y478958D03*
X741602Y486752D03*
X749402Y479665D03*
Y486752D03*
Y493839D03*
X741602D03*
X749402Y523799D03*
Y516713D03*
Y509626D03*
X741602D03*
Y516713D03*
X749402Y537973D03*
Y530886D03*
X738062Y537973D03*
X740542Y525483D03*
X740463Y532756D03*
X749402Y559665D03*
Y566752D03*
X741602Y559665D03*
Y566752D03*
X749402Y573839D03*
Y588012D03*
Y580925D03*
X741452Y579978D03*
X741602Y573839D03*
X749402Y602185D03*
Y595099D03*
X741666Y608117D03*
X735576Y861780D03*
X738707Y987952D03*
X751140Y1581335D03*
X740640Y1586885D03*
X748924Y1617709D03*
X735878Y1617010D03*
X747590Y1627871D03*
X755145Y3000D03*
X765847Y55513D03*
X763040Y91951D03*
X762065Y117040D03*
X753638Y103621D03*
X754098Y180527D03*
X757821Y192421D03*
X754053Y185121D03*
X756201Y288345D03*
Y290845D03*
X753701Y288345D03*
Y290845D03*
Y293645D03*
X756201D03*
X760407Y324494D03*
X767099Y316731D03*
X763898Y342319D03*
X759029Y332017D03*
X766344Y393924D03*
Y389912D03*
Y385912D03*
X758038Y381143D03*
X766344Y401924D03*
X752341Y407148D03*
X756800Y403824D03*
X758381Y395391D03*
X755593Y445908D03*
X765713Y1437365D03*
X766433Y1583713D03*
X767310Y1599164D03*
X756358Y1616917D03*
X752150Y1627871D03*
X762776Y1629415D03*
X752000Y1644980D03*
X775145Y3000D03*
X771011Y60922D03*
X781393Y102249D03*
X767929Y96890D03*
X771824Y110784D03*
X777393Y102249D03*
X773393D03*
X769175Y113394D03*
X779418Y133298D03*
X771960Y130898D03*
X773565Y134579D03*
X769351Y172665D03*
Y180665D03*
X779693Y195176D03*
X779312Y198883D03*
X777193Y195176D03*
X782493D03*
X774693D03*
X780741Y206838D03*
X783241D03*
X777053Y203393D03*
X779312Y201683D03*
X774553Y203393D03*
X769383Y200864D03*
Y212864D03*
Y221864D03*
Y216864D03*
X782737Y238589D03*
X771140Y252371D03*
X780968Y303839D03*
X776943Y321649D03*
X772990Y336324D03*
X778881Y446510D03*
X779029Y450510D03*
X780575Y471484D03*
Y466528D03*
Y480701D03*
X775583Y485657D03*
X780575D03*
Y510661D03*
X775583Y515617D03*
X780575D03*
X775583Y510661D03*
X780575Y524835D03*
Y529791D03*
X775583Y524835D03*
Y529791D03*
X780575Y560701D03*
Y565657D03*
X775583Y560701D03*
Y565657D03*
Y579830D03*
X780575D03*
X775583Y574874D03*
X780575D03*
X775583Y589047D03*
X780575D03*
Y594003D03*
X775583D03*
Y603221D03*
X780575D03*
X775583Y608177D03*
X780575D03*
X778860Y626912D03*
X783694Y1410977D03*
X778685Y1416198D03*
X768910Y1437741D03*
X777033Y1595215D03*
X781545Y1602835D03*
X774658Y1601012D03*
X778045Y1622545D03*
X782289Y1620109D03*
X773822Y1627418D03*
X772000Y1644980D03*
X791129Y4469D03*
X792490Y24773D03*
Y44773D03*
X799811Y53597D03*
X784410Y109172D03*
X787410D03*
X786417Y106495D03*
X799861Y114655D03*
Y111255D03*
X792561Y132515D03*
Y118342D03*
X799861Y128828D03*
X792561Y121742D03*
X799861Y125428D03*
X788057Y141228D03*
X786151Y146012D03*
X792561Y135915D03*
X790945Y150847D03*
X798693Y213539D03*
X792913Y247292D03*
X792139Y238689D03*
X785703Y236121D03*
X785622Y253198D03*
X788522Y290304D03*
X789581Y405011D03*
X793893Y409502D03*
X784586Y421000D03*
Y418500D03*
X785985Y473640D03*
X790977D03*
X785985Y487813D03*
X790977D03*
X785985Y478596D03*
X790977D03*
X785985Y492769D03*
X790977D03*
Y517774D03*
Y522730D03*
X785985Y517774D03*
Y522730D03*
Y531947D03*
Y536903D03*
X790977Y531947D03*
Y536903D03*
X796000Y553101D03*
X784665Y564843D03*
X790977Y567813D03*
X785985Y572769D03*
X790977D03*
X785985Y567813D03*
X790977Y581987D03*
Y586943D03*
X785985Y581987D03*
Y586943D03*
X790977Y601116D03*
X785985D03*
Y596160D03*
X790977D03*
Y615289D03*
Y610333D03*
X785985Y615289D03*
Y610333D03*
X794983Y1334030D03*
Y1331230D03*
X790754Y1441399D03*
X793994Y1441499D03*
X797083Y1467883D03*
X794005Y1464178D03*
X799314Y1475693D03*
X797318Y1471242D03*
X787447Y1593586D03*
X791610Y1593708D03*
X793564Y1642682D03*
X810623Y77784D03*
Y82984D03*
Y80384D03*
Y75184D03*
X813177Y92849D03*
X810623Y85584D03*
X810161Y102323D03*
X810413Y109410D03*
X802161Y102323D03*
X813902Y730738D03*
X813678Y740979D03*
X813653Y746856D03*
X817584Y764219D03*
X817845Y817879D03*
X818500Y810135D03*
X810148Y1374884D03*
X806874Y1447457D03*
X812474D03*
X806874Y1452587D03*
Y1457717D03*
X812474D03*
X815096Y1464387D03*
X812009Y1473432D03*
Y1470432D03*
X815096Y1467387D03*
X812096Y1479587D03*
Y1476587D03*
X815096Y1473387D03*
Y1479587D03*
Y1476587D03*
Y1470387D03*
X804919Y1489247D03*
X811457Y1639797D03*
X819811Y53597D03*
X820137Y103037D03*
X820271Y116496D03*
Y109410D03*
X828271Y116496D03*
Y109410D03*
Y102323D03*
X820271Y123583D03*
X828271Y130670D03*
Y123583D03*
Y137756D03*
X829362Y231461D03*
Y228961D03*
Y226461D03*
Y223661D03*
X824952Y293796D03*
X822452D03*
X830466Y285690D03*
Y288190D03*
X825792Y305225D03*
X825971Y345101D03*
X834282Y536085D03*
X828272Y535462D03*
X827291Y533100D03*
X829496Y676793D03*
X827500Y750000D03*
X824500Y756000D03*
Y774000D03*
Y782500D03*
X824342Y792315D03*
X824500Y800500D03*
X817139Y890330D03*
X818031Y907747D03*
X818347Y939610D03*
X828193Y949324D03*
X828423Y964731D03*
X832432Y977982D03*
X832711Y993268D03*
X816648Y1380758D03*
X817974Y1447457D03*
Y1452587D03*
Y1457717D03*
X818096Y1464387D03*
X821096D03*
X818096Y1473387D03*
X821096D03*
X824096D03*
X818096Y1479587D03*
X821096D03*
X824096D03*
X818096Y1476587D03*
X821096D03*
X824096D03*
X818096Y1467387D03*
Y1470387D03*
X821096D03*
Y1467387D03*
X824096D03*
Y1470387D03*
X831457Y1639797D03*
X838606Y5374D03*
X837919Y24773D03*
Y44773D03*
X841554Y94017D03*
X837554D03*
X845563D03*
X833554D03*
X837283Y101701D03*
X837682Y110445D03*
Y115401D03*
X848084Y117557D03*
X842674Y115401D03*
Y110445D03*
X844833Y103783D03*
X842674Y129574D03*
Y124618D03*
X837682D03*
Y129574D03*
X848084Y131731D03*
Y122513D03*
Y136687D03*
X839112Y188727D03*
X839245Y191941D03*
X845745Y184619D03*
X847725Y206760D03*
X837331Y229286D03*
X841024Y224712D03*
Y222212D03*
X833069Y226141D03*
X835869D03*
X835812Y236611D03*
X838312D03*
X833312D03*
X837331Y231786D03*
X833014Y248891D03*
X848939Y256535D03*
X840939D03*
X838014Y248891D03*
X835514D03*
X832966Y288190D03*
Y285690D03*
X835766Y288190D03*
Y285690D03*
X843992Y290755D03*
X839992D03*
X847992D03*
X839573Y325327D03*
X842240Y324854D03*
X848879Y360849D03*
X845435Y356172D03*
X833953Y530621D03*
X848444Y657756D03*
X837272Y663910D03*
X839636Y666533D03*
X842352Y659243D03*
X842640Y662814D03*
X836839Y831301D03*
X836894Y824401D03*
X848224Y823502D03*
X848384Y843459D03*
X846239Y847490D03*
X848384Y835459D03*
X847138Y859459D03*
X848384Y863459D03*
X846336Y855459D03*
X848384Y851459D03*
Y867459D03*
Y879459D03*
X848322Y888421D03*
X837276Y883459D03*
X848200Y883400D03*
X839122Y939655D03*
X836704Y1440849D03*
X845306Y1438269D03*
X835474Y1457397D03*
X850145Y3000D03*
X850631Y84140D03*
Y80140D03*
Y76140D03*
X864006Y117261D03*
X853076Y117557D03*
X856000Y103621D03*
X853076Y131731D03*
Y122513D03*
Y136687D03*
X851777Y180572D03*
X856460Y180527D03*
X860183Y192421D03*
X851777Y185165D03*
X856415Y185121D03*
X849969Y279208D03*
X854073Y281307D03*
X858563Y293645D03*
Y290845D03*
X856063Y293645D03*
Y290845D03*
X858563Y288345D03*
X856063D03*
X864920Y343168D03*
X852569Y356712D03*
X856069Y356426D03*
X858586Y385000D03*
X857973Y404867D03*
X862522Y400229D03*
X862566Y404867D03*
X862020Y410899D03*
X862882Y468791D03*
Y465991D03*
X854882D03*
Y468791D03*
X850733Y461382D03*
X850832Y473382D03*
X861468Y491303D03*
X850738Y477382D03*
X850909Y482382D03*
X853989Y630453D03*
Y632953D03*
X861663Y646653D03*
X855300Y646819D03*
X853982Y657506D03*
X864029Y688970D03*
X849500Y758500D03*
Y763500D03*
Y776500D03*
Y781500D03*
Y794500D03*
Y799500D03*
Y812500D03*
Y817500D03*
X851184Y835459D03*
X859165Y848728D03*
X851239Y847459D03*
X851184Y843459D03*
Y851459D03*
Y871459D03*
Y875459D03*
X849267Y892567D03*
X850900Y888359D03*
X858988Y898307D03*
X855867Y935540D03*
X849088Y951081D03*
X861047Y1018909D03*
X860887Y1023208D03*
Y1026762D03*
X863956Y1020763D03*
X863689Y1024974D03*
X859071Y1447459D03*
X864671D03*
X850544Y1447559D03*
X859071Y1452589D03*
Y1457719D03*
X864671D03*
X864644Y1464759D03*
X861644D03*
X855644D03*
X858644D03*
Y1467759D03*
X855644Y1470759D03*
X858644D03*
X864644Y1467759D03*
Y1470759D03*
X861644Y1467759D03*
Y1470759D03*
X855644Y1467759D03*
Y1473759D03*
X858644D03*
X864644D03*
X861644D03*
X855644Y1476759D03*
X858644D03*
X864644D03*
X861644D03*
X851457Y1639797D03*
X873373Y60922D03*
X868209Y55513D03*
X870395Y96738D03*
X865402Y91951D03*
X871713Y172665D03*
Y180665D03*
X871745Y200864D03*
Y212864D03*
Y216864D03*
Y221864D03*
X883118Y262687D03*
X876246Y302754D03*
X873885Y340892D03*
X872158Y359962D03*
X871382Y373971D03*
X872736Y383125D03*
X872318Y408589D03*
X866128Y417532D03*
X869342Y417399D03*
X880910Y471982D03*
Y469182D03*
Y466382D03*
X870882Y465991D03*
Y468791D03*
X875907Y486256D03*
X874649Y545296D03*
X879135Y632552D03*
X874142Y748914D03*
X870035Y801032D03*
X879916Y808965D03*
X880628Y918042D03*
X876481Y941126D03*
X868908Y933640D03*
X867199Y949372D03*
X869390Y978003D03*
X871069Y1023114D03*
X878927Y1022387D03*
X878783Y1018751D03*
X872845Y1018988D03*
X866906Y1018751D03*
X866887Y1023208D03*
X875887D03*
X878887Y1026762D03*
X872887D03*
X866887D03*
X869741Y1025895D03*
X871624Y1213314D03*
X874624D03*
X871624Y1221714D03*
Y1218914D03*
Y1216114D03*
X874624Y1221714D03*
Y1218914D03*
Y1216114D03*
X872440Y1230083D03*
Y1227583D03*
X871624Y1224514D03*
X874624D03*
X872440Y1234483D03*
Y1236983D03*
X878004Y1224406D03*
X872440Y1243883D03*
Y1241383D03*
Y1248283D03*
Y1250783D03*
X883142Y1259935D03*
X870171Y1447459D03*
Y1452589D03*
Y1457719D03*
X867644Y1464759D03*
X870644D03*
X867644Y1467759D03*
X870644D03*
X867644Y1470759D03*
X870644D03*
X867644Y1473759D03*
X870644D03*
X867644Y1476759D03*
X870644D03*
X871457Y1639797D03*
X886011Y154100D03*
X895780Y237517D03*
Y232634D03*
X895064Y250186D03*
X885884Y255118D03*
X887148Y249670D03*
X886496Y268968D03*
X896592Y362369D03*
Y366369D03*
Y370369D03*
X884736Y383125D03*
X893736D03*
X888736D03*
X894844Y418983D03*
X889219Y426952D03*
X887770Y415290D03*
X891699Y420445D03*
X890270Y415290D03*
X891699Y423245D03*
X897344Y418983D03*
X894519Y426952D03*
X889596Y437264D03*
X896388Y437614D03*
X887096Y437264D03*
X892019Y426952D03*
X897019D03*
X890903Y469182D03*
Y471982D03*
Y466382D03*
X882907Y480350D03*
X896431Y534093D03*
X896449Y550863D03*
X893949Y550363D03*
X892023Y570176D03*
X882949Y557363D03*
X890959Y579788D03*
X890956Y588325D03*
X894015Y588253D03*
X895933Y618143D03*
X887949Y608863D03*
X894449Y606363D03*
X893241Y704656D03*
X889525Y722060D03*
X887916Y808965D03*
X883916Y800815D03*
X895050Y828548D03*
X884628Y918042D03*
X896553D03*
X892628Y915242D03*
X888628D03*
X882609Y994245D03*
X888400Y994579D03*
X894660Y994330D03*
X885099Y1021685D03*
X881887Y1023208D03*
X888743Y1019931D03*
X895394Y1026985D03*
X893147Y1020025D03*
X893887Y1023208D03*
X887887D03*
X890887Y1026762D03*
X884887D03*
X888650Y1199622D03*
X893190Y1208069D03*
X893328Y1212887D03*
X894887Y1227209D03*
X892244Y1449636D03*
Y1440859D03*
X891457Y1639797D03*
X898813Y146461D03*
X897715Y152367D03*
X899573Y158195D03*
X898851Y231496D03*
Y238583D03*
Y245669D03*
X910977Y238583D03*
X898851Y259843D03*
X898576Y253056D03*
X910977Y252756D03*
Y257480D03*
X898851Y274016D03*
X910977Y266929D03*
X898851D03*
X912278Y343881D03*
X913206Y336489D03*
X898533Y334498D03*
X910040Y353532D03*
X902169Y413002D03*
Y418002D03*
Y415502D03*
X905094Y424581D03*
X902594D03*
X907594D03*
X905212Y436734D03*
X902712D03*
X907712D03*
X907173Y440581D03*
X898888Y437614D03*
X907173Y443081D03*
X910779Y471380D03*
X903431Y534093D03*
X906996Y530707D03*
X902459Y530755D03*
X911630Y543998D03*
X910578Y550186D03*
X909362Y555614D03*
X898156Y554812D03*
X913853Y561487D03*
X904393Y570176D03*
X908517D03*
X898815D03*
X909024Y578394D03*
X898232Y588320D03*
X909024Y586768D03*
X902635Y588305D03*
X906999Y588274D03*
X909024Y574394D03*
X908730Y619120D03*
X913686D03*
X899898Y619040D03*
X904854D03*
X902841Y703665D03*
X913858Y721289D03*
X912628Y915242D03*
X908628Y918042D03*
X900628Y915242D03*
X912628Y918042D03*
X904838D03*
X908628Y915242D03*
X911355Y944909D03*
X906710Y962433D03*
X906909Y951494D03*
X897825Y994413D03*
X897717Y1019915D03*
X899887Y1023208D03*
Y1026762D03*
X901940Y1236799D03*
Y1229899D03*
Y1232399D03*
Y1246199D03*
Y1243699D03*
Y1239299D03*
X912171Y1447459D03*
X906671D03*
X901071D03*
X912171Y1457719D03*
Y1452589D03*
X906671Y1457719D03*
X901071D03*
Y1452589D03*
X908370Y1464583D03*
X905370D03*
X899370D03*
X902370D03*
X911370D03*
X905370Y1476583D03*
X908370D03*
X902370D03*
X899370D03*
X905370Y1473583D03*
X908370D03*
X902370D03*
X899370D03*
X902370Y1467583D03*
X899370Y1470583D03*
X902370D03*
X908370Y1467583D03*
Y1470583D03*
X905370Y1467583D03*
Y1470583D03*
X899370Y1467583D03*
X911370Y1476583D03*
Y1473583D03*
Y1467583D03*
Y1470583D03*
X911457Y1639797D03*
X930145Y3000D03*
X931393Y102249D03*
X919175Y113394D03*
X921824Y110784D03*
X923393Y102249D03*
X927393D03*
X921418Y133298D03*
X929418D03*
X923565Y134579D03*
X925359Y180347D03*
X927859D03*
X916453Y167975D03*
X925219Y188564D03*
X929978Y186854D03*
X927719Y188564D03*
X929978Y184054D03*
X919606Y231000D03*
X919577Y245669D03*
Y233858D03*
X919682Y236921D03*
X919577Y259843D03*
Y255118D03*
X919729Y274580D03*
X920142Y308501D03*
X926801Y323302D03*
X922629Y336609D03*
X922198Y342051D03*
X917858Y331453D03*
X923902Y332411D03*
X927309Y357267D03*
X921389D03*
X915395D03*
X921847Y346622D03*
X915395Y363212D03*
X927309Y363239D03*
Y369210D03*
X921468D03*
X915395D03*
X914202Y418002D03*
Y413002D03*
Y415502D03*
X927636Y452505D03*
X929050Y450316D03*
X924600Y533706D03*
X920961Y550075D03*
X915949Y563363D03*
X915712Y613792D03*
X922626Y633772D03*
X915194Y666671D03*
X929690Y666593D03*
X920090Y666714D03*
X928043Y677795D03*
X928353Y686342D03*
X928704Y680261D03*
X926961Y723797D03*
X927916Y817015D03*
X920628Y918042D03*
X916628D03*
X924628D03*
X928628D03*
X924628Y915242D03*
X920628D03*
X928628D03*
X916628D03*
X918648Y964717D03*
X915490Y969886D03*
X916932Y994405D03*
X924956Y994321D03*
X924864Y1026762D03*
Y1023208D03*
X925024Y1018909D03*
X927861Y1024768D03*
X917110Y1101902D03*
X927598Y1120636D03*
X924898D03*
X924919Y1130336D03*
X927619D03*
X924919Y1139336D03*
X927419D03*
X925097Y1147708D03*
X927597D03*
X930754Y1310564D03*
X914370Y1464583D03*
Y1476583D03*
Y1473583D03*
Y1467583D03*
Y1470583D03*
X926044Y1545370D03*
Y1542370D03*
X929094Y1542353D03*
Y1545353D03*
X926041Y1554503D03*
Y1551503D03*
Y1548503D03*
Y1557503D03*
Y1560503D03*
X941129Y4469D03*
X942490Y24773D03*
Y44773D03*
X934410Y109172D03*
X936417Y106495D03*
X937410Y109172D03*
X942561Y118342D03*
Y132515D03*
Y121742D03*
X936151Y146012D03*
X938057Y141228D03*
X942561Y135915D03*
X940945Y150847D03*
X930359Y180347D03*
X933159D03*
X931407Y192009D03*
X933907D03*
X938125Y230891D03*
X942805Y223860D03*
X936369Y221292D03*
X940158Y245707D03*
X946064Y252998D03*
X941845Y278968D03*
X939606Y310521D03*
X939653Y317474D03*
X940924Y328959D03*
X936608Y326058D03*
X945120Y326441D03*
X932388Y330517D03*
X930398Y342050D03*
X936453Y345336D03*
X945599Y345383D03*
X940972Y338238D03*
X932622Y336817D03*
X943663Y355674D03*
X944694Y352192D03*
X944900Y363700D03*
X938499Y362202D03*
X940600Y370600D03*
X941505Y463442D03*
X939827Y531104D03*
X939992Y536726D03*
Y527726D03*
Y540726D03*
Y544726D03*
X931627Y561578D03*
Y565578D03*
X943825Y581222D03*
X931620Y584417D03*
X943825Y591215D03*
X931594Y599420D03*
X931647Y593271D03*
X931578Y590669D03*
X943181Y632536D03*
X945434Y634325D03*
X941859Y625311D03*
X946128Y666522D03*
X935281Y677795D03*
X945626Y789761D03*
X946970Y786366D03*
X941916Y808965D03*
X936628Y915242D03*
X940628D03*
X932628D03*
X936628Y918042D03*
X932628D03*
X940015Y1020176D03*
X934911Y1023579D03*
X945864Y1023208D03*
X930864Y1026762D03*
X936864D03*
X942864D03*
X939864Y1023208D03*
X930864D03*
X930883Y1018751D03*
X936822Y1018988D03*
X942760Y1018751D03*
X943093Y1021769D03*
X935601Y1221714D03*
Y1218914D03*
Y1216114D03*
Y1213314D03*
X938601Y1221714D03*
Y1218914D03*
Y1216114D03*
Y1213314D03*
X936417Y1234483D03*
Y1236983D03*
Y1230083D03*
Y1227583D03*
X935601Y1224514D03*
X938601D03*
X941981Y1224406D03*
X936417Y1243883D03*
Y1241383D03*
Y1248283D03*
Y1250783D03*
X947119Y1259935D03*
X939559Y1398427D03*
X931159Y1394627D03*
Y1402227D03*
X939559D03*
X943725Y1430744D03*
Y1427744D03*
X934725Y1430744D03*
X940725Y1427744D03*
Y1430744D03*
X934725Y1427744D03*
X937725D03*
Y1430744D03*
X943725Y1433744D03*
Y1439744D03*
Y1436744D03*
X940725Y1433744D03*
Y1439744D03*
Y1436744D03*
X934725Y1433744D03*
X937725D03*
X934725Y1439744D03*
X937725D03*
X934725Y1436744D03*
X937725D03*
X930441Y1455039D03*
Y1458039D03*
Y1464039D03*
Y1461039D03*
Y1467039D03*
X938670Y1510528D03*
X941270D03*
Y1505328D03*
X938670D03*
X940170Y1507928D03*
X943870Y1510528D03*
Y1505328D03*
X945370Y1507928D03*
X942770D03*
X935094Y1542353D03*
X932094D03*
X935094Y1545353D03*
X932094D03*
X938094Y1542353D03*
Y1545353D03*
X941094Y1542353D03*
X944094D03*
X941094Y1545353D03*
X944094D03*
X931457Y1639797D03*
X949811Y53597D03*
X960623Y82984D03*
Y77784D03*
Y80384D03*
Y75184D03*
Y85584D03*
X960161Y102323D03*
X960413Y109410D03*
X952161Y102323D03*
X949861Y111255D03*
Y114655D03*
Y125428D03*
Y128828D03*
X952170Y356131D03*
X954888Y369513D03*
X948400Y370045D03*
X960376Y392807D03*
X949823Y487982D03*
X949876Y478486D03*
X949823Y483982D03*
Y499982D03*
X953816Y555194D03*
X951016D03*
X953816Y571194D03*
X951016D03*
X953816Y563194D03*
X951016D03*
X946625Y581222D03*
X949425D03*
Y591215D03*
X946625D03*
X948427Y611091D03*
X956365Y641817D03*
X950865D03*
X949137Y666660D03*
X954526Y666671D03*
X957551Y698251D03*
X951151Y730111D03*
X957579Y744168D03*
X950699Y779711D03*
X957487Y798553D03*
X955343Y866850D03*
X953240Y876834D03*
X947029Y915242D03*
X957671Y991564D03*
X946642Y991361D03*
X954937Y1021998D03*
X948864Y1026762D03*
X954864D03*
X951864Y1023208D03*
X957864D03*
X957678Y1018555D03*
X961208Y1018592D03*
X960636Y1021917D03*
X959371Y1026985D03*
X948975Y1021325D03*
X961033Y1091391D03*
X948883Y1102760D03*
X948867Y1098724D03*
X955032Y1095407D03*
X961033Y1095984D03*
X952627Y1199622D03*
X957305Y1212887D03*
X957167Y1208069D03*
X958864Y1227209D03*
X948259Y1295965D03*
X952561Y1383465D03*
X952716Y1387402D03*
X946725Y1427744D03*
Y1430744D03*
X949725D03*
Y1427744D03*
X960883Y1427997D03*
Y1430997D03*
X946725Y1433744D03*
X949725D03*
X946725Y1439744D03*
X949725D03*
X946725Y1436744D03*
X949725D03*
X960883Y1433997D03*
Y1436997D03*
Y1439997D03*
X956238Y1455139D03*
Y1458139D03*
Y1461139D03*
Y1464139D03*
X952676Y1461039D03*
Y1464039D03*
Y1458039D03*
Y1455039D03*
X956238Y1467139D03*
Y1469902D03*
X952676Y1467039D03*
X946470Y1510528D03*
Y1505328D03*
X956035Y1545333D03*
X959035D03*
X953035D03*
X950035D03*
X959035Y1542333D03*
X956035D03*
X953035D03*
X950035D03*
X947094Y1545353D03*
Y1542353D03*
X951457Y1639797D03*
X969811Y53597D03*
X963177Y92849D03*
X978271Y109410D03*
Y102323D03*
X970137Y103037D03*
X970271Y116496D03*
Y109410D03*
X978271Y116496D03*
X970271Y123583D03*
X978271Y130670D03*
Y123583D03*
Y137756D03*
X979362Y223661D03*
X974952Y293796D03*
X972452D03*
X976763Y307303D03*
X972147Y323681D03*
X973338Y345018D03*
X977150Y331972D03*
Y338972D03*
X969623Y405614D03*
X963577Y426391D03*
X975932Y437508D03*
X971932D03*
X962769Y458466D03*
X973695Y448874D03*
X969109Y449352D03*
X967816Y472905D03*
X972397Y472954D03*
X973843Y500086D03*
X978723Y504699D03*
X976223D03*
X973723D03*
X978425Y516979D03*
X973425D03*
X974406Y521804D03*
X975925Y516979D03*
X978668Y527449D03*
X974406Y524304D03*
X970713Y531378D03*
Y528878D03*
X975868Y527449D03*
X964012Y546830D03*
X978581Y572975D03*
X976962Y608311D03*
X980683Y628242D03*
X967302Y627948D03*
X969491Y629362D03*
X978865Y642184D03*
X963187Y667620D03*
X973138Y667621D03*
X968589Y722434D03*
X970839Y729923D03*
X965042Y722234D03*
X971081Y722637D03*
X978352Y730766D03*
X965983Y763567D03*
X968094Y799792D03*
X976186Y789819D03*
X967562Y802982D03*
X967337Y828901D03*
X974437Y849140D03*
X970299Y853773D03*
X969806Y993033D03*
X965671Y991564D03*
X963864Y1026762D03*
Y1023208D03*
X965716Y1091346D03*
X965671Y1095940D03*
X967148Y1123803D03*
X969748D03*
X969648Y1114103D03*
X967048D03*
X972348Y1123803D03*
X975048D03*
X972248Y1114103D03*
X974948D03*
X965405Y1136426D03*
X970485Y1132870D03*
X967885D03*
X968874Y1145169D03*
X966374D03*
X965917Y1236799D03*
Y1229899D03*
Y1232399D03*
Y1246199D03*
Y1243699D03*
Y1239299D03*
X974985Y1290950D03*
X963883Y1430997D03*
Y1427997D03*
X966883Y1430997D03*
Y1427997D03*
X969883D03*
Y1430997D03*
X975883Y1427997D03*
Y1430997D03*
X972883D03*
Y1427997D03*
X963883Y1433997D03*
X966883D03*
X969883D03*
X963883Y1436997D03*
Y1439997D03*
X966883Y1436997D03*
Y1439997D03*
X969883Y1436997D03*
Y1439997D03*
X975883Y1433997D03*
X972883D03*
X975883Y1436997D03*
X972883D03*
X975883Y1439997D03*
X972883D03*
X971467Y1509515D03*
X974067D03*
X972567Y1512115D03*
X969967D03*
X976667Y1509515D03*
X977767Y1506915D03*
X975167D03*
X969967D03*
X972567D03*
X975167Y1512115D03*
X977767D03*
X971140Y1514693D03*
X968540D03*
X973740D03*
X976340D03*
X977547Y1546081D03*
X974547D03*
X971547D03*
X971457Y1639797D03*
X988606Y5374D03*
X987919Y24773D03*
Y44773D03*
X983554Y94017D03*
X987554D03*
X991554D03*
X987283Y101701D03*
X987682Y115401D03*
X992674D03*
Y110445D03*
X987682D03*
X994833Y103783D03*
X992674Y124618D03*
X987682D03*
Y129574D03*
X992674D03*
X985595Y151540D03*
X989245Y191941D03*
X989112Y188727D03*
X987331Y229286D03*
X991024Y224712D03*
Y222212D03*
X983069Y226141D03*
X985869D03*
X979362Y231461D03*
Y228961D03*
Y226461D03*
X987331Y231786D03*
X985812Y236611D03*
X988312D03*
X983312D03*
X983014Y248891D03*
X988014D03*
X985514D03*
X990939Y256535D03*
X985766Y288190D03*
X982966D03*
X985766Y285690D03*
X982966D03*
X980466Y288190D03*
Y285690D03*
X987055Y320273D03*
X990420Y340454D03*
Y337954D03*
X980045Y366559D03*
X982670Y450201D03*
X980397Y473045D03*
X985699Y480705D03*
X980544Y482134D03*
Y484634D03*
X988499Y480705D03*
X983989Y475946D03*
Y478446D03*
X982375Y522129D03*
X989936Y519531D03*
X987436D03*
X982436D03*
X984936D03*
X982375Y527129D03*
Y524629D03*
Y529929D03*
X989068Y532949D03*
X986268D03*
X981795Y572842D03*
X985903Y579475D03*
X985357Y585507D03*
X989950D03*
X985401Y590145D03*
X989995Y590190D03*
X989857Y605443D03*
X981857Y605637D03*
X983843Y633205D03*
Y636005D03*
Y638805D03*
X983712Y722064D03*
X988371Y764143D03*
X983786Y765647D03*
X985921Y805135D03*
X994094Y829000D03*
X982300Y821200D03*
X981087Y1101902D03*
X995009Y1131223D03*
X991763Y1140378D03*
Y1128378D03*
Y1134378D03*
X984558Y1140774D03*
X988112Y1137774D03*
X984558Y1128774D03*
Y1134774D03*
X987804Y1131619D03*
X984817Y1303297D03*
X979001Y1288925D03*
X990613Y1324248D03*
Y1327048D03*
X993413Y1324248D03*
Y1327048D03*
X984136Y1401636D03*
X987136D03*
X986949Y1430997D03*
Y1427997D03*
X983949D03*
X989949Y1430997D03*
Y1427997D03*
X983949Y1430997D03*
X992949Y1427997D03*
Y1430997D03*
X986949Y1433997D03*
X983949D03*
X989949D03*
X992949D03*
X986949Y1436997D03*
X983949D03*
X986949Y1439997D03*
X983949D03*
X989949Y1436997D03*
Y1439997D03*
X992949Y1436997D03*
Y1439997D03*
X979538Y1464039D03*
Y1461039D03*
Y1458039D03*
Y1455039D03*
Y1467039D03*
Y1469802D03*
X978987Y1489832D03*
X982241Y1489637D03*
X979267Y1509515D03*
X984467D03*
X981867D03*
X985567Y1512115D03*
Y1506915D03*
X980367D03*
X982967D03*
Y1512115D03*
X980367D03*
X989667Y1509515D03*
X992267D03*
X987067D03*
X988167Y1512115D03*
X990767D03*
Y1506915D03*
X988167D03*
X984140Y1514693D03*
X981540D03*
X978940D03*
X986740D03*
X989340D03*
X986773Y1546081D03*
X983773D03*
X980773D03*
X991457Y1639797D03*
X1007508Y3000D03*
X1000631Y84140D03*
Y76140D03*
Y80140D03*
X995563Y94017D03*
X1006000Y103621D03*
X1003076Y117557D03*
X998084D03*
X1003076Y122513D03*
Y131731D03*
X998084Y122513D03*
Y131731D03*
X1001175Y146461D03*
X1003076Y136687D03*
X998084D03*
X1000077Y152367D03*
X1001777Y180572D03*
X1006460Y180527D03*
X1010183Y192421D03*
X1001777Y185165D03*
X1006415Y185121D03*
X995745Y184619D03*
X997725Y206760D03*
X998939Y256535D03*
X999826Y278734D03*
X1004061Y280808D03*
X1000698Y300276D03*
X997857Y605443D03*
X995913Y633450D03*
Y636250D03*
Y639050D03*
X1008342Y761735D03*
X1013151Y756726D03*
X1001187Y850084D03*
X1004577Y853679D03*
X1010119Y933822D03*
X1006619D03*
X1006222Y980337D03*
X1010009Y998100D03*
X1005301Y1006560D03*
X995317Y1137378D03*
X996213Y1324248D03*
Y1327048D03*
X1008387Y1380797D03*
X1009338Y1391597D03*
Y1388597D03*
X1008138Y1407186D03*
Y1409986D03*
X1005338Y1407186D03*
Y1409986D03*
X1008138Y1415586D03*
Y1412786D03*
X1005338Y1415586D03*
Y1412786D03*
X1008138Y1418386D03*
X1005338D03*
X998949Y1427997D03*
Y1430997D03*
X995949D03*
Y1427997D03*
X1009981Y1431097D03*
Y1428097D03*
X1006981D03*
Y1431097D03*
X998949Y1433997D03*
X995949D03*
X998949Y1436997D03*
X995949D03*
X998949Y1439997D03*
X995949D03*
X1009981Y1434097D03*
X1006981D03*
X1009981Y1437097D03*
X1006981D03*
X1009981Y1440097D03*
X1006981D03*
X1002538Y1463939D03*
Y1460939D03*
Y1457939D03*
Y1454939D03*
Y1466939D03*
Y1469702D03*
X1008549Y1509815D03*
X1007049Y1507215D03*
X1011149Y1509815D03*
X1009649Y1507215D03*
Y1512415D03*
X1007049D03*
X1008222Y1514993D03*
X1005622D03*
X1010822D03*
X1010606Y1547824D03*
X1007611Y1561247D03*
Y1558247D03*
Y1555247D03*
Y1552247D03*
X1004611Y1561247D03*
Y1558247D03*
Y1555247D03*
Y1552247D03*
X1010659Y1568771D03*
Y1565771D03*
X1010653Y1571669D03*
X1027508Y3000D03*
X1023373Y60922D03*
X1018209Y55513D03*
X1020254Y97068D03*
X1015402Y91951D03*
X1014006Y117261D03*
X1021537Y113394D03*
X1025755Y102249D03*
X1024186Y110784D03*
X1024289Y130898D03*
X1025927Y134579D03*
X1021713Y180665D03*
Y172665D03*
X1027055Y195176D03*
X1026915Y203393D03*
X1021745Y212864D03*
Y200864D03*
Y221864D03*
Y216864D03*
X1023502Y252371D03*
X1016635Y300276D03*
X1012635D03*
X1025749D03*
X1020635D03*
X1015195Y428305D03*
X1018238Y678647D03*
X1018155Y684132D03*
X1025116Y698332D03*
X1021885Y698974D03*
X1024932Y717856D03*
X1015804Y760454D03*
X1026090Y770943D03*
X1021895Y771974D03*
X1026340Y917761D03*
X1027319Y938322D03*
X1017998Y1009655D03*
X1015198D03*
X1025143Y1030672D03*
X1023144Y1109564D03*
X1017297D03*
X1023144Y1122164D03*
X1017297D03*
X1023144Y1134764D03*
X1017297D03*
X1023144Y1147364D03*
X1017297D03*
X1023144Y1159964D03*
X1017297D03*
Y1172564D03*
X1023162Y1174445D03*
X1023358Y1363921D03*
X1013991Y1360842D03*
X1012338Y1388597D03*
Y1391597D03*
X1015338D03*
Y1388597D03*
X1021338D03*
Y1391597D03*
X1018338D03*
Y1388597D03*
X1027338D03*
Y1391597D03*
X1024338D03*
Y1388597D03*
X1012981Y1431097D03*
Y1428097D03*
X1015981D03*
Y1431097D03*
X1021981Y1428097D03*
Y1431097D03*
X1018981D03*
Y1428097D03*
X1012981Y1434097D03*
X1015981D03*
X1012981Y1437097D03*
Y1440097D03*
X1015981Y1437097D03*
Y1440097D03*
X1021981Y1434097D03*
X1018981D03*
X1021981Y1437097D03*
X1018981D03*
X1021981Y1440097D03*
X1018981D03*
X1025138Y1463839D03*
Y1460839D03*
Y1457839D03*
Y1454839D03*
Y1466839D03*
Y1469602D03*
X1013749Y1509815D03*
X1016349D03*
X1021549D03*
X1018949D03*
X1024149D03*
X1022649Y1507215D03*
X1025249D03*
X1017449D03*
X1020049D03*
X1014849D03*
X1012249D03*
X1026749Y1509815D03*
X1012249Y1512415D03*
X1014849D03*
X1025249D03*
X1022649D03*
X1020049D03*
X1017449D03*
X1013422Y1514993D03*
X1023822D03*
X1021222D03*
X1018622D03*
X1016022D03*
X1026422D03*
X1013606Y1547824D03*
X1016606D03*
X1019606D03*
X1013659Y1568771D03*
X1016659D03*
X1019659D03*
X1013659Y1565771D03*
X1016659D03*
X1019659D03*
X1013653Y1571669D03*
X1016653D03*
X1019653D03*
X1011457Y1639797D03*
X1043492Y4469D03*
X1033755Y102249D03*
X1036772Y109172D03*
X1039772D03*
X1038779Y106495D03*
X1029755Y102249D03*
X1031780Y133298D03*
X1038513Y146012D03*
X1040419Y141228D03*
X1043307Y150847D03*
X1032055Y195176D03*
X1031674Y198883D03*
X1029555Y195176D03*
X1034855D03*
X1033103Y206838D03*
X1035603D03*
X1029415Y203393D03*
X1031674Y201683D03*
X1038065Y236121D03*
X1035099Y238589D03*
X1037984Y253198D03*
X1045650Y300093D03*
X1029639Y300141D03*
X1030753Y732213D03*
X1038796Y763272D03*
X1043016Y782161D03*
X1043425Y830800D03*
X1043626Y836563D03*
X1041100Y838500D03*
X1037527Y836486D03*
X1031813Y850273D03*
X1046045Y841217D03*
X1040822Y841339D03*
X1044390Y861210D03*
X1038363Y875288D03*
X1043252Y902501D03*
X1033019Y933022D03*
Y935822D03*
X1030819Y938422D03*
X1042009Y997860D03*
X1028943Y1016827D03*
X1034790D03*
X1028943Y1029427D03*
X1034790D03*
X1039053Y1105091D03*
X1044553D03*
X1030338Y1391597D03*
Y1388597D03*
X1032867Y1431213D03*
Y1428213D03*
X1029867D03*
X1035867Y1431213D03*
Y1428213D03*
X1029867Y1431213D03*
X1038867Y1428213D03*
Y1431213D03*
X1041867D03*
Y1428213D03*
X1032867Y1434213D03*
X1029867D03*
X1035867D03*
X1038867D03*
X1032867Y1437213D03*
X1029867D03*
X1032867Y1440213D03*
X1029867D03*
X1035867Y1437213D03*
Y1440213D03*
X1038867Y1437213D03*
Y1440213D03*
X1041867Y1434213D03*
Y1437213D03*
Y1440213D03*
X1029349Y1509815D03*
X1027849Y1507215D03*
Y1512415D03*
X1031457Y1639797D03*
X1044853Y24773D03*
Y44773D03*
X1052174Y53597D03*
X1054523Y102323D03*
X1052223Y111255D03*
Y114655D03*
X1044923Y118342D03*
X1052223Y125428D03*
Y128828D03*
X1044923Y132515D03*
Y121742D03*
Y135915D03*
X1051055Y213539D03*
X1044501Y238689D03*
X1045275Y247292D03*
X1048695Y280161D03*
X1050164Y302748D03*
X1050076Y305512D03*
X1060679Y356151D03*
X1052367Y402291D03*
X1057359D03*
X1052367Y397335D03*
X1057359D03*
X1054959Y411509D03*
X1049967Y416465D03*
Y411509D03*
X1054959Y425682D03*
X1049967D03*
X1054959Y416465D03*
X1049967Y439855D03*
X1054959Y430638D03*
X1049967D03*
X1054959Y439855D03*
X1049967Y444811D03*
X1050777Y450750D03*
X1054959Y444811D03*
X1049967Y468609D03*
X1054959D03*
X1049967Y473565D03*
X1054959D03*
X1049967Y487738D03*
X1054959D03*
X1049967Y482782D03*
X1054959D03*
Y517699D03*
X1049967Y512743D03*
X1054959D03*
X1049967Y517699D03*
Y526916D03*
X1054959Y531872D03*
X1049967D03*
X1054959Y526916D03*
X1054876Y536382D03*
X1059843Y597580D03*
X1059782Y594668D03*
X1062098Y615600D03*
X1048314Y833102D03*
X1053392Y832788D03*
X1051550Y823146D03*
X1050358Y837793D03*
X1052500Y841200D03*
X1049087Y856033D03*
X1053909Y855472D03*
X1045300Y872352D03*
X1057961Y931919D03*
X1046009Y997860D03*
X1054009D03*
X1050009D03*
X1058009D03*
X1056199Y1012354D03*
Y1024954D03*
X1050699D03*
Y1012354D03*
X1044867Y1428213D03*
Y1431213D03*
Y1434213D03*
Y1437213D03*
Y1440213D03*
X1051457Y1639797D03*
X1072174Y53597D03*
X1062985Y82984D03*
Y75184D03*
Y77784D03*
Y80384D03*
X1065539Y92849D03*
X1062985Y85584D03*
X1072499Y103037D03*
X1062523Y102323D03*
X1062775Y109410D03*
X1072633Y116496D03*
Y109410D03*
Y123583D03*
X1060679Y368276D03*
X1060369Y390223D03*
Y395179D03*
Y404396D03*
Y409352D03*
Y418569D03*
Y423525D03*
X1065361D03*
Y418569D03*
X1060369Y432743D03*
Y437699D03*
X1065361Y432743D03*
Y437699D03*
Y489895D03*
X1060369D03*
Y480677D03*
Y475721D03*
X1065361Y480677D03*
Y475721D03*
X1060369Y494851D03*
X1065361D03*
X1060369Y519855D03*
X1065361D03*
Y524811D03*
X1060369D03*
Y538984D03*
Y534028D03*
X1062066Y599588D03*
X1061328Y589556D03*
X1061267Y592354D03*
X1062069Y596095D03*
X1062066Y607588D03*
X1066559Y634946D03*
X1066009Y997860D03*
X1062009D03*
X1074009D03*
X1071457Y1639797D03*
X1090280Y44773D03*
X1089916Y94017D03*
X1085916D03*
X1089645Y101701D03*
X1090044Y110445D03*
Y115401D03*
X1080633Y102323D03*
Y116496D03*
Y109410D03*
Y130670D03*
Y123583D03*
X1090044Y124618D03*
Y129574D03*
X1080633Y137756D03*
X1087957Y151540D03*
X1091607Y191941D03*
X1091474Y188727D03*
X1085431Y226141D03*
X1081724Y226461D03*
X1088231Y226141D03*
X1081724Y223661D03*
X1089693Y229286D03*
X1081724Y231461D03*
Y228961D03*
X1089693Y231786D03*
X1085674Y236611D03*
X1088174D03*
X1090674D03*
X1090376Y248891D03*
X1087876D03*
X1085376D03*
X1088128Y285690D03*
Y288190D03*
X1085328D03*
X1082828Y285690D03*
X1085328D03*
X1082828Y288190D03*
X1077314Y293796D03*
X1092354Y290755D03*
X1091542Y389154D03*
Y410413D03*
Y396240D03*
Y403327D03*
Y417500D03*
Y424587D03*
Y431673D03*
Y438760D03*
Y445847D03*
Y467539D03*
Y474626D03*
Y488799D03*
Y481713D03*
Y495886D03*
Y511673D03*
Y518760D03*
Y525847D03*
Y532933D03*
Y540020D03*
Y547106D03*
X1090823Y602197D03*
X1091287Y595108D03*
X1086904Y1599004D03*
X1089474Y1638213D03*
X1092000Y1644980D03*
X1102993Y84140D03*
Y76140D03*
Y80140D03*
X1097925Y94017D03*
X1093916D03*
X1100446Y117557D03*
X1095036Y115401D03*
Y110445D03*
X1105438Y117557D03*
X1097195Y103783D03*
X1108362Y103621D03*
X1095036Y129574D03*
Y124618D03*
X1105438Y131731D03*
Y122513D03*
X1100446Y131731D03*
Y122513D03*
X1103537Y146461D03*
X1100446Y136687D03*
X1105438D03*
X1102439Y152367D03*
X1104139Y180572D03*
X1108822Y180527D03*
X1104139Y185165D03*
X1108777Y185121D03*
X1098107Y184619D03*
X1100087Y206760D03*
X1093386Y224712D03*
Y222212D03*
X1101301Y256535D03*
X1093301D03*
X1102331Y279208D03*
X1106435Y281307D03*
X1108425Y293645D03*
Y290845D03*
Y288345D03*
X1096354Y290755D03*
X1100354D03*
X1100703Y340560D03*
X1101999Y353495D03*
X1093994Y374003D03*
X1099342Y389154D03*
X1106161D03*
X1099342Y396240D03*
X1100621Y404911D03*
X1104691Y396240D03*
X1099575Y412571D03*
X1108776Y422864D03*
X1100762Y426299D03*
X1108846Y429832D03*
X1108451Y436447D03*
X1101073Y445847D03*
X1099342Y467539D03*
Y474626D03*
X1108395Y472772D03*
X1099603Y480828D03*
X1101553Y498834D03*
X1105002Y516841D03*
X1108253Y510565D03*
X1099342Y518760D03*
Y511673D03*
Y525847D03*
X1099949Y550123D03*
X1099827Y552872D03*
X1101581Y572334D03*
X1099272Y562443D03*
X1101040Y560675D03*
X1099813Y574102D03*
X1108236Y577716D03*
X1105298Y598400D03*
Y602400D03*
Y594400D03*
Y614400D03*
Y606400D03*
X1104448Y653161D03*
X1108045Y677843D03*
X1100233Y1588000D03*
X1105474Y1638426D03*
X1123052Y57511D03*
X1122613Y97042D03*
X1117764Y91951D03*
X1116368Y117261D03*
X1123899Y113394D03*
X1124075Y180665D03*
Y172665D03*
X1112545Y192421D03*
X1124107Y200864D03*
Y212864D03*
Y216864D03*
Y221864D03*
X1110925Y293645D03*
Y290845D03*
Y288345D03*
X1123500Y329000D03*
Y339000D03*
Y334000D03*
X1117453Y389154D03*
X1124753Y389153D03*
X1122253Y396240D03*
X1124753D03*
X1122253Y403327D03*
X1124753Y403326D03*
X1122253Y410413D03*
X1124753D03*
X1117453Y396240D03*
Y403327D03*
Y410413D03*
X1109468Y414823D03*
X1122253Y424586D03*
X1124753D03*
X1117453Y417500D03*
Y424586D03*
X1122253Y417500D03*
X1124753Y417499D03*
X1122253Y438760D03*
X1124753D03*
Y431673D03*
X1117453D03*
Y438760D03*
X1122253Y431673D03*
X1110486Y447953D03*
X1122253Y445847D03*
X1117453D03*
X1109653Y467539D03*
X1124753D03*
X1117453D03*
X1122253Y474626D03*
X1124753D03*
X1117453D03*
X1122253Y488799D03*
X1124753D03*
X1117453D03*
X1109129Y487711D03*
X1109242Y479104D03*
X1124753Y481712D03*
X1122253D03*
X1117453Y481713D03*
X1122253Y495886D03*
X1117453D03*
X1109653D03*
X1124753Y518760D03*
X1122253D03*
X1124753Y511673D03*
X1117453D03*
Y518760D03*
X1124753Y532933D03*
X1122253D03*
Y540020D03*
Y525846D03*
X1124753D03*
X1117453Y525847D03*
Y532933D03*
Y540020D03*
Y554193D03*
Y547106D03*
X1118847Y551683D03*
X1117913Y565414D03*
Y567914D03*
Y570414D03*
Y572914D03*
Y575414D03*
X1122718Y598857D03*
X1121191Y612555D03*
X1120512Y617332D03*
X1121022Y607750D03*
X1115151Y650119D03*
X1115320Y646449D03*
X1118863Y662981D03*
X1112839Y668885D03*
X1113244Y691851D03*
X1118855Y705043D03*
X1112000Y1644980D03*
X1125735Y60922D03*
X1136117Y102249D03*
X1139134Y109172D03*
X1141141Y106495D03*
X1132117Y102249D03*
X1128117D03*
X1126548Y110784D03*
X1134142Y133298D03*
X1126142D03*
X1140875Y146012D03*
X1128289Y134579D03*
X1134036Y198883D03*
X1134417Y195176D03*
X1131917D03*
X1137217D03*
X1129417D03*
X1137965Y206838D03*
X1134036Y201683D03*
X1131777Y203393D03*
X1129277D03*
X1135465Y206838D03*
X1137461Y238589D03*
X1140427Y236121D03*
X1140346Y253198D03*
X1125864Y252371D03*
X1129553Y389153D03*
Y396240D03*
Y403326D03*
Y410413D03*
X1142440Y404718D03*
X1129553Y424586D03*
Y417499D03*
X1142440Y412718D03*
X1129553Y431673D03*
Y438760D03*
X1126931Y453564D03*
X1130355Y453483D03*
X1129553Y467539D03*
X1125178Y459792D03*
X1129553Y474626D03*
Y488799D03*
Y481712D03*
Y518760D03*
Y511673D03*
Y532933D03*
Y525846D03*
X1138166Y534759D03*
X1138098Y543925D03*
X1126633Y560500D03*
X1125287Y592897D03*
X1129637Y1594253D03*
Y1589522D03*
X1138298Y1593853D03*
Y1598584D03*
Y1603315D03*
X1129637Y1609607D03*
Y1598984D03*
Y1604876D03*
X1138298Y1609207D03*
X1129637Y1614338D03*
X1138298Y1613938D03*
Y1618669D03*
X1132000Y1644980D03*
X1147214Y44773D03*
X1154535Y53597D03*
X1142134Y109172D03*
X1156885Y102323D03*
X1154585Y114655D03*
Y111255D03*
Y128828D03*
X1147285Y118342D03*
Y121742D03*
Y132515D03*
X1154585Y125428D03*
X1142781Y141228D03*
X1147285Y135915D03*
X1145669Y150847D03*
X1153417Y213539D03*
X1146863Y238689D03*
X1147637Y247292D03*
X1145761Y324148D03*
X1142440Y392718D03*
Y400718D03*
Y408718D03*
X1157251Y636842D03*
X1156023Y678462D03*
X1152316Y746625D03*
X1149345Y771517D03*
X1151277Y790996D03*
X1149627Y813323D03*
X1146985Y812642D03*
X1152510Y844642D03*
X1146960Y1594253D03*
X1155621Y1593853D03*
X1146960Y1589522D03*
Y1609607D03*
Y1604876D03*
Y1598984D03*
X1155621Y1609207D03*
Y1598584D03*
Y1603315D03*
X1146960Y1614338D03*
X1155621Y1613938D03*
Y1618669D03*
X1152000Y1644980D03*
X1165347Y82984D03*
Y75184D03*
Y77784D03*
Y80384D03*
X1167756Y92734D03*
X1165347Y85584D03*
X1164885Y102323D03*
X1165137Y109410D03*
X1168902Y431029D03*
X1167931Y435029D03*
X1169173Y427017D03*
X1168851Y449873D03*
X1171255Y456287D03*
X1173278Y472579D03*
X1168478D03*
X1173278Y479666D03*
X1168478D03*
Y486752D03*
X1173278D03*
X1168478Y493839D03*
X1173278D03*
X1168478Y523800D03*
Y516713D03*
X1173278D03*
Y523800D03*
Y537973D03*
X1168478D03*
X1173278Y530886D03*
X1168478D03*
X1161274Y550462D03*
X1173278Y566752D03*
X1168478D03*
Y580926D03*
X1173278D03*
Y588013D03*
X1168478D03*
X1173278Y573839D03*
X1168478D03*
Y602186D03*
X1173278D03*
Y595099D03*
X1168478D03*
X1173278Y609272D03*
X1168478D03*
Y616359D03*
X1173278D03*
X1163157Y638125D03*
X1160756Y665140D03*
X1170603Y715281D03*
X1163751Y719498D03*
X1168577Y733812D03*
X1157985Y791142D03*
X1161291Y791662D03*
X1173697Y791911D03*
X1160516Y800900D03*
X1169266Y800799D03*
X1164283Y1589522D03*
Y1594253D03*
X1172944Y1593853D03*
Y1598584D03*
Y1603315D03*
X1164283Y1609607D03*
Y1604876D03*
Y1598984D03*
X1172944Y1609207D03*
X1164283Y1614338D03*
X1172944Y1613938D03*
Y1618669D03*
X1172000Y1644980D03*
X1174535Y53597D03*
X1188278Y94017D03*
X1174861Y103037D03*
X1174995Y116496D03*
Y109410D03*
X1182995Y116496D03*
Y109410D03*
Y102323D03*
X1174995Y123583D03*
X1182995Y130670D03*
Y123583D03*
Y137756D03*
X1184086Y231461D03*
Y228961D03*
X1187793Y226141D03*
X1184086Y226461D03*
X1190593Y226141D03*
X1184086Y223661D03*
X1188036Y236611D03*
X1187738Y248891D03*
X1179676Y293796D03*
X1187690Y288190D03*
X1185190Y285690D03*
X1187690D03*
X1185190Y288190D03*
X1177176Y293796D03*
X1176858Y306534D03*
X1182911Y336516D03*
X1177036Y334148D03*
X1188598Y390500D03*
X1179184Y410394D03*
Y403307D03*
X1180118Y430098D03*
Y440098D03*
Y437598D03*
Y435098D03*
Y432598D03*
X1180578Y458406D03*
Y451319D03*
X1188378Y466027D03*
X1180402Y462264D03*
X1175778Y465492D03*
X1180578D03*
X1188520Y475262D03*
X1175778Y472579D03*
X1180578D03*
X1188520Y489435D03*
Y482666D03*
X1175778Y479666D03*
X1180578Y479665D03*
Y486752D03*
X1175778D03*
X1180578Y493839D03*
X1188336Y495088D03*
X1175778Y509626D03*
X1180578Y523799D03*
Y516713D03*
Y509626D03*
X1175778Y516713D03*
Y523800D03*
X1189071Y514608D03*
X1188993Y522134D03*
X1188378Y509626D03*
X1180578Y537973D03*
X1175778Y530886D03*
X1180578D03*
X1189475Y535677D03*
X1189636Y529136D03*
X1180578Y559665D03*
Y566752D03*
X1175778D03*
Y559665D03*
X1188378D03*
X1188759Y565574D03*
X1175778Y580926D03*
X1180578D03*
Y588012D03*
X1175778D03*
X1180578Y573839D03*
X1175778D03*
X1188406Y574338D03*
X1175778Y602185D03*
X1180578D03*
X1175778Y595099D03*
X1180578D03*
X1175778Y609272D03*
X1180578Y616358D03*
Y609272D03*
X1188505Y616358D03*
X1190062Y844378D03*
X1187703Y849734D03*
X1186742Y855466D03*
X1183431Y868340D03*
X1177775Y894053D03*
X1178480Y915220D03*
X1178000Y936500D03*
X1188431Y936568D03*
X1187200Y963400D03*
X1181605Y1589522D03*
Y1594253D03*
Y1598984D03*
Y1609607D03*
Y1604876D03*
Y1614338D03*
X1193330Y5374D03*
X1192643Y24773D03*
Y44773D03*
X1205355Y84140D03*
Y76140D03*
Y80140D03*
X1196278Y94017D03*
X1200287D03*
X1192278D03*
X1192007Y101701D03*
X1202808Y117557D03*
X1197398Y110445D03*
Y115401D03*
X1192406Y110445D03*
Y115401D03*
X1199557Y103783D03*
X1197398Y129574D03*
Y124618D03*
X1192406D03*
Y129574D03*
X1202808Y122513D03*
Y131731D03*
X1205899Y146461D03*
X1202808Y136687D03*
X1204801Y152367D03*
X1190319Y151540D03*
X1200469Y184619D03*
X1193969Y191941D03*
X1193836Y188727D03*
X1202449Y206760D03*
X1192055Y229286D03*
X1195748Y224712D03*
Y222212D03*
X1192055Y231786D03*
X1190536Y236611D03*
X1193036D03*
X1192738Y248891D03*
X1190238D03*
X1203663Y256535D03*
X1195663D03*
X1204693Y279208D03*
X1194716Y290755D03*
X1202716D03*
X1190490Y285690D03*
Y288190D03*
X1198716Y290755D03*
X1192500Y322400D03*
X1198248Y381500D03*
X1198468Y430760D03*
X1198489Y433570D03*
X1198305Y437072D03*
X1198346Y439963D03*
X1198552Y452018D03*
X1198590Y443180D03*
X1198610Y454744D03*
X1198689Y465492D03*
X1198655Y460250D03*
X1196420Y470136D03*
X1198689Y472579D03*
Y486752D03*
Y479665D03*
Y493839D03*
Y509626D03*
Y516713D03*
X1195149Y537973D03*
X1197629Y525483D03*
X1197550Y532756D03*
X1198689Y559665D03*
Y566752D03*
X1198539Y579978D03*
X1198689Y573839D03*
X1198753Y608117D03*
X1198997Y790610D03*
X1192990Y914873D03*
X1195118Y936296D03*
X1199615Y950670D03*
X1201794Y985289D03*
X1198845Y998504D03*
X1204919Y1021860D03*
X1202268Y1013551D03*
X1190267Y1593853D03*
X1198928Y1594253D03*
Y1589522D03*
X1190267Y1609207D03*
Y1598584D03*
Y1603315D03*
X1198928Y1609607D03*
Y1598984D03*
Y1604876D03*
X1190267Y1613938D03*
Y1618669D03*
X1198928Y1614338D03*
X1192000Y1644980D03*
X1212232Y3000D03*
X1220126Y91951D03*
X1218730Y117261D03*
X1207800Y117557D03*
X1210724Y103621D03*
X1207800Y122513D03*
Y131731D03*
Y136687D03*
X1206501Y180572D03*
X1211184Y180527D03*
X1214907Y192421D03*
X1206501Y185165D03*
X1211139Y185121D03*
X1208797Y281307D03*
X1213287Y293645D03*
Y290845D03*
Y288345D03*
X1210787Y293645D03*
Y290845D03*
Y288345D03*
X1217139Y324139D03*
X1221337Y332017D03*
X1220985Y342319D03*
X1206673Y410394D03*
Y403307D03*
X1206489Y458406D03*
X1212680Y445908D03*
X1206489Y465492D03*
Y472579D03*
Y479665D03*
Y486752D03*
Y493839D03*
Y523799D03*
Y516713D03*
Y509626D03*
Y537973D03*
Y530886D03*
Y566752D03*
Y559665D03*
Y580925D03*
Y588012D03*
Y573839D03*
Y602185D03*
Y595099D03*
X1212000Y1644980D03*
X1232232Y3000D03*
X1222933Y55513D03*
X1228097Y60922D03*
X1225041Y97080D03*
X1238479Y102249D03*
X1230479D03*
X1234479D03*
X1228910Y110784D03*
X1226261Y113394D03*
X1229195Y130898D03*
X1236504Y133298D03*
X1230651Y134579D03*
X1226437Y180665D03*
Y172665D03*
X1236779Y195176D03*
X1236398Y198883D03*
X1234279Y195176D03*
X1239579D03*
X1231779D03*
X1236398Y201683D03*
X1234139Y203393D03*
X1231639D03*
X1226469Y200864D03*
Y212864D03*
X1237827Y206838D03*
X1226469Y216864D03*
Y221864D03*
X1228226Y252371D03*
X1238055Y303839D03*
X1229028Y311740D03*
X1234100Y322924D03*
X1224186Y316731D03*
X1230077Y336324D03*
X1223431Y377912D03*
Y393924D03*
Y389912D03*
Y385912D03*
Y381912D03*
Y401924D03*
X1237662Y466528D03*
Y471484D03*
Y480701D03*
X1232670Y485657D03*
X1237662D03*
X1232670Y515617D03*
X1237662D03*
X1232670Y510661D03*
X1237662D03*
Y524835D03*
Y529791D03*
X1232670Y524835D03*
Y529791D03*
Y565657D03*
Y560701D03*
X1237662Y565657D03*
Y560701D03*
X1232670Y579830D03*
X1237662Y589047D03*
X1232670D03*
X1237662Y574874D03*
X1232670D03*
X1237662Y579830D03*
Y603221D03*
X1232670D03*
Y594003D03*
X1237662D03*
Y608177D03*
X1232670D03*
X1235930Y626229D03*
X1232000Y1644980D03*
X1248216Y4469D03*
X1249577Y24773D03*
Y44773D03*
X1243503Y106495D03*
X1244496Y109172D03*
X1241496D03*
X1249647Y118342D03*
Y132515D03*
Y121742D03*
X1243237Y146012D03*
X1245143Y141228D03*
X1249647Y135915D03*
X1248031Y150847D03*
X1240327Y206838D03*
X1249999Y247292D03*
X1239823Y238589D03*
X1242789Y236121D03*
X1242708Y253198D03*
X1241205Y303962D03*
X1243072Y473640D03*
X1248064D03*
X1243072Y487813D03*
X1248064D03*
X1243072Y478596D03*
X1248064D03*
X1243072Y492769D03*
X1248064D03*
X1243072Y522730D03*
X1248064Y517774D03*
Y522730D03*
X1243072Y517774D03*
X1248064Y531947D03*
Y536903D03*
X1243072D03*
Y531947D03*
X1253087Y553101D03*
X1248064Y567813D03*
X1241752Y564843D03*
X1243072Y567813D03*
X1248064Y572769D03*
X1243072D03*
X1248064Y581987D03*
Y586943D03*
X1243072D03*
Y581987D03*
Y601116D03*
X1248064D03*
X1243072Y596160D03*
X1248064D03*
X1243072Y610333D03*
Y615289D03*
X1248064D03*
Y610333D03*
X1246800Y1001600D03*
X1248721Y1025864D03*
X1246000Y1014800D03*
X1252500Y1014288D03*
X1256898Y53597D03*
X1267709Y82984D03*
Y75184D03*
Y77784D03*
Y80384D03*
X1270263Y92849D03*
X1267709Y85584D03*
X1259247Y102323D03*
X1267247D03*
X1267499Y109410D03*
X1256947Y114655D03*
Y111255D03*
Y128828D03*
Y125428D03*
X1255779Y213539D03*
X1261659Y318258D03*
X1264088Y320382D03*
X1256000Y338000D03*
X1259991Y340691D03*
X1266219Y374300D03*
X1268659Y377173D03*
X1261623Y447486D03*
X1259223Y458334D03*
X1267843Y488618D03*
Y491118D03*
Y493618D03*
X1270951Y491870D03*
X1272661Y929858D03*
X1276898Y53597D03*
X1277223Y103037D03*
X1277357Y116496D03*
Y109410D03*
X1285357Y116496D03*
Y109410D03*
Y102323D03*
Y123583D03*
X1277357D03*
X1285357Y130670D03*
Y137756D03*
X1286448Y223661D03*
Y226461D03*
Y228961D03*
Y231461D03*
X1279538Y293796D03*
X1282038D03*
X1283494Y339495D03*
X1281834Y374839D03*
X1287437Y370010D03*
X1275940Y392228D03*
X1271346Y392183D03*
X1275407Y402867D03*
X1271391Y396866D03*
X1275984D03*
X1282760Y409016D03*
X1278724Y409032D03*
X1272215Y442518D03*
Y439718D03*
X1279127Y450091D03*
X1282092Y449118D03*
Y446318D03*
X1281737Y452740D03*
X1283455Y468088D03*
Y465288D03*
X1280616Y472189D03*
X1279505Y487570D03*
Y490070D03*
X1276060Y496258D03*
X1273451Y491870D03*
X1276060Y493758D03*
X1278255Y722241D03*
X1279539Y748576D03*
X1282539Y751076D03*
X1279539Y763576D03*
X1282539Y766076D03*
X1279539Y758576D03*
X1282539Y756076D03*
Y761076D03*
X1279539Y753576D03*
X1279460Y854487D03*
Y859487D03*
Y864487D03*
Y874487D03*
Y869487D03*
Y879487D03*
Y884487D03*
X1285302Y885783D03*
X1279460Y889487D03*
X1282184Y898854D03*
X1281733Y949475D03*
X1297687Y-33656D03*
Y-30256D03*
X1302232Y3000D03*
X1295692Y5374D03*
X1303229Y23274D03*
X1295005Y24773D03*
X1297785Y30618D03*
X1295005Y44773D03*
X1302649Y94017D03*
X1298640D03*
X1290640D03*
X1294369Y101701D03*
X1294640Y94017D03*
X1301919Y103783D03*
X1299760Y110445D03*
Y115401D03*
X1294768Y110445D03*
Y115401D03*
Y129574D03*
X1299760D03*
Y124618D03*
X1294768D03*
X1296331Y191941D03*
X1302831Y184619D03*
X1296198Y188727D03*
X1292955Y226141D03*
X1290155D03*
X1294417Y229286D03*
X1298110Y222212D03*
Y224712D03*
X1290398Y236611D03*
X1295398D03*
X1292898D03*
X1294417Y231786D03*
X1298025Y256535D03*
X1290100Y248891D03*
X1292600D03*
X1295100D03*
X1290052Y288190D03*
X1292852D03*
Y285690D03*
X1305078Y290755D03*
X1297078D03*
X1301078D03*
X1287552Y288190D03*
X1290052Y285690D03*
X1287552D03*
X1301500Y329000D03*
X1294425Y321425D03*
X1292731Y331820D03*
X1300400Y339619D03*
Y344575D03*
X1299959Y351454D03*
X1303158Y371043D03*
X1299410Y370976D03*
X1291165Y395248D03*
X1290092Y449118D03*
Y446318D03*
X1299757Y450041D03*
Y452841D03*
Y455641D03*
X1290272Y458309D03*
Y454309D03*
Y462309D03*
X1296783Y511956D03*
X1296770Y828775D03*
X1293500Y871800D03*
Y875800D03*
X1301657Y899129D03*
X1292836Y975244D03*
X1292631Y979845D03*
X1299717Y1024136D03*
X1302866Y1609607D03*
Y1604876D03*
Y1614338D03*
X1292000Y1644980D03*
X1307717Y84140D03*
Y76140D03*
Y80140D03*
X1310162Y117557D03*
X1305170D03*
X1313086Y103621D03*
X1310162Y122513D03*
Y131731D03*
X1305170Y122513D03*
Y131731D03*
X1310162Y136687D03*
X1305170D03*
X1313546Y180527D03*
X1308863Y180572D03*
Y185165D03*
X1317269Y192421D03*
X1313501Y185121D03*
X1304811Y206760D03*
X1306025Y256535D03*
X1307055Y279208D03*
X1311159Y281307D03*
X1313149Y288345D03*
Y290845D03*
Y293645D03*
X1315649Y288345D03*
Y290845D03*
Y293645D03*
X1314569Y318013D03*
X1312069D03*
X1317584Y313058D03*
X1316017Y349889D03*
X1308012Y348109D03*
X1308410Y370899D03*
X1311283Y370801D03*
X1313691Y402642D03*
X1316191D03*
X1310546Y409904D03*
Y407104D03*
X1309117Y398949D03*
X1306617Y401949D03*
X1308066Y413611D03*
X1310866D03*
X1313366D03*
X1315866D03*
X1315806Y423944D03*
X1313306D03*
X1310806D03*
X1308006D03*
X1309750Y455641D03*
Y450041D03*
Y452841D03*
X1308010Y466409D03*
X1307996Y487382D03*
X1311488Y479560D03*
X1307919Y478382D03*
X1307825Y482382D03*
X1305412Y799061D03*
X1305134Y812065D03*
X1308220Y889253D03*
X1311061Y889361D03*
X1321256Y943815D03*
X1307707Y979870D03*
X1307561Y986951D03*
X1309937Y1037038D03*
X1319326Y1040723D03*
X1313459Y1081599D03*
X1310589Y1097278D03*
X1313089D03*
X1317437Y1152684D03*
Y1160834D03*
X1318178Y1192621D03*
Y1190121D03*
X1319237Y1221428D03*
X1311237D03*
X1315237D03*
X1311237Y1233428D03*
Y1229428D03*
Y1225428D03*
X1315237Y1237428D03*
Y1233428D03*
Y1229428D03*
Y1225428D03*
X1319237Y1237428D03*
Y1233428D03*
Y1229428D03*
Y1225428D03*
X1315237Y1241428D03*
X1319237D03*
X1308276Y1276446D03*
X1311527Y1609207D03*
Y1613938D03*
Y1618669D03*
X1312000Y1644980D03*
X1322232Y3000D03*
X1334223Y33425D03*
X1321092Y117261D03*
X1328799Y172665D03*
Y180665D03*
X1328831Y212864D03*
Y200864D03*
Y208864D03*
Y221864D03*
Y216864D03*
X1330414Y310058D03*
X1325458D03*
X1322540Y313058D03*
X1333332D03*
X1331085Y334347D03*
X1323816D03*
Y341615D03*
X1331085Y348868D03*
X1323816D03*
X1326489Y356945D03*
X1320903Y370995D03*
X1333331Y370905D03*
X1329064Y370951D03*
X1333049Y399268D03*
Y401768D03*
Y396768D03*
X1321016Y399161D03*
Y401661D03*
Y396661D03*
X1325941Y408240D03*
X1328441D03*
X1323441D03*
X1326059Y420393D03*
X1326020Y424240D03*
X1323559Y420393D03*
X1328559D03*
X1326020Y426740D03*
X1329626Y455039D03*
X1332927Y468607D03*
X1325927Y474513D03*
X1326912Y493153D03*
X1325630Y513238D03*
X1326993Y556788D03*
X1327043Y573346D03*
X1327000Y562500D03*
Y578500D03*
Y605000D03*
Y695500D03*
X1335803Y826500D03*
X1331078Y900500D03*
X1333132Y933781D03*
X1323000Y934075D03*
X1329834Y988132D03*
X1331890Y1051919D03*
X1331359Y1098898D03*
X1334161Y1098518D03*
X1334956Y1105552D03*
X1333905Y1123101D03*
X1331405D03*
X1323405D03*
X1320279Y1131935D03*
Y1134435D03*
Y1136935D03*
Y1139435D03*
X1334305Y1129301D03*
X1331805D03*
X1329305D03*
X1326805D03*
X1324305D03*
X1321805D03*
X1334305Y1125801D03*
X1331805D03*
X1323405D03*
X1320279Y1141935D03*
Y1146935D03*
Y1144435D03*
X1326269Y1152713D03*
Y1155213D03*
X1325635Y1172384D03*
Y1162384D03*
Y1164884D03*
Y1167384D03*
Y1169884D03*
X1323135Y1172384D03*
Y1162384D03*
Y1164884D03*
Y1167384D03*
Y1169884D03*
X1334793Y1179421D03*
Y1181921D03*
Y1184421D03*
Y1186921D03*
X1320493Y1186709D03*
Y1184209D03*
Y1181709D03*
Y1179209D03*
X1325635Y1174884D03*
X1323135D03*
X1331643Y1192621D03*
Y1190121D03*
X1327237Y1221428D03*
X1331237D03*
X1335237D03*
X1323237D03*
X1327237Y1237428D03*
Y1233428D03*
Y1229428D03*
Y1225428D03*
X1331237Y1237428D03*
Y1233428D03*
Y1229428D03*
Y1225428D03*
X1335237Y1237428D03*
Y1233428D03*
Y1229428D03*
Y1225428D03*
X1323237Y1237428D03*
Y1233428D03*
Y1229428D03*
Y1225428D03*
X1335237Y1241428D03*
X1323237Y1245428D03*
Y1241428D03*
X1327237Y1245428D03*
Y1241428D03*
X1331237Y1245428D03*
Y1241428D03*
X1335237Y1245428D03*
X1330070Y1297498D03*
X1335470D03*
X1320189Y1609607D03*
Y1604876D03*
X1328850Y1609207D03*
Y1613938D03*
Y1618669D03*
X1320189Y1614338D03*
X1332000Y1644980D03*
X1337687Y-69306D03*
Y-72706D03*
X1342232Y3000D03*
X1340320Y151540D03*
X1348419Y265222D03*
X1338288Y313058D03*
X1338378Y334347D03*
X1338275Y341603D03*
X1338378Y348830D03*
X1338287Y370905D03*
X1347897Y433975D03*
X1346483Y436164D03*
X1350929Y687043D03*
X1340299Y686243D03*
X1349976Y829000D03*
X1350000Y825500D03*
X1343465Y1026123D03*
X1340665D03*
X1343465Y1028923D03*
X1340665D03*
X1347380Y1057998D03*
Y1055498D03*
X1344880D03*
Y1057998D03*
X1347380Y1060498D03*
Y1062998D03*
X1344880D03*
Y1060498D03*
X1339349Y1098767D03*
X1339305Y1129301D03*
X1336805D03*
X1339305Y1125801D03*
X1336805D03*
X1343505Y1136935D03*
Y1134435D03*
Y1139435D03*
Y1131935D03*
X1349907D03*
Y1134435D03*
Y1136935D03*
Y1139435D03*
X1352407Y1131935D03*
Y1134435D03*
Y1136935D03*
Y1139435D03*
X1347300Y1128332D03*
X1343725Y1128738D03*
X1343505Y1146935D03*
Y1144435D03*
Y1141935D03*
X1349907D03*
Y1146935D03*
Y1144435D03*
X1352407Y1141935D03*
Y1146935D03*
Y1144435D03*
X1336669Y1152713D03*
Y1155213D03*
X1351405Y1154902D03*
Y1152402D03*
X1343905Y1162384D03*
Y1164884D03*
Y1167384D03*
Y1169884D03*
Y1172384D03*
X1341405D03*
Y1169884D03*
Y1167384D03*
Y1164884D03*
Y1162384D03*
X1350963Y1172384D03*
Y1169884D03*
Y1167384D03*
Y1164884D03*
Y1162384D03*
X1351149Y1158200D03*
X1347423Y1186709D03*
Y1184209D03*
Y1181709D03*
Y1179209D03*
X1343905Y1174884D03*
X1341405D03*
X1350963D03*
X1337108Y1192621D03*
Y1190121D03*
X1345108D03*
Y1192621D03*
X1347237Y1221428D03*
X1343237D03*
X1339237D03*
X1347237Y1237428D03*
Y1233428D03*
Y1229428D03*
X1343237D03*
Y1233428D03*
Y1237428D03*
X1339237D03*
Y1233428D03*
Y1229428D03*
Y1225428D03*
X1347237Y1245428D03*
Y1241428D03*
X1343237D03*
Y1245428D03*
X1339237D03*
Y1241428D03*
X1340870Y1297498D03*
X1346270D03*
X1351670D03*
X1337512Y1609607D03*
Y1604876D03*
X1346173Y1609207D03*
X1337512Y1614338D03*
X1346173Y1613938D03*
Y1618669D03*
X1352000Y1644980D03*
X1362232Y3000D03*
X1355900Y146461D03*
X1354802Y152367D03*
X1361039Y327099D03*
Y332055D03*
X1364039Y334973D03*
Y339929D03*
X1361039Y342847D03*
X1364039Y350721D03*
X1361039Y347803D03*
X1364039Y355677D03*
X1360719Y424601D03*
X1360352Y447101D03*
X1365948Y939475D03*
X1361948Y943603D03*
X1369948D03*
X1363173Y994483D03*
X1363905Y1000855D03*
X1366493Y1000828D03*
X1367884Y1018825D03*
X1357265Y1022766D03*
X1364237Y1043140D03*
X1357265Y1030266D03*
X1366265Y1039880D03*
X1363941Y1047047D03*
X1364418Y1090568D03*
Y1093068D03*
X1366289Y1098518D03*
X1361037Y1098428D03*
X1367084Y1105552D03*
X1355533Y1123101D03*
X1363533D03*
X1366033D03*
X1366433Y1129301D03*
X1355533Y1125801D03*
X1363933D03*
X1366433D03*
X1353933Y1129301D03*
X1356433D03*
X1358933D03*
X1361433D03*
X1363933D03*
X1357397Y1155213D03*
Y1152713D03*
X1366797D03*
Y1155213D03*
X1353463Y1172384D03*
Y1169884D03*
Y1167384D03*
Y1164884D03*
Y1162384D03*
X1361723Y1179421D03*
Y1181921D03*
Y1184421D03*
Y1186921D03*
X1353463Y1174884D03*
X1364038Y1190121D03*
Y1192621D03*
X1357070Y1297498D03*
X1354834Y1609607D03*
Y1604876D03*
X1363496Y1609207D03*
X1354834Y1614338D03*
X1363496Y1613938D03*
Y1618669D03*
X1382232Y3000D03*
X1376262Y113394D03*
X1378911Y110784D03*
X1380480Y102249D03*
X1384480D03*
X1378505Y133298D03*
X1380652Y134579D03*
X1384280Y195176D03*
X1381780D03*
X1384140Y203393D03*
X1381640D03*
X1386399Y201683D03*
X1378227Y252371D03*
X1384253Y346826D03*
X1384447Y356871D03*
X1384174Y362641D03*
X1373748Y397758D03*
X1377024Y397713D03*
X1375108Y420838D03*
X1375171Y424741D03*
X1375375Y428995D03*
X1383343Y508228D03*
X1383907Y516591D03*
X1383556Y554388D03*
X1371379Y986717D03*
X1370384Y1004680D03*
X1383669Y1011303D03*
Y1017303D03*
Y1023303D03*
X1376601Y1030218D03*
X1378559Y1038534D03*
X1374451Y1090568D03*
Y1093068D03*
X1371477Y1098767D03*
X1375633Y1136935D03*
Y1134435D03*
Y1139435D03*
Y1131935D03*
X1383366D03*
Y1134435D03*
Y1136935D03*
Y1139435D03*
X1368933Y1125801D03*
X1371433D03*
X1368933Y1129301D03*
X1371433D03*
X1383024Y1152684D03*
X1376861D03*
X1375633Y1146935D03*
Y1144435D03*
Y1141935D03*
X1383366D03*
Y1146935D03*
Y1144435D03*
X1369233Y1169884D03*
Y1172384D03*
X1371733D03*
Y1169884D03*
Y1167384D03*
Y1164884D03*
Y1162384D03*
X1369233D03*
Y1164884D03*
Y1167384D03*
X1376861Y1160834D03*
X1383024D03*
X1369233Y1174884D03*
X1371733D03*
X1377390Y1254164D03*
X1372157Y1604876D03*
Y1609607D03*
Y1614338D03*
X1372000Y1644980D03*
X1398216Y4469D03*
X1399577Y24773D03*
Y44773D03*
X1388480Y102249D03*
X1391497Y109172D03*
X1394497D03*
X1393504Y106495D03*
X1386505Y133298D03*
X1399648Y132515D03*
Y121742D03*
Y118342D03*
X1393238Y146012D03*
X1395144Y141228D03*
X1399648Y135915D03*
X1398032Y150847D03*
X1389580Y195176D03*
X1386399Y198883D03*
X1386780Y195176D03*
X1390328Y206838D03*
X1387828D03*
X1400000Y247292D03*
X1399226Y238689D03*
X1392790Y236121D03*
X1389824Y238589D03*
X1392709Y253198D03*
X1385943Y323222D03*
X1385971Y327688D03*
X1386143Y331982D03*
X1386057Y341200D03*
X1385971Y336791D03*
X1386286Y350218D03*
X1397550Y390484D03*
X1396528Y397454D03*
X1399571Y397418D03*
X1393575Y397310D03*
X1390553Y397436D03*
X1387125Y417312D03*
X1393177Y424804D03*
X1393208Y428109D03*
X1393336Y431100D03*
X1403085Y460565D03*
X1397079Y527726D03*
X1400912Y581222D03*
Y591215D03*
X1402000Y900000D03*
X1398247Y926261D03*
X1401000Y925789D03*
X1396869Y958707D03*
X1402064Y965913D03*
X1395669Y1011303D03*
X1389669D03*
X1395669Y1017303D03*
Y1023303D03*
X1389669D03*
X1390322Y1057998D03*
Y1055498D03*
X1392822D03*
Y1057998D03*
X1390322Y1060498D03*
Y1062998D03*
X1392822D03*
Y1060498D03*
X1399748Y1098518D03*
X1394496Y1098428D03*
X1400543Y1105552D03*
X1388992Y1123101D03*
X1396992D03*
X1399492D03*
X1385866Y1131935D03*
Y1134435D03*
Y1136935D03*
Y1139435D03*
X1388992Y1125801D03*
X1397392D03*
X1399892D03*
X1387392Y1129301D03*
X1389892D03*
X1392392D03*
X1394892D03*
X1397392D03*
X1399892D03*
X1391856Y1155213D03*
Y1152713D03*
X1385866Y1141935D03*
Y1146935D03*
Y1144435D03*
X1388722Y1162384D03*
Y1164884D03*
Y1167384D03*
Y1169884D03*
Y1172384D03*
X1391222Y1162384D03*
Y1164884D03*
Y1167384D03*
Y1169884D03*
Y1172384D03*
X1388722Y1174884D03*
X1391222D03*
X1393695Y1186709D03*
Y1184209D03*
Y1181709D03*
Y1179209D03*
X1391380Y1190121D03*
Y1192621D03*
X1385992Y1285466D03*
X1390492D03*
X1392000Y1644980D03*
X1406898Y53597D03*
X1417248Y102323D03*
X1409248D03*
X1406948Y111255D03*
Y114655D03*
Y128828D03*
Y125428D03*
X1405780Y213539D03*
X1402921Y322403D03*
X1416347Y384373D03*
X1408254Y398041D03*
X1407844Y411033D03*
X1410903Y470419D03*
X1415823Y482165D03*
X1406910Y491982D03*
X1408103Y555194D03*
X1410903D03*
X1408103Y563194D03*
X1410903D03*
X1408103Y571194D03*
X1410903D03*
X1406512Y581222D03*
X1403712D03*
Y591215D03*
X1406512D03*
X1405514Y611091D03*
X1418000Y701000D03*
Y729000D03*
X1406867Y783273D03*
X1413500Y832000D03*
Y828000D03*
Y848000D03*
Y840000D03*
Y836000D03*
Y864000D03*
Y856000D03*
Y852000D03*
Y872000D03*
X1405500Y888000D03*
X1404689Y910897D03*
X1405500Y904000D03*
X1404760Y915186D03*
X1413575D03*
X1413322Y958908D03*
X1404317Y989436D03*
X1411038Y985379D03*
X1404936Y1098767D03*
X1415494Y1139435D03*
Y1136935D03*
Y1134435D03*
Y1131935D03*
X1409092Y1136935D03*
Y1134435D03*
Y1139435D03*
Y1131935D03*
X1402392Y1125801D03*
X1404892D03*
X1402392Y1129301D03*
X1404892D03*
X1409425Y1129238D03*
X1413177Y1128894D03*
X1409092Y1141935D03*
X1416736Y1152713D03*
Y1155213D03*
X1402256D03*
Y1152713D03*
X1415494Y1144435D03*
Y1146935D03*
Y1141935D03*
X1409092Y1146935D03*
Y1144435D03*
X1409492Y1167384D03*
Y1169884D03*
Y1172384D03*
X1406992D03*
Y1169884D03*
X1416550Y1162384D03*
Y1164884D03*
Y1167384D03*
Y1169884D03*
Y1172384D03*
X1406992Y1167384D03*
Y1164884D03*
Y1162384D03*
X1409492D03*
Y1164884D03*
X1416736Y1158200D03*
X1416550Y1174884D03*
X1409492D03*
X1406992D03*
X1407995Y1179421D03*
Y1181921D03*
Y1184421D03*
Y1186921D03*
X1410310Y1192621D03*
Y1190121D03*
X1404845D03*
Y1192621D03*
X1408736Y1222194D03*
X1412736D03*
X1416736D03*
X1408736Y1238194D03*
Y1234194D03*
Y1230194D03*
Y1226194D03*
X1412736Y1238194D03*
Y1234194D03*
Y1230194D03*
Y1226194D03*
X1416736Y1238194D03*
Y1234194D03*
Y1230194D03*
Y1226194D03*
X1412736Y1246194D03*
Y1242194D03*
X1416736Y1246194D03*
Y1242194D03*
X1408736D03*
Y1246194D03*
X1415903Y1282590D03*
X1404019Y1285290D03*
X1414346Y1303020D03*
X1404239Y1547755D03*
X1403747Y1570433D03*
X1412000Y1644980D03*
X1426898Y53597D03*
X1417710Y82984D03*
Y75184D03*
Y77784D03*
Y80384D03*
X1420264Y92849D03*
X1417710Y85584D03*
X1427224Y103037D03*
X1417500Y109410D03*
X1427358Y116496D03*
Y109410D03*
Y123583D03*
X1429539Y293796D03*
X1432039D03*
X1431019Y434508D03*
X1427019D03*
X1424196Y446352D03*
X1428782Y445874D03*
X1427484Y470045D03*
X1422903Y469905D03*
X1431484Y470045D03*
X1430930Y500086D03*
X1433310Y504699D03*
X1430810D03*
X1433012Y516979D03*
X1430512D03*
X1431493Y521804D03*
X1427800Y528578D03*
X1432955Y527449D03*
X1431493Y524304D03*
X1427800Y531378D03*
X1421099Y546830D03*
X1427233Y628183D03*
X1424389Y627948D03*
X1433529Y660564D03*
X1426000Y717000D03*
Y761000D03*
X1435000Y765500D03*
Y770500D03*
X1422813Y910065D03*
X1424126Y900295D03*
X1427553Y939200D03*
X1420699Y958452D03*
X1427473Y965621D03*
X1420740Y1004766D03*
Y1000766D03*
Y1016266D03*
Y1030766D03*
X1420107Y1052514D03*
X1430005Y1090568D03*
Y1093068D03*
X1431876Y1098518D03*
X1426624Y1098428D03*
X1432671Y1105552D03*
X1421120Y1123101D03*
X1429120D03*
X1431620D03*
X1422020Y1129301D03*
X1424520D03*
X1427020D03*
X1429520D03*
X1432020D03*
X1417994Y1139435D03*
Y1136935D03*
Y1134435D03*
Y1131935D03*
X1421120Y1125801D03*
X1429520D03*
X1432020D03*
X1419520Y1129301D03*
X1432384Y1155213D03*
Y1152713D03*
X1422984D03*
Y1155213D03*
X1417994Y1144435D03*
Y1146935D03*
Y1141935D03*
X1419050Y1162384D03*
Y1164884D03*
Y1167384D03*
Y1169884D03*
Y1172384D03*
Y1174884D03*
X1420625Y1186709D03*
Y1184209D03*
Y1181709D03*
Y1179209D03*
X1418310Y1192621D03*
Y1190121D03*
X1420736Y1222194D03*
X1424736D03*
X1428736D03*
X1432736D03*
X1420736Y1238194D03*
Y1234194D03*
Y1230194D03*
Y1226194D03*
X1424736Y1238194D03*
Y1234194D03*
Y1230194D03*
Y1226194D03*
X1428736Y1238194D03*
Y1234194D03*
Y1230194D03*
Y1226194D03*
X1432736Y1234194D03*
Y1230194D03*
Y1226194D03*
X1420736Y1246194D03*
Y1242194D03*
X1424736Y1246194D03*
Y1242194D03*
X1428736Y1246194D03*
Y1242194D03*
X1425652Y1297411D03*
X1422176Y1491198D03*
X1423065Y1508327D03*
X1432499Y1512175D03*
X1423806Y1524252D03*
X1424245Y1543338D03*
X1425558Y1537432D03*
X1425260Y1558072D03*
X1433558Y1555366D03*
X1423701Y1563978D03*
X1432000Y1644980D03*
X1445692Y5374D03*
X1445005Y24773D03*
Y44773D03*
X1444641Y94017D03*
X1448641D03*
X1440641D03*
X1444370Y101701D03*
X1435358Y116496D03*
Y109410D03*
X1449761Y115401D03*
Y110445D03*
X1444769D03*
Y115401D03*
X1435358Y102323D03*
X1449761Y124618D03*
X1444769D03*
Y129574D03*
X1435358Y130670D03*
Y123583D03*
X1449761Y129574D03*
X1435358Y137756D03*
X1442682Y151540D03*
X1446332Y191941D03*
X1446199Y188727D03*
X1436449Y228961D03*
X1444418Y229286D03*
X1442956Y226141D03*
X1436449Y226461D03*
X1440156Y226141D03*
X1436449Y223661D03*
X1448111Y222212D03*
Y224712D03*
X1436449Y231461D03*
X1440399Y236611D03*
X1442899D03*
X1444418Y231786D03*
X1445399Y236611D03*
X1448026Y256535D03*
X1440101Y248891D03*
X1442601D03*
X1445101D03*
X1440053Y285690D03*
X1437553D03*
X1440053Y288190D03*
X1442853D03*
Y285690D03*
X1447079Y290755D03*
X1437553Y288190D03*
X1440568Y369566D03*
X1449619Y363290D03*
X1437758Y362584D03*
X1435019Y434508D03*
X1437757Y447201D03*
X1437879Y444269D03*
X1435484Y470045D03*
X1442786Y480705D03*
X1437631Y482134D03*
Y484634D03*
X1445586Y480705D03*
X1441076Y475946D03*
Y478446D03*
X1435810Y504699D03*
X1447036Y519518D03*
X1435512Y516979D03*
X1439462Y522129D03*
X1444536Y519518D03*
X1439536D03*
X1442036D03*
X1439462Y529929D03*
X1435755Y527449D03*
X1439462Y527129D03*
Y524629D03*
X1443555Y532949D03*
X1446355D03*
X1438882Y572842D03*
X1447037Y585507D03*
X1442444D03*
X1442990Y579475D03*
X1435668Y572975D03*
X1442488Y590145D03*
X1447082Y590190D03*
X1435241Y593796D03*
X1434049Y608311D03*
X1446944Y605443D03*
X1437770Y628242D03*
X1440930Y636005D03*
Y633205D03*
Y638805D03*
X1435952Y642184D03*
X1448991Y694392D03*
X1451976Y693844D03*
X1446538Y719548D03*
X1435212Y854042D03*
X1438188Y867633D03*
X1443041Y873683D03*
X1437703Y880067D03*
X1449072Y892581D03*
X1435288Y897500D03*
X1444453Y938806D03*
X1439031Y957683D03*
X1439449Y979009D03*
X1440610Y1021567D03*
X1435266Y1031522D03*
X1437064Y1098767D03*
X1441220Y1131935D03*
Y1139435D03*
Y1134435D03*
Y1136935D03*
X1434520Y1125801D03*
X1437020D03*
X1434520Y1129301D03*
X1437020D03*
X1441220Y1141935D03*
Y1144435D03*
Y1146935D03*
X1442448Y1152684D03*
Y1160834D03*
X1434820Y1162384D03*
Y1164884D03*
Y1167384D03*
Y1169884D03*
Y1172384D03*
X1437320D03*
Y1169884D03*
Y1167384D03*
Y1164884D03*
Y1162384D03*
X1434925Y1179421D03*
Y1181921D03*
Y1184421D03*
Y1186921D03*
X1434820Y1174884D03*
X1437320D03*
X1437240Y1192621D03*
Y1190121D03*
X1436736Y1222194D03*
Y1226194D03*
X1436408Y1303462D03*
X1444438Y1308312D03*
X1439482D03*
X1441286Y1335776D03*
X1437293Y1546125D03*
X1436801Y1568803D03*
X1464594Y3000D03*
X1462675Y14334D03*
X1457718Y84140D03*
Y76140D03*
Y80140D03*
X1452650Y94017D03*
X1460163Y117557D03*
X1455171D03*
X1463087Y103621D03*
X1451920Y103783D03*
X1455171Y122513D03*
X1460163Y131731D03*
Y122513D03*
X1455171Y131731D03*
X1458262Y146461D03*
X1460163Y136687D03*
X1455171D03*
X1457164Y152367D03*
X1463547Y180527D03*
X1458864Y180572D03*
Y185165D03*
X1463502Y185121D03*
X1452832Y184619D03*
X1454812Y206760D03*
X1456026Y256535D03*
X1457056Y279208D03*
X1461160Y281307D03*
X1465650Y293645D03*
X1455079Y290755D03*
X1451079D03*
X1465650Y288345D03*
Y290845D03*
X1463150Y288345D03*
Y290845D03*
Y293645D03*
X1451215Y323193D03*
X1451330Y327588D03*
X1451272Y340971D03*
X1451344Y336620D03*
X1451300Y332225D03*
X1451387Y345609D03*
X1451186Y350447D03*
X1458982Y356861D03*
X1455979Y391756D03*
X1458212Y403374D03*
X1454944Y605443D03*
X1453000Y633450D03*
Y636250D03*
Y639050D03*
X1455761Y683448D03*
X1468372Y673812D03*
X1460111Y683536D03*
X1455291Y759656D03*
X1455159Y763714D03*
X1461241Y867475D03*
X1462694Y874859D03*
Y877859D03*
X1460472Y885985D03*
X1459420Y899226D03*
X1451005Y931848D03*
X1462819Y949996D03*
X1462000Y960378D03*
X1460655Y964253D03*
X1466076Y979746D03*
X1455939Y1018368D03*
X1459683Y1028377D03*
X1465503Y1030233D03*
X1452000Y1644980D03*
X1481905Y-69278D03*
Y-72678D03*
X1476822Y40780D03*
X1480460Y60922D03*
X1475296Y55513D03*
X1472489Y91951D03*
X1471093Y117261D03*
X1478624Y113394D03*
X1481273Y110784D03*
X1481368Y130898D03*
X1478800Y180665D03*
Y172665D03*
X1467270Y192421D03*
X1478832Y200864D03*
Y212864D03*
Y216864D03*
Y221864D03*
X1480589Y252371D03*
X1473364Y410724D03*
X1472403Y417338D03*
X1469293Y428815D03*
X1473900Y433100D03*
X1479759Y720885D03*
X1479794Y709388D03*
X1469116Y719055D03*
X1479665Y754555D03*
X1473634Y864337D03*
X1481454Y911570D03*
X1474075Y920575D03*
X1474349Y949394D03*
X1468500Y974181D03*
X1479096Y997860D03*
X1471096D03*
X1475096D03*
X1467096D03*
X1468869Y1018469D03*
X1471854Y1035088D03*
X1479624Y1035102D03*
X1468371Y1030701D03*
X1480193Y1102091D03*
X1474384D03*
X1480193Y1114691D03*
X1474384D03*
X1480193Y1127291D03*
X1474384D03*
X1476094Y1465913D03*
Y1461182D03*
Y1456451D03*
Y1471805D03*
Y1481267D03*
Y1476536D03*
Y1491890D03*
Y1487159D03*
Y1496621D03*
Y1563544D03*
Y1558813D03*
Y1568275D03*
Y1578898D03*
Y1574167D03*
Y1583629D03*
Y1609607D03*
Y1604876D03*
Y1614338D03*
X1472000Y1644980D03*
X1484594Y3000D03*
X1498621Y15043D03*
Y35043D03*
Y27043D03*
X1490842Y102249D03*
X1486842D03*
X1482842D03*
X1493859Y109172D03*
X1496859D03*
X1495866Y106495D03*
X1488867Y133298D03*
X1495600Y146012D03*
X1497506Y141228D03*
X1483014Y134579D03*
X1486642Y195176D03*
X1488761Y198883D03*
X1489142Y195176D03*
X1484142D03*
X1491942D03*
X1488761Y201683D03*
X1492690Y206838D03*
X1490190D03*
X1484002Y203393D03*
X1486502D03*
X1492186Y238589D03*
X1495152Y236121D03*
X1495071Y253198D03*
X1484796Y320359D03*
X1484968Y325025D03*
X1484876Y329377D03*
X1488255Y342921D03*
X1484682Y338394D03*
X1497760Y336543D03*
X1487926Y347387D03*
X1486360Y358700D03*
Y354200D03*
X1483813Y368516D03*
X1487050Y809413D03*
X1486386Y825296D03*
X1491425Y845575D03*
X1496500Y836000D03*
X1489805Y866386D03*
X1497488Y873839D03*
X1491414Y875383D03*
X1494000Y884000D03*
X1498084Y894825D03*
X1492101Y894860D03*
X1498446Y912370D03*
X1496383Y898023D03*
X1497208Y909740D03*
X1496500Y919000D03*
X1496000Y922000D03*
X1487075Y920925D03*
X1485100Y943900D03*
X1496425Y943075D03*
X1496072Y950044D03*
X1482591Y961909D03*
X1486500Y947000D03*
X1485226Y973886D03*
X1492560Y974654D03*
X1482535Y1008262D03*
Y1002453D03*
X1495339Y1009354D03*
X1491839D03*
X1486030D03*
X1491096Y997860D03*
X1483096D03*
X1495096D03*
X1487096D03*
X1482535Y1011762D03*
X1495339Y1021954D03*
X1491839D03*
X1486030D03*
Y1016827D03*
X1483693Y1102091D03*
Y1114691D03*
Y1127291D03*
X1484755Y1609207D03*
X1493417Y1609607D03*
Y1604876D03*
X1484755Y1613938D03*
Y1618669D03*
X1493417Y1614338D03*
X1492000Y1644980D03*
X1500578Y4469D03*
X1501939Y24773D03*
Y44773D03*
X1509260Y53597D03*
X1511610Y102323D03*
X1509310Y114655D03*
Y111255D03*
X1502010Y121742D03*
X1509310Y125428D03*
Y128828D03*
X1502010Y118342D03*
Y132515D03*
Y135915D03*
X1500394Y150847D03*
X1508142Y213539D03*
X1502362Y247292D03*
X1501588Y238689D03*
X1500480Y295727D03*
X1501807Y323766D03*
X1509454Y402291D03*
X1514446D03*
X1509454Y397335D03*
X1514446D03*
X1512046Y411509D03*
X1507054Y416465D03*
Y411509D03*
X1512046Y425682D03*
X1507054D03*
X1512046Y416465D03*
Y439855D03*
X1507054D03*
X1512046Y430638D03*
X1507054D03*
X1512046Y444811D03*
X1507054D03*
X1507864Y450750D03*
X1507054Y468609D03*
X1512046D03*
X1507054Y473565D03*
X1512046D03*
X1507054Y487738D03*
X1512046D03*
X1507054Y482782D03*
X1512046D03*
X1507054Y517699D03*
X1512046D03*
X1507054Y512743D03*
X1512046D03*
X1511963Y536382D03*
X1507054Y526916D03*
X1512046Y531872D03*
X1507054D03*
X1512046Y526916D03*
X1507034Y888133D03*
X1507358Y909740D03*
X1507305Y912262D03*
X1510280Y899732D03*
X1514354Y938811D03*
X1510500Y931500D03*
X1513955Y950396D03*
X1505888Y965964D03*
X1501400Y966000D03*
X1514000Y968739D03*
X1510740Y973740D03*
X1507096Y997860D03*
X1503096D03*
X1511096D03*
X1499096D03*
X1505130Y1105091D03*
Y1117691D03*
X1502078Y1609207D03*
X1510740Y1609607D03*
Y1604876D03*
X1502078Y1613938D03*
Y1618669D03*
X1510740Y1614338D03*
X1512000Y1644980D03*
X1517261Y-33758D03*
Y-30358D03*
X1529260Y53597D03*
X1520072Y82984D03*
Y75184D03*
Y77784D03*
Y80384D03*
X1522626Y92849D03*
X1520072Y85584D03*
X1529586Y103037D03*
X1519610Y102323D03*
X1519862Y109410D03*
X1529720Y116496D03*
Y109410D03*
Y123583D03*
X1515779Y351594D03*
X1517456Y390223D03*
Y395179D03*
Y404396D03*
Y409352D03*
Y418569D03*
Y423525D03*
X1522448D03*
Y418569D03*
Y437699D03*
X1517456Y432743D03*
Y437699D03*
X1522448Y432743D03*
X1517456Y489895D03*
X1522448D03*
X1517456Y480677D03*
Y475721D03*
X1522448Y480677D03*
Y475721D03*
X1517456Y494851D03*
X1522448D03*
X1517456Y519855D03*
X1522448D03*
X1517456Y538984D03*
Y524811D03*
Y534028D03*
X1522448Y524811D03*
X1519156Y596095D03*
X1516869Y594668D03*
X1518354Y592354D03*
X1518415Y589556D03*
X1519153Y599588D03*
X1516930Y597580D03*
X1519185Y615600D03*
X1519153Y607588D03*
X1523646Y634946D03*
X1517344Y896999D03*
X1515743Y888133D03*
X1517344Y903179D03*
X1517153Y908367D03*
X1516283Y912240D03*
X1519116D03*
X1523053Y912262D03*
X1523000Y923740D03*
X1526611Y921442D03*
X1525740Y928740D03*
X1527876Y939439D03*
X1528087Y936394D03*
X1524500Y949500D03*
X1525022Y957340D03*
X1530174Y956986D03*
X1525522Y971075D03*
X1523966Y980281D03*
X1515096Y997860D03*
X1531096D03*
X1519096D03*
X1523096D03*
X1516776Y1024954D03*
Y1012354D03*
X1519401Y1609207D03*
X1528062Y1609607D03*
Y1604876D03*
X1519401Y1613938D03*
Y1618669D03*
X1528062Y1614338D03*
X1547367Y44773D03*
X1547003Y94017D03*
X1543003D03*
X1546732Y101701D03*
X1547131Y110445D03*
Y115401D03*
X1537720Y116496D03*
Y109410D03*
Y102323D03*
X1547131Y129574D03*
X1537720Y130670D03*
Y123583D03*
X1547131Y124618D03*
X1537720Y137756D03*
X1545044Y151540D03*
X1548561Y188727D03*
X1538811Y226461D03*
X1542518Y226141D03*
X1538811Y228961D03*
Y231461D03*
X1546780Y229286D03*
X1538811Y223661D03*
X1545318Y226141D03*
X1542761Y236611D03*
X1545261D03*
X1546780Y231786D03*
X1542463Y248891D03*
X1544963D03*
X1539915Y288190D03*
X1542415Y285690D03*
X1539915D03*
X1542415Y288190D03*
X1545215D03*
Y285690D03*
X1534401Y293796D03*
X1541534Y322850D03*
X1541283Y354553D03*
X1536724Y1609207D03*
X1545385Y1609607D03*
Y1604876D03*
Y1614338D03*
X1536724Y1613938D03*
Y1618669D03*
X1532000Y1644980D03*
X1560080Y84140D03*
Y76140D03*
Y80140D03*
X1555012Y94017D03*
X1551003D03*
X1562525Y117557D03*
X1557533D03*
X1552123Y115401D03*
Y110445D03*
X1554282Y103783D03*
X1562525Y122513D03*
X1552123Y129574D03*
Y124618D03*
X1557533Y131731D03*
Y122513D03*
X1562525Y131731D03*
X1560624Y146461D03*
X1557533Y136687D03*
X1562525D03*
X1559526Y152367D03*
X1561226Y180572D03*
X1548694Y191941D03*
X1555194Y184619D03*
X1561226Y185165D03*
X1557174Y206760D03*
X1550473Y222212D03*
Y224712D03*
X1547761Y236611D03*
X1550388Y256535D03*
X1558388D03*
X1547463Y248891D03*
X1559418Y279208D03*
X1563522Y281307D03*
X1549441Y290755D03*
X1553441D03*
X1557441D03*
X1547972Y304906D03*
X1556151Y318596D03*
X1556294Y327814D03*
X1556437Y332022D03*
X1556380Y336917D03*
X1556498Y340958D03*
X1556353Y345636D03*
X1554403Y352363D03*
X1556429Y389154D03*
X1563248D03*
X1548629D03*
Y403327D03*
Y410413D03*
X1556429Y396240D03*
X1557708Y404911D03*
X1561778Y396240D03*
X1548629D03*
X1556662Y412571D03*
X1557849Y426299D03*
X1548629Y417500D03*
Y424587D03*
Y438760D03*
Y431673D03*
X1558160Y445847D03*
X1548629D03*
X1556429Y467539D03*
X1548629D03*
X1556429Y474626D03*
X1548629D03*
Y488799D03*
X1556690Y480828D03*
X1548629Y481713D03*
Y495886D03*
X1558640Y498834D03*
X1548629Y511673D03*
Y518760D03*
X1562089Y516841D03*
X1556429Y518760D03*
Y511673D03*
X1548629Y540020D03*
Y525847D03*
Y532933D03*
X1556429Y525847D03*
X1548629Y547106D03*
X1556914Y552872D03*
X1557036Y550123D03*
X1556359Y562443D03*
X1558668Y572334D03*
X1558127Y560675D03*
X1556900Y574102D03*
X1547910Y602197D03*
X1562385Y598400D03*
Y602400D03*
Y594400D03*
X1548374Y595108D03*
X1562385Y614400D03*
Y606400D03*
X1561535Y653161D03*
X1565132Y677843D03*
X1552000Y1644980D03*
X1574851Y91951D03*
X1573455Y117261D03*
X1565449Y103621D03*
X1565909Y180527D03*
X1569632Y192421D03*
X1565864Y185121D03*
X1565512Y288345D03*
X1568012Y293645D03*
Y290845D03*
Y288345D03*
X1565512Y293645D03*
Y290845D03*
X1574845Y338843D03*
X1571625Y333549D03*
X1574540Y389154D03*
X1579340Y396240D03*
Y403327D03*
Y410413D03*
X1574540Y396240D03*
Y403327D03*
Y410413D03*
X1566555Y414823D03*
X1565863Y422864D03*
X1579340Y417500D03*
Y424586D03*
X1574540Y417500D03*
Y424586D03*
X1565933Y429832D03*
X1565538Y436447D03*
X1574540Y438760D03*
X1579340Y431673D03*
Y438760D03*
X1574540Y431673D03*
X1567573Y447953D03*
X1579340Y445847D03*
X1574540D03*
X1566740Y467539D03*
X1574540D03*
X1565482Y472772D03*
X1574540Y474626D03*
X1579340D03*
Y488799D03*
X1574540D03*
X1566216Y487711D03*
X1566329Y479104D03*
X1574540Y481713D03*
X1579340Y481712D03*
Y495886D03*
X1574540D03*
X1566740D03*
X1579340Y518760D03*
X1574540Y511673D03*
Y518760D03*
X1565050Y511673D03*
X1574540Y540020D03*
X1579340D03*
Y532933D03*
Y525846D03*
X1574540Y525847D03*
Y532933D03*
Y547106D03*
Y554193D03*
X1577862Y554121D03*
X1575000Y565414D03*
Y567914D03*
Y570414D03*
Y572914D03*
Y575414D03*
X1565323Y577716D03*
X1574540Y602205D03*
Y595118D03*
X1579753Y599100D03*
X1578679Y613047D03*
X1578114Y607563D03*
X1574222Y629872D03*
X1574880Y645891D03*
X1571888Y649380D03*
X1569926Y668885D03*
X1575950Y662981D03*
X1570331Y691851D03*
X1575942Y705043D03*
X1572000Y1644980D03*
X1582822Y60922D03*
X1580327Y57448D03*
X1593204Y102249D03*
X1585204D03*
X1589204D03*
X1580986Y113394D03*
X1583635Y110784D03*
X1591229Y133298D03*
X1583229D03*
X1585376Y134579D03*
X1581162Y180665D03*
Y172665D03*
X1586504Y195176D03*
X1594304D03*
X1589004D03*
X1591123Y198883D03*
X1591504Y195176D03*
X1581194Y212864D03*
Y200864D03*
X1586364Y203393D03*
X1588864D03*
X1591123Y201683D03*
X1595052Y206838D03*
X1592552D03*
X1581194Y221864D03*
Y216864D03*
X1594548Y238589D03*
X1582951Y252371D03*
X1593290Y339876D03*
X1586640Y389153D03*
X1581840D03*
Y403326D03*
Y410413D03*
X1586640D03*
X1581840Y396240D03*
X1586640D03*
Y403326D03*
Y417499D03*
X1581840D03*
Y424586D03*
X1586640D03*
X1581840Y438760D03*
X1586640D03*
Y431673D03*
X1581840D03*
X1586640Y467539D03*
X1581840D03*
Y474626D03*
X1586640D03*
X1581840Y488799D03*
X1586640D03*
X1581840Y481712D03*
X1586640D03*
X1581840Y518760D03*
Y511673D03*
X1586640D03*
Y518760D03*
Y525846D03*
Y532933D03*
X1581840D03*
Y525846D03*
X1595185Y543925D03*
X1583720Y560500D03*
X1591610Y1469940D03*
X1591586Y1505130D03*
X1604301Y44773D03*
X1611622Y53597D03*
X1596221Y109172D03*
X1599221D03*
X1598228Y106495D03*
X1611672Y111255D03*
Y114655D03*
X1604372Y118342D03*
X1611672Y125428D03*
X1604372Y121742D03*
X1611672Y128828D03*
X1604372Y132515D03*
X1597962Y146012D03*
X1599868Y141228D03*
X1604372Y135915D03*
X1602756Y150847D03*
X1610504Y213539D03*
X1604724Y247292D03*
X1597514Y236121D03*
X1603950Y238689D03*
X1597433Y253198D03*
X1597006Y290417D03*
X1603664Y342596D03*
X1598223Y351003D03*
X1599127Y375587D03*
X1596714Y383003D03*
X1599527Y392718D03*
Y408718D03*
Y400718D03*
Y404718D03*
Y412718D03*
X1614338Y636842D03*
X1603363Y1460570D03*
X1597457Y1452556D03*
X1598500Y1472500D03*
X1606745Y1474242D03*
X1602580Y1483108D03*
X1598000Y1486000D03*
X1604000Y1516000D03*
X1600700Y1534300D03*
X1622434Y82984D03*
Y80384D03*
Y75184D03*
Y77784D03*
X1624988Y92849D03*
X1622434Y85584D03*
X1621972Y102323D03*
X1622224Y109410D03*
X1613972Y102323D03*
X1625952Y431029D03*
X1626260Y427017D03*
X1625018Y435029D03*
X1625938Y449873D03*
X1625565Y472579D03*
Y479666D03*
Y486752D03*
Y493839D03*
Y523800D03*
Y516713D03*
Y537973D03*
Y530886D03*
Y566752D03*
Y588013D03*
Y573839D03*
Y580926D03*
Y602186D03*
Y595099D03*
Y609272D03*
Y616359D03*
X1620244Y638125D03*
X1617843Y665140D03*
X1613110Y678462D03*
X1624148Y708258D03*
X1627455Y759489D03*
X1619612Y783152D03*
X1620359Y774830D03*
X1619569Y796035D03*
X1620755Y787530D03*
X1613235Y808466D03*
X1620479Y815730D03*
X1620072Y801630D03*
X1616255Y824405D03*
X1619859Y839519D03*
X1614200Y1519500D03*
X1614360Y1542860D03*
X1618600Y1532000D03*
X1631622Y53597D03*
X1631948Y103037D03*
X1632082Y116496D03*
Y109410D03*
X1640082Y116496D03*
Y109410D03*
Y102323D03*
X1632082Y123583D03*
X1640082Y130670D03*
Y123583D03*
Y137756D03*
X1641173Y231461D03*
Y223661D03*
Y226461D03*
X1644880Y226141D03*
X1641173Y228961D03*
X1644825Y248891D03*
X1644777Y288190D03*
X1642277Y285690D03*
X1644777D03*
X1642277Y288190D03*
X1636763Y293796D03*
X1634263D03*
X1632230Y330400D03*
X1635987Y335616D03*
X1630703Y350655D03*
X1636468Y345595D03*
X1636271Y410394D03*
Y403307D03*
X1637205Y440098D03*
Y437598D03*
Y435098D03*
Y432598D03*
Y430098D03*
X1637665Y458406D03*
Y451319D03*
X1637489Y462264D03*
X1632865Y465492D03*
X1637665D03*
Y472579D03*
X1632865D03*
X1630365D03*
Y479666D03*
X1632865D03*
X1637665Y479665D03*
Y486752D03*
X1630365D03*
X1632865D03*
X1630365Y493839D03*
X1637665D03*
X1632865Y509626D03*
Y516713D03*
X1630365D03*
Y523800D03*
X1632865D03*
X1637665Y523799D03*
Y516713D03*
Y509626D03*
X1630365Y530886D03*
X1637665D03*
X1632865D03*
X1637665Y537973D03*
X1630365D03*
X1637665Y559665D03*
Y566752D03*
X1630365D03*
X1632865D03*
Y559665D03*
Y573839D03*
X1630365Y580926D03*
X1632865D03*
X1637665D03*
Y588012D03*
X1630365Y588013D03*
X1632865Y588012D03*
X1637665Y573839D03*
X1630365D03*
X1632865Y602185D03*
X1630365Y602186D03*
X1637665Y602185D03*
Y595099D03*
X1632865D03*
X1630365D03*
Y616359D03*
X1632865Y609272D03*
X1630365D03*
X1637665Y616358D03*
Y609272D03*
X1637526Y699930D03*
X1637472Y717830D03*
X1631031Y732430D03*
X1628813Y727045D03*
X1631187Y750630D03*
X1629969Y740826D03*
X1644304Y891353D03*
X1650417Y5374D03*
X1649730Y24773D03*
Y44773D03*
X1649365Y94017D03*
X1657374D03*
X1653365D03*
X1645365D03*
X1649094Y101701D03*
X1659895Y117557D03*
X1654485Y110445D03*
Y115401D03*
X1649493Y110445D03*
Y115401D03*
X1656644Y103783D03*
X1659895Y122513D03*
Y131731D03*
X1654485Y124618D03*
Y129574D03*
X1649493Y124618D03*
Y129574D03*
X1659895Y136687D03*
X1647406Y151540D03*
X1651056Y191941D03*
X1657556Y184619D03*
X1650923Y188727D03*
X1659536Y206760D03*
X1647680Y226141D03*
X1649142Y229286D03*
X1652835Y222212D03*
Y224712D03*
X1645123Y236611D03*
X1650123D03*
X1647623D03*
X1649142Y231786D03*
X1647325Y248891D03*
X1649825D03*
X1660750Y256535D03*
X1652750D03*
X1647577Y285690D03*
Y288190D03*
X1655803Y290755D03*
X1651803D03*
X1659803D03*
X1645685Y390500D03*
X1655335Y381500D03*
X1655555Y430760D03*
X1655576Y433570D03*
X1655392Y437072D03*
X1655433Y439963D03*
X1655677Y443180D03*
X1655697Y454744D03*
X1655639Y452018D03*
X1653507Y470136D03*
X1645465Y466027D03*
X1655776Y465492D03*
X1655742Y460250D03*
X1655776Y472579D03*
X1645607Y475262D03*
Y489435D03*
X1655776Y486752D03*
Y479665D03*
X1645607Y482666D03*
X1645423Y495088D03*
X1655776Y493839D03*
X1646158Y514608D03*
X1646080Y522134D03*
X1645465Y509626D03*
X1655776D03*
Y516713D03*
X1646562Y535677D03*
X1646723Y529136D03*
X1652236Y537973D03*
X1654716Y525483D03*
X1654637Y532756D03*
X1645465Y559665D03*
X1645846Y565574D03*
X1655776Y559665D03*
Y566752D03*
X1645493Y574338D03*
X1655626Y579978D03*
X1655776Y573839D03*
X1645592Y616358D03*
X1655840Y608117D03*
X1656112Y768669D03*
X1657042Y773604D03*
X1645128Y929263D03*
X1645342Y962120D03*
X1657091Y990823D03*
X1649571Y983857D03*
X1657983Y1480867D03*
Y1496221D03*
Y1491490D03*
Y1485598D03*
Y1500952D03*
Y1511576D03*
Y1506845D03*
Y1516307D03*
X1649322Y1574167D03*
Y1578898D03*
X1657983Y1578498D03*
X1649322Y1583629D03*
X1657983Y1583229D03*
X1649322Y1594253D03*
X1657983Y1593853D03*
Y1587960D03*
X1649322Y1589522D03*
Y1609607D03*
X1657983Y1609207D03*
X1649322Y1598984D03*
X1657983Y1598584D03*
Y1603315D03*
X1649322Y1604876D03*
Y1614338D03*
X1657983Y1613938D03*
Y1618669D03*
X1652000Y1644980D03*
X1669319Y3001D03*
X1662442Y84140D03*
Y76140D03*
Y80140D03*
X1677213Y91951D03*
X1675817Y117261D03*
X1664887Y117557D03*
X1667811Y103621D03*
X1664887Y122513D03*
Y131731D03*
X1662986Y146461D03*
X1664887Y136687D03*
X1661888Y152367D03*
X1663588Y180572D03*
X1668271Y180527D03*
X1671994Y192421D03*
X1663588Y185165D03*
X1668226Y185121D03*
X1661780Y279208D03*
X1665884Y281307D03*
X1670374Y290845D03*
Y288345D03*
X1667874Y290845D03*
Y288345D03*
X1670374Y293645D03*
X1667874D03*
X1674226Y324139D03*
X1673203Y332017D03*
X1663760Y410394D03*
Y403307D03*
X1663576Y458406D03*
X1669767Y445908D03*
X1663576Y465492D03*
Y472579D03*
Y479665D03*
Y486752D03*
Y493839D03*
Y523799D03*
Y516713D03*
Y509626D03*
Y537973D03*
Y530886D03*
Y559665D03*
Y566752D03*
Y580925D03*
Y588012D03*
Y573839D03*
Y602185D03*
Y595099D03*
X1666645Y1481267D03*
X1675306Y1480867D03*
X1666645Y1487159D03*
Y1491890D03*
Y1496621D03*
X1675306Y1491490D03*
Y1485598D03*
Y1496221D03*
Y1511576D03*
X1666645Y1511976D03*
Y1507245D03*
Y1502514D03*
X1675306Y1506845D03*
Y1500952D03*
Y1516307D03*
Y1578498D03*
X1666645Y1574167D03*
Y1578898D03*
Y1583629D03*
X1675306Y1583229D03*
X1666645Y1589522D03*
Y1594253D03*
X1675306Y1593853D03*
Y1587960D03*
X1666645Y1604876D03*
Y1598984D03*
X1675306Y1609207D03*
Y1598584D03*
Y1603315D03*
X1666645Y1609607D03*
Y1614338D03*
X1675306Y1613938D03*
Y1618669D03*
X1672000Y1644980D03*
X1689319Y3001D03*
X1685184Y60922D03*
X1680020Y55513D03*
X1695566Y102249D03*
X1683348Y113394D03*
X1685997Y110784D03*
X1687566Y102249D03*
X1691566D03*
X1686171Y130898D03*
X1693591Y133298D03*
X1687738Y134579D03*
X1683524Y172665D03*
Y180665D03*
X1691366Y195176D03*
X1688866D03*
X1693485Y198883D03*
X1683556Y200864D03*
Y212864D03*
X1691226Y203393D03*
X1693485Y201683D03*
X1688726Y203393D03*
X1683556Y221864D03*
Y216864D03*
X1685313Y252371D03*
X1681273Y316731D03*
X1691117Y321649D03*
X1687164Y336324D03*
X1678072Y342319D03*
X1680518Y385912D03*
Y393924D03*
Y389912D03*
Y401924D03*
X1689757Y485657D03*
Y515617D03*
Y510661D03*
Y524835D03*
Y529791D03*
X1692028Y550137D03*
X1689757Y565657D03*
Y560701D03*
Y589047D03*
Y574874D03*
Y579830D03*
Y603221D03*
Y594003D03*
Y608177D03*
X1693000Y626912D03*
X1683968Y1481267D03*
X1692629Y1480867D03*
X1683968Y1487159D03*
Y1491890D03*
Y1496621D03*
X1692629Y1491490D03*
Y1485598D03*
Y1496221D03*
X1683968Y1502514D03*
Y1511976D03*
X1692629Y1506845D03*
Y1500952D03*
Y1511576D03*
X1683968Y1507245D03*
X1692629Y1516307D03*
X1683968Y1574167D03*
Y1578898D03*
X1692629Y1578498D03*
X1683968Y1583629D03*
Y1589522D03*
Y1594253D03*
X1692629Y1583229D03*
Y1593853D03*
Y1587960D03*
X1683968Y1598984D03*
X1692629Y1609207D03*
Y1598584D03*
Y1603315D03*
X1683968Y1609607D03*
Y1604876D03*
Y1614338D03*
X1692629Y1613938D03*
Y1618669D03*
X1692000Y1644980D03*
X1705303Y4470D03*
X1706664Y24774D03*
Y44774D03*
X1698583Y109172D03*
X1701583D03*
X1700590Y106495D03*
X1706734Y118342D03*
Y132515D03*
Y121742D03*
X1700324Y146012D03*
X1702230Y141228D03*
X1706734Y135915D03*
X1705118Y150847D03*
X1696666Y195176D03*
X1693866D03*
X1697414Y206838D03*
X1694914D03*
X1707086Y247292D03*
X1699876Y236121D03*
X1696910Y238589D03*
X1706312Y238689D03*
X1699795Y253198D03*
X1701495Y289735D03*
X1695142Y303839D03*
X1694749Y466528D03*
Y471484D03*
X1700159Y473640D03*
X1705151D03*
Y487813D03*
X1700159D03*
X1705151Y478596D03*
X1694749Y480701D03*
X1700159Y478596D03*
X1694749Y485657D03*
X1700159Y492769D03*
X1705151D03*
Y517774D03*
Y522730D03*
X1694749Y510661D03*
Y515617D03*
X1700159Y517774D03*
Y522730D03*
Y536903D03*
X1705151D03*
Y531947D03*
X1694749Y524835D03*
Y529791D03*
X1700159Y531947D03*
X1705151Y572769D03*
X1700159D03*
X1705151Y567813D03*
X1698839Y564843D03*
X1700159Y567813D03*
X1694749Y565657D03*
Y560701D03*
Y579830D03*
X1705151Y586943D03*
Y581987D03*
X1694749Y589047D03*
X1700159Y586943D03*
Y581987D03*
X1694749Y574874D03*
Y603221D03*
X1700159Y601116D03*
X1705151D03*
Y596160D03*
X1700159D03*
X1694749Y594003D03*
X1705151Y615289D03*
X1700159Y610333D03*
X1694749Y608177D03*
X1700159Y615289D03*
X1705151Y610333D03*
X1701290Y1481267D03*
Y1487159D03*
Y1491890D03*
Y1496621D03*
Y1507245D03*
Y1502514D03*
Y1511976D03*
Y1574167D03*
Y1578898D03*
Y1583629D03*
Y1589522D03*
Y1594253D03*
Y1609607D03*
Y1604876D03*
Y1598984D03*
Y1614338D03*
X1713985Y53598D03*
X1724796Y82984D03*
Y77784D03*
Y80384D03*
Y75184D03*
Y85584D03*
X1716334Y102323D03*
X1724334D03*
X1724586Y109410D03*
X1714034Y111255D03*
Y114655D03*
Y125428D03*
Y128828D03*
X1712866Y213539D03*
X1725746Y377173D03*
X1723964Y370935D03*
X1718710Y447486D03*
X1716310Y458334D03*
Y454334D03*
X1724930Y491118D03*
Y488618D03*
Y493618D03*
Y496118D03*
X1710174Y553101D03*
X1718613Y1476537D03*
Y1481268D03*
X1709952Y1480867D03*
Y1491490D03*
Y1485598D03*
Y1496221D03*
X1718613Y1491891D03*
Y1487160D03*
Y1496622D03*
Y1502515D03*
Y1511977D03*
X1709952Y1506845D03*
Y1500952D03*
Y1511576D03*
X1718613Y1507246D03*
X1709952Y1516307D03*
Y1578498D03*
X1718613Y1578898D03*
Y1574167D03*
Y1589522D03*
X1709952Y1583229D03*
X1718613Y1583629D03*
X1709952Y1593853D03*
Y1587960D03*
X1718613Y1594253D03*
Y1609607D03*
Y1598984D03*
Y1604876D03*
X1709952Y1609207D03*
Y1598584D03*
Y1603315D03*
Y1618669D03*
X1718613Y1614338D03*
X1709952Y1613938D03*
X1712000Y1644980D03*
X1733985Y53598D03*
X1727350Y92849D03*
X1734310Y103037D03*
X1734444Y116496D03*
Y109410D03*
Y123583D03*
X1743535Y223661D03*
X1739125Y293796D03*
X1736625D03*
X1734826Y376499D03*
X1733027Y392228D03*
X1728433Y392183D03*
X1739847Y409016D03*
X1735811Y409032D03*
X1732494Y402867D03*
X1728478Y396866D03*
X1733071D03*
X1729302Y439718D03*
Y442518D03*
X1739179Y449118D03*
Y446318D03*
X1738824Y452740D03*
X1736214Y450091D03*
X1737703Y472189D03*
X1740542Y468088D03*
Y465288D03*
X1736592Y487570D03*
Y490070D03*
X1728038Y491870D03*
X1730538D03*
X1733147Y493758D03*
Y496258D03*
X1732000Y1644980D03*
X1752778Y5374D03*
X1752091Y24773D03*
Y44773D03*
X1755727Y94017D03*
X1751456Y101701D03*
X1747727Y94017D03*
X1751727D03*
X1742444Y102323D03*
Y116496D03*
Y109410D03*
X1751855Y110445D03*
Y115401D03*
X1756847D03*
Y110445D03*
X1742444Y130670D03*
Y123583D03*
X1751855Y129574D03*
Y124618D03*
X1756847D03*
Y129574D03*
X1742444Y137756D03*
X1753418Y191941D03*
X1753285Y188727D03*
X1743535Y226461D03*
X1747242Y226141D03*
X1755197Y224712D03*
X1743535Y228961D03*
Y231461D03*
X1751504Y229286D03*
X1755197Y222212D03*
X1750042Y226141D03*
X1752485Y236611D03*
X1749985D03*
X1751504Y231786D03*
X1747485Y236611D03*
X1747187Y248891D03*
X1749687D03*
X1752187D03*
X1755112Y256535D03*
X1749939Y288190D03*
X1747139D03*
X1744639D03*
X1749939Y285690D03*
X1744639D03*
X1747139D03*
X1758165Y290755D03*
X1754165D03*
X1744524Y370010D03*
X1756497Y370976D03*
X1747561Y385161D03*
X1748252Y395248D03*
X1756844Y450041D03*
Y452841D03*
Y455641D03*
X1747179Y449118D03*
Y446318D03*
X1747359Y454309D03*
Y458309D03*
Y462309D03*
X1758401Y484882D03*
X1753474Y542699D03*
X1757402Y825111D03*
Y820155D03*
X1744937Y912517D03*
X1747937D03*
X1750751Y910785D03*
X1748081Y984379D03*
X1753860Y997271D03*
X1758583Y1581027D03*
X1750685Y1618504D03*
X1756422Y1640303D03*
X1752000Y1644980D03*
X1765559Y3001D03*
X1764804Y84140D03*
Y76140D03*
Y80140D03*
X1759736Y94017D03*
X1767249Y117557D03*
X1770173Y103621D03*
X1759006Y103783D03*
X1762257Y117557D03*
Y122513D03*
Y131731D03*
X1767249Y122513D03*
Y131731D03*
X1762257Y136687D03*
X1767249D03*
X1765950Y180572D03*
X1770633Y180527D03*
X1774356Y192421D03*
X1759918Y184619D03*
X1770588Y185121D03*
X1765950Y185165D03*
X1761898Y206760D03*
X1763112Y256535D03*
X1764142Y279208D03*
X1768246Y281307D03*
X1772736Y293645D03*
X1770236D03*
Y290845D03*
Y288345D03*
X1772736Y290845D03*
Y288345D03*
X1762165Y290755D03*
X1760497Y371070D03*
X1765497Y370899D03*
X1766204Y398949D03*
X1770778Y402642D03*
X1773278D03*
X1767633Y409904D03*
Y407104D03*
X1763704Y401949D03*
X1767953Y413611D03*
X1770453D03*
X1772953D03*
X1772893Y423944D03*
X1770393D03*
X1767893D03*
X1765093D03*
X1765153Y413611D03*
X1766837Y450041D03*
Y452841D03*
Y455641D03*
X1765097Y466409D03*
X1765083Y487382D03*
X1764912Y482382D03*
X1768575Y479560D03*
X1765006Y478382D03*
X1761953Y706827D03*
X1772768Y818696D03*
X1761953Y865160D03*
X1773600Y888100D03*
X1773614Y895275D03*
X1773600Y902800D03*
X1770680Y926322D03*
X1763818Y926241D03*
X1772599Y993053D03*
X1762898Y992883D03*
X1758881Y995633D03*
X1774339Y1437975D03*
X1774216Y1470165D03*
X1765294Y1575434D03*
X1759092Y1588137D03*
X1767142Y1588219D03*
X1764422Y1640303D03*
X1772000Y1644980D03*
X1788884Y59871D03*
X1782382Y55513D03*
X1779575Y91951D03*
X1778179Y117261D03*
X1785886Y172665D03*
Y180665D03*
X1785918Y200864D03*
Y212864D03*
Y216864D03*
Y221864D03*
X1790533Y303750D03*
X1790136Y399161D03*
Y401661D03*
Y396661D03*
X1778103Y399161D03*
Y401661D03*
Y396661D03*
X1783028Y408240D03*
X1785528D03*
X1780528D03*
X1783107Y424240D03*
X1780646Y420393D03*
X1785646D03*
X1783146D03*
X1783107Y426740D03*
X1786713Y455039D03*
X1790014Y468607D03*
X1783014Y474513D03*
X1784602Y564092D03*
X1778801Y836469D03*
X1782600Y874500D03*
X1788400Y888100D03*
X1781000Y888087D03*
X1788396Y895066D03*
X1788300Y902800D03*
X1780665Y902796D03*
X1786256Y927626D03*
X1784306Y924601D03*
X1786256Y930626D03*
X1781263Y964660D03*
X1784763D03*
X1789363Y969160D03*
X1775998Y1074707D03*
Y1072207D03*
X1781198Y1074707D03*
X1778598D03*
X1783798D03*
Y1072207D03*
X1778598D03*
X1781198D03*
X1790736Y1072090D03*
Y1074590D03*
X1780326Y1089851D03*
X1777726D03*
X1782926D03*
Y1092351D03*
X1777726D03*
X1780326D03*
X1775126Y1089851D03*
Y1092351D03*
X1790639Y1082585D03*
X1790572Y1085152D03*
X1779581Y1222200D03*
Y1219400D03*
Y1216600D03*
Y1213800D03*
X1782581Y1222200D03*
Y1219400D03*
Y1216600D03*
Y1213800D03*
X1780397Y1237469D03*
Y1230569D03*
Y1228069D03*
X1779581Y1225000D03*
X1782581D03*
X1785961Y1224892D03*
X1780397Y1234969D03*
Y1241869D03*
Y1244369D03*
Y1248769D03*
Y1251269D03*
X1791099Y1260421D03*
X1779868Y1446668D03*
X1786564Y1478858D03*
X1777131Y1604357D03*
X1776422Y1640303D03*
X1791570Y74535D03*
X1804993Y297591D03*
X1804984Y433975D03*
X1803570Y436164D03*
X1793149Y662810D03*
X1798705Y718793D03*
X1791302Y829031D03*
X1794163Y968760D03*
X1797963D03*
X1792263Y962960D03*
X1805463Y969260D03*
X1801963Y969160D03*
X1798163Y982360D03*
X1793563D03*
X1805863Y980760D03*
X1795936Y1072090D03*
X1793336D03*
X1798536D03*
Y1074590D03*
X1793336D03*
X1795936D03*
X1796607Y1200108D03*
X1801285Y1213373D03*
X1801147Y1208555D03*
X1802844Y1227695D03*
X1793976Y1440762D03*
X1807270Y1468535D03*
X1793879Y1472952D03*
X1792000Y1644980D03*
X1822983Y346053D03*
Y366053D03*
Y386053D03*
Y406053D03*
Y426053D03*
Y446053D03*
Y466053D03*
Y486053D03*
Y506053D03*
Y526053D03*
Y546053D03*
Y566053D03*
Y586053D03*
Y606053D03*
Y626053D03*
Y646053D03*
Y666053D03*
Y686053D03*
Y706053D03*
Y726053D03*
Y746053D03*
Y766053D03*
Y786053D03*
Y806053D03*
Y826053D03*
Y846053D03*
Y866053D03*
Y886053D03*
Y906053D03*
Y926053D03*
Y946053D03*
X1816322Y977215D03*
X1807663Y966660D03*
Y963860D03*
X1809897Y1237285D03*
Y1230385D03*
Y1232885D03*
Y1239785D03*
Y1244185D03*
Y1246685D03*
X1807393Y1436345D03*
X1812000Y1644980D03*
X1825559Y3001D03*
X1836543Y4470D03*
X1837904Y24774D03*
Y44774D03*
Y64774D03*
Y84774D03*
Y104774D03*
Y124774D03*
Y144774D03*
Y164774D03*
Y184774D03*
Y204774D03*
Y224774D03*
Y244774D03*
Y264774D03*
Y284774D03*
Y304774D03*
X1837728Y324733D03*
X1830094Y333210D03*
X1830472Y960970D03*
X1837937Y973244D03*
Y993244D03*
Y1013244D03*
Y1033244D03*
Y1053244D03*
Y1073244D03*
Y1093244D03*
Y1113244D03*
Y1133244D03*
Y1153244D03*
Y1173244D03*
Y1193244D03*
Y1213244D03*
Y1253244D03*
Y1273244D03*
Y1293244D03*
Y1313244D03*
Y1333244D03*
Y1353244D03*
Y1373244D03*
Y1393244D03*
Y1433244D03*
Y1453244D03*
Y1473244D03*
Y1493244D03*
Y1513244D03*
Y1533244D03*
Y1553244D03*
Y1573244D03*
X1837933Y1636171D03*
X1832000Y1644980D03*
G54D11*
X13780Y1226024D03*
X1450591Y1086654D03*
X1761614Y1215000D03*
X1827165Y1235630D03*
G54D20*
X343286Y1738583D03*
Y1728583D03*
X595386D03*
Y1738583D03*
X629711Y1775438D03*
Y1785438D03*
X881761Y1775438D03*
Y1785438D03*
G54D30*
G01X433216Y1148477D02*
Y1129199D01*
X432838Y1128821D01*
G01X495236Y1129094D02*
X495622D01*
X498803Y1132275D01*
Y1148477D01*
X497228Y1150052D01*
X434791D01*
X433216Y1148477D01*
G01X1347390D02*
Y1132403D01*
X1343725Y1128738D01*
G01X1347390Y1148477D02*
X1348965Y1150052D01*
X1411114D01*
X1412321Y1148845D01*
Y1129750D01*
X1413177Y1128894D01*
G54D12*
X23622Y1604724D03*
X62205Y765197D03*
X74016Y333464D03*
X102224Y70866D03*
X409488Y1604724D03*
X433130Y70866D03*
X463387Y286221D03*
X463386Y765197D03*
X661674Y23622D03*
X785039Y1547638D03*
X890217Y23622D03*
X1118760D03*
X1347303Y70866D03*
X1377559Y286220D03*
X1431457Y1604724D03*
X1575846Y23622D03*
X1766929Y333464D03*
X1778740Y765197D03*
X1795010Y23622D03*
X1817323Y1604724D03*
G54D21*
X420661Y1119422D03*
X423141Y1113822D03*
Y1119422D03*
X418181Y1113822D03*
Y1119422D03*
X420661Y1113822D03*
X455269Y1119422D03*
X450309Y1113822D03*
Y1119422D03*
X452789Y1113822D03*
Y1119422D03*
X455269Y1113822D03*
X488728Y1119422D03*
X483768Y1113822D03*
X486248D03*
Y1119422D03*
X483768D03*
X488728Y1113822D03*
X518376D03*
Y1119422D03*
X520856Y1113822D03*
Y1119422D03*
X515896Y1113822D03*
Y1119422D03*
X1332355Y1113822D03*
Y1119422D03*
X1334835Y1113822D03*
Y1119422D03*
X1337315Y1113822D03*
Y1119422D03*
X1366963D03*
Y1113822D03*
X1364483Y1119422D03*
Y1113822D03*
X1369443Y1119422D03*
Y1113822D03*
X1397942Y1119422D03*
X1400422D03*
Y1113822D03*
X1397942D03*
X1402902Y1119422D03*
Y1113822D03*
X1432550Y1119422D03*
Y1113822D03*
X1430070Y1119422D03*
Y1113822D03*
X1435030Y1119422D03*
Y1113822D03*
G54D31*
G01X-20602Y-468335D02*
Y-543335D01*
X479398D01*
Y-468335D01*
X-20602D01*
G01X-8602Y-533335D02*
Y-538335D01*
G01X-10059Y-533335D02*
X-7145D01*
G01X-2235Y-538335D02*
X-4769D01*
Y-533335D01*
X-2235D01*
G01X-3249Y-535752D02*
X-4769D01*
G01X331Y-533335D02*
Y-538335D01*
X2865D01*
G01X6698Y-538502D02*
X6571Y-538418D01*
Y-538252D01*
X6698Y-538168D01*
X6825Y-538252D01*
Y-538418D01*
X6698Y-538502D01*
G01Y-536252D02*
X6571Y-536168D01*
Y-536002D01*
X6698Y-535918D01*
X6825Y-536002D01*
Y-536168D01*
X6698Y-536252D01*
G01X11481Y-540002D02*
X10848Y-539168D01*
X10531Y-538335D01*
Y-535002D01*
X10848Y-534168D01*
X11481Y-533335D01*
G01X16898D02*
X16391Y-533502D01*
X16011Y-533918D01*
X15758Y-534418D01*
X15568Y-535085D01*
X15505Y-535835D01*
X15568Y-536585D01*
X15758Y-537252D01*
X16011Y-537752D01*
X16391Y-538168D01*
X16898Y-538335D01*
X17405Y-538168D01*
X17785Y-537752D01*
X18038Y-537252D01*
X18228Y-536585D01*
X18291Y-535835D01*
X18228Y-535085D01*
X18038Y-534418D01*
X17785Y-533918D01*
X17405Y-533502D01*
X16898Y-533335D01*
G01X20605Y-537335D02*
X20985Y-537918D01*
X21491Y-538252D01*
X22061Y-538335D01*
X22568Y-538252D01*
X23075Y-537835D01*
X23391Y-537335D01*
X23455Y-536835D01*
X23328Y-536252D01*
X22885Y-535835D01*
X22441Y-535668D01*
X21871D01*
G01X22441D02*
X22821Y-535418D01*
X23138Y-535002D01*
X23265Y-534502D01*
X23138Y-534002D01*
X22821Y-533585D01*
X22251Y-533335D01*
X21681Y-533418D01*
X21111Y-533752D01*
G01X27415Y-540002D02*
X28048Y-539168D01*
X28365Y-538335D01*
Y-535002D01*
X28048Y-534168D01*
X27415Y-533335D01*
G01X30805Y-537335D02*
X31185Y-537918D01*
X31691Y-538252D01*
X32261Y-538335D01*
X32768Y-538252D01*
X33275Y-537835D01*
X33591Y-537335D01*
X33655Y-536835D01*
X33528Y-536252D01*
X33085Y-535835D01*
X32641Y-535668D01*
X32071D01*
G01X32641D02*
X33021Y-535418D01*
X33338Y-535002D01*
X33465Y-534502D01*
X33338Y-534002D01*
X33021Y-533585D01*
X32451Y-533335D01*
X31881Y-533418D01*
X31311Y-533752D01*
G01X36095Y-534168D02*
X36475Y-533668D01*
X36918Y-533418D01*
X37425Y-533335D01*
X38058Y-533502D01*
X38501Y-533918D01*
X38628Y-534418D01*
X38565Y-534918D01*
X38311Y-535335D01*
X37045Y-536168D01*
X36475Y-536752D01*
X36095Y-537585D01*
X35968Y-538335D01*
X38628D01*
G01X42271D02*
X42398Y-537252D01*
X42588Y-536335D01*
X42841Y-535502D01*
X43158Y-534585D01*
X43665Y-533335D01*
X41131D01*
G01X46675Y-536668D02*
X48321D01*
G01X51395Y-534168D02*
X51775Y-533668D01*
X52218Y-533418D01*
X52725Y-533335D01*
X53358Y-533502D01*
X53801Y-533918D01*
X53928Y-534418D01*
X53865Y-534918D01*
X53611Y-535335D01*
X52345Y-536168D01*
X51775Y-536752D01*
X51395Y-537585D01*
X51268Y-538335D01*
X53928D01*
G01X56305Y-537335D02*
X56685Y-537918D01*
X57191Y-538252D01*
X57761Y-538335D01*
X58268Y-538252D01*
X58775Y-537835D01*
X59091Y-537335D01*
X59155Y-536835D01*
X59028Y-536252D01*
X58585Y-535835D01*
X58141Y-535668D01*
X57571D01*
G01X58141D02*
X58521Y-535418D01*
X58838Y-535002D01*
X58965Y-534502D01*
X58838Y-534002D01*
X58521Y-533585D01*
X57951Y-533335D01*
X57381Y-533418D01*
X56811Y-533752D01*
G01X63558Y-538335D02*
Y-533335D01*
X61215Y-536918D01*
X64381D01*
G01X66505Y-537585D02*
X66885Y-538002D01*
X67328Y-538252D01*
X67898Y-538335D01*
X68468Y-538168D01*
X68911Y-537835D01*
X69228Y-537252D01*
X69291Y-536585D01*
X69165Y-535918D01*
X68848Y-535502D01*
X68405Y-535168D01*
X67961Y-535085D01*
X67518Y-535168D01*
X66948Y-535502D01*
X67138Y-533335D01*
X68848D01*
G01X76895Y-538335D02*
Y-533335D01*
X79301D01*
G01X78415Y-535752D02*
X76895D01*
G01X81615Y-538335D02*
X83198Y-533335D01*
X84781Y-538335D01*
G01X84211Y-536585D02*
X82185D01*
G01X86968Y-538335D02*
X89628Y-533335D01*
G01X86968D02*
X89628Y-538335D01*
G01X93398Y-538502D02*
X93271Y-538418D01*
Y-538252D01*
X93398Y-538168D01*
X93525Y-538252D01*
Y-538418D01*
X93398Y-538502D01*
G01Y-536252D02*
X93271Y-536168D01*
Y-536002D01*
X93398Y-535918D01*
X93525Y-536002D01*
Y-536168D01*
X93398Y-536252D01*
G01X98181Y-540002D02*
X97548Y-539168D01*
X97231Y-538335D01*
Y-535002D01*
X97548Y-534168D01*
X98181Y-533335D01*
G01X103598D02*
X103091Y-533502D01*
X102711Y-533918D01*
X102458Y-534418D01*
X102268Y-535085D01*
X102205Y-535835D01*
X102268Y-536585D01*
X102458Y-537252D01*
X102711Y-537752D01*
X103091Y-538168D01*
X103598Y-538335D01*
X104105Y-538168D01*
X104485Y-537752D01*
X104738Y-537252D01*
X104928Y-536585D01*
X104991Y-535835D01*
X104928Y-535085D01*
X104738Y-534418D01*
X104485Y-533918D01*
X104105Y-533502D01*
X103598Y-533335D01*
G01X107305Y-537335D02*
X107685Y-537918D01*
X108191Y-538252D01*
X108761Y-538335D01*
X109268Y-538252D01*
X109775Y-537835D01*
X110091Y-537335D01*
X110155Y-536835D01*
X110028Y-536252D01*
X109585Y-535835D01*
X109141Y-535668D01*
X108571D01*
G01X109141D02*
X109521Y-535418D01*
X109838Y-535002D01*
X109965Y-534502D01*
X109838Y-534002D01*
X109521Y-533585D01*
X108951Y-533335D01*
X108381Y-533418D01*
X107811Y-533752D01*
G01X114115Y-540002D02*
X114748Y-539168D01*
X115065Y-538335D01*
Y-535002D01*
X114748Y-534168D01*
X114115Y-533335D01*
G01X117505Y-537335D02*
X117885Y-537918D01*
X118391Y-538252D01*
X118961Y-538335D01*
X119468Y-538252D01*
X119975Y-537835D01*
X120291Y-537335D01*
X120355Y-536835D01*
X120228Y-536252D01*
X119785Y-535835D01*
X119341Y-535668D01*
X118771D01*
G01X119341D02*
X119721Y-535418D01*
X120038Y-535002D01*
X120165Y-534502D01*
X120038Y-534002D01*
X119721Y-533585D01*
X119151Y-533335D01*
X118581Y-533418D01*
X118011Y-533752D01*
G01X122921Y-537752D02*
X123365Y-538168D01*
X123871Y-538335D01*
X124378Y-538168D01*
X124821Y-537668D01*
X125138Y-536918D01*
X125265Y-536168D01*
Y-535252D01*
X125138Y-534502D01*
X124821Y-533835D01*
X124441Y-533502D01*
X123998Y-533335D01*
X123491Y-533502D01*
X123111Y-533835D01*
X122858Y-534335D01*
X122731Y-535002D01*
X122858Y-535585D01*
X123175Y-536168D01*
X123555Y-536502D01*
X123998Y-536585D01*
X124505Y-536418D01*
X124885Y-536002D01*
X125265Y-535252D01*
G01X128971Y-538335D02*
X129098Y-537252D01*
X129288Y-536335D01*
X129541Y-535502D01*
X129858Y-534585D01*
X130365Y-533335D01*
X127831D01*
G01X133375Y-536668D02*
X135021D01*
G01X137905Y-537335D02*
X138285Y-537918D01*
X138791Y-538252D01*
X139361Y-538335D01*
X139868Y-538252D01*
X140375Y-537835D01*
X140691Y-537335D01*
X140755Y-536835D01*
X140628Y-536252D01*
X140185Y-535835D01*
X139741Y-535668D01*
X139171D01*
G01X139741D02*
X140121Y-535418D01*
X140438Y-535002D01*
X140565Y-534502D01*
X140438Y-534002D01*
X140121Y-533585D01*
X139551Y-533335D01*
X138981Y-533418D01*
X138411Y-533752D01*
G01X143195Y-536252D02*
X143638Y-535668D01*
X144018Y-535335D01*
X144525Y-535168D01*
X144968Y-535335D01*
X145285Y-535668D01*
X145538Y-536168D01*
X145601Y-536752D01*
X145538Y-537252D01*
X145285Y-537752D01*
X144905Y-538168D01*
X144461Y-538335D01*
X143955Y-538168D01*
X143511Y-537668D01*
X143258Y-536918D01*
X143195Y-536085D01*
X143321Y-535002D01*
X143511Y-534418D01*
X143828Y-533835D01*
X144271Y-533418D01*
X144715Y-533335D01*
X145158Y-533502D01*
X145475Y-533918D01*
G01X149498Y-538335D02*
Y-533335D01*
X148738Y-534335D01*
G01Y-538335D02*
X150258D01*
G01X155358D02*
Y-533335D01*
X153015Y-536918D01*
X156181D01*
G01X174398Y-468335D02*
Y-543335D01*
G01Y-518335D02*
X277398D01*
Y-493335D01*
G01X174398D02*
X277398D01*
G01Y-468335D02*
Y-543335D01*
G01X279398Y-468335D02*
Y-543335D01*
G01X284905Y-528335D02*
Y-523335D01*
X286171D01*
X286678Y-523585D01*
X287058Y-523918D01*
X287375Y-524418D01*
X287628Y-525002D01*
X287691Y-525835D01*
X287628Y-526668D01*
X287375Y-527252D01*
X287058Y-527752D01*
X286678Y-528085D01*
X286171Y-528335D01*
X284905D01*
G01X289815D02*
X291398Y-523335D01*
X292981Y-528335D01*
G01X292411Y-526585D02*
X290385D01*
G01X296498Y-523335D02*
Y-528335D01*
G01X295041Y-523335D02*
X297955D01*
G01X302865Y-528335D02*
X300331D01*
Y-523335D01*
X302865D01*
G01X301851Y-525752D02*
X300331D01*
G01X306698Y-528502D02*
X306571Y-528418D01*
Y-528252D01*
X306698Y-528168D01*
X306825Y-528252D01*
Y-528418D01*
X306698Y-528502D01*
G01Y-526252D02*
X306571Y-526168D01*
Y-526002D01*
X306698Y-525918D01*
X306825Y-526002D01*
Y-526168D01*
X306698Y-526252D01*
G01X279398Y-518335D02*
X479398D01*
G01X285031Y-503335D02*
Y-498335D01*
X286551D01*
X287058Y-498585D01*
X287438Y-499168D01*
X287565Y-499835D01*
X287438Y-500502D01*
X287121Y-501002D01*
X286551Y-501252D01*
X285031D01*
G01X290258Y-503502D02*
X292538Y-498335D01*
G01X295041Y-503335D02*
Y-498335D01*
X297955Y-503335D01*
Y-498335D01*
G01X301598Y-503502D02*
X301471Y-503418D01*
Y-503252D01*
X301598Y-503168D01*
X301725Y-503252D01*
Y-503418D01*
X301598Y-503502D01*
G01Y-501252D02*
X301471Y-501168D01*
Y-501002D01*
X301598Y-500918D01*
X301725Y-501002D01*
Y-501168D01*
X301598Y-501252D01*
G01X279398Y-493335D02*
X479398D01*
G01X285031Y-478335D02*
Y-473335D01*
X286551D01*
X287058Y-473585D01*
X287438Y-474168D01*
X287565Y-474835D01*
X287438Y-475502D01*
X287121Y-476002D01*
X286551Y-476252D01*
X285031D01*
G01X290131Y-478335D02*
Y-473335D01*
X291715D01*
X292221Y-473585D01*
X292538Y-473918D01*
X292665Y-474585D01*
X292538Y-475252D01*
X292158Y-475668D01*
X291715Y-475918D01*
X290131D01*
G01X291715D02*
X292665Y-478335D01*
G01X296498D02*
X295991Y-478252D01*
X295548Y-477918D01*
X295168Y-477418D01*
X294915Y-476835D01*
X294788Y-476168D01*
Y-475502D01*
X294915Y-474835D01*
X295168Y-474252D01*
X295548Y-473752D01*
X295991Y-473418D01*
X296498Y-473335D01*
X297005Y-473418D01*
X297448Y-473752D01*
X297828Y-474252D01*
X298081Y-474835D01*
X298208Y-475502D01*
Y-476168D01*
X298081Y-476835D01*
X297828Y-477418D01*
X297448Y-477918D01*
X297005Y-478252D01*
X296498Y-478335D01*
G01X300331Y-477335D02*
X300648Y-477835D01*
X301028Y-478168D01*
X301471Y-478335D01*
X301978Y-478168D01*
X302358Y-477835D01*
X302738Y-477335D01*
X302865Y-476668D01*
Y-473335D01*
G01X307965Y-478335D02*
X305431D01*
Y-473335D01*
X307965D01*
G01X306951Y-475752D02*
X305431D01*
G01X313191Y-473752D02*
X312811Y-473502D01*
X312368Y-473335D01*
X311861D01*
X311291Y-473585D01*
X310848Y-474002D01*
X310531Y-474502D01*
X310278Y-475335D01*
X310215Y-476085D01*
X310341Y-476835D01*
X310531Y-477335D01*
X310911Y-477835D01*
X311355Y-478168D01*
X311798Y-478335D01*
X312241D01*
X312685Y-478168D01*
X313065Y-477918D01*
X313381Y-477585D01*
G01X316898Y-473335D02*
Y-478335D01*
G01X315441Y-473335D02*
X318355D01*
G01X321998Y-478502D02*
X321871Y-478418D01*
Y-478252D01*
X321998Y-478168D01*
X322125Y-478252D01*
Y-478418D01*
X321998Y-478502D01*
G01Y-476252D02*
X321871Y-476168D01*
Y-476002D01*
X321998Y-475918D01*
X322125Y-476002D01*
Y-476168D01*
X321998Y-476252D01*
G01X394258Y-543563D02*
Y-518563D01*
G01X397031Y-520835D02*
Y-525835D01*
X399565D01*
G01X402638Y-520835D02*
X404158D01*
G01X403398D02*
Y-525835D01*
G01X402638D02*
X404158D01*
G01X409005Y-523168D02*
X409258Y-522918D01*
X409448Y-522502D01*
X409575Y-521918D01*
X409448Y-521418D01*
X409195Y-521085D01*
X408751Y-520835D01*
X407041D01*
Y-525835D01*
X409131D01*
X409575Y-525502D01*
X409828Y-525002D01*
X409955Y-524418D01*
X409828Y-523835D01*
X409448Y-523335D01*
X409005Y-523168D01*
X407041D01*
G01X413598Y-526002D02*
X413471Y-525918D01*
Y-525752D01*
X413598Y-525668D01*
X413725Y-525752D01*
Y-525918D01*
X413598Y-526002D01*
G01Y-523752D02*
X413471Y-523668D01*
Y-523502D01*
X413598Y-523418D01*
X413725Y-523502D01*
Y-523668D01*
X413598Y-523752D01*
G01X437258Y-518563D02*
Y-543563D01*
G01X437398Y-518335D02*
Y-543335D01*
G01X441298Y-520835D02*
Y-525835D01*
G01X439841Y-520835D02*
X442755D01*
G01X446398Y-525835D02*
X446018Y-525752D01*
X445638Y-525418D01*
X445385Y-524835D01*
X445258Y-524168D01*
X445385Y-523502D01*
X445638Y-522918D01*
X446018Y-522585D01*
X446398Y-522502D01*
X446778Y-522585D01*
X447158Y-522918D01*
X447411Y-523502D01*
X447475Y-524168D01*
X447411Y-524835D01*
X447158Y-525418D01*
X446778Y-525752D01*
X446398Y-525835D01*
G01X451498D02*
X451118Y-525752D01*
X450738Y-525418D01*
X450485Y-524835D01*
X450358Y-524168D01*
X450485Y-523502D01*
X450738Y-522918D01*
X451118Y-522585D01*
X451498Y-522502D01*
X451878Y-522585D01*
X452258Y-522918D01*
X452511Y-523502D01*
X452575Y-524168D01*
X452511Y-524835D01*
X452258Y-525418D01*
X451878Y-525752D01*
X451498Y-525835D01*
G01X456598D02*
Y-520835D01*
G01X461698Y-526002D02*
X461571Y-525918D01*
Y-525752D01*
X461698Y-525668D01*
X461825Y-525752D01*
Y-525918D01*
X461698Y-526002D01*
G01Y-523752D02*
X461571Y-523668D01*
Y-523502D01*
X461698Y-523418D01*
X461825Y-523502D01*
Y-523668D01*
X461698Y-523752D01*
G01X437398Y-493335D02*
Y-518335D01*
G01X440031Y-500835D02*
Y-495835D01*
X441615D01*
X442121Y-496085D01*
X442438Y-496418D01*
X442565Y-497085D01*
X442438Y-497752D01*
X442058Y-498168D01*
X441615Y-498418D01*
X440031D01*
G01X441615D02*
X442565Y-500835D01*
G01X447665D02*
X445131D01*
Y-495835D01*
X447665D01*
G01X446651Y-498252D02*
X445131D01*
G01X449915Y-495835D02*
X451498Y-500835D01*
X453081Y-495835D01*
G01X456598Y-501002D02*
X456471Y-500918D01*
Y-500752D01*
X456598Y-500668D01*
X456725Y-500752D01*
Y-500918D01*
X456598Y-501002D01*
G01Y-498752D02*
X456471Y-498668D01*
Y-498502D01*
X456598Y-498418D01*
X456725Y-498502D01*
Y-498668D01*
X456598Y-498752D01*
G01X445411Y-546502D02*
X445518Y-546377D01*
X445598Y-546168D01*
X445651Y-545877D01*
X445598Y-545627D01*
X445491Y-545460D01*
X445305Y-545335D01*
X444585D01*
Y-547835D01*
X445465D01*
X445651Y-547668D01*
X445758Y-547418D01*
X445811Y-547127D01*
X445758Y-546835D01*
X445598Y-546585D01*
X445411Y-546502D01*
X444585D01*
G01X447878Y-547835D02*
Y-546168D01*
G01Y-546460D02*
X447771Y-546293D01*
X447611Y-546210D01*
X447425Y-546168D01*
X447238Y-546252D01*
X447078Y-546418D01*
X446971Y-546668D01*
X446918Y-547002D01*
X446971Y-547335D01*
X447078Y-547585D01*
X447238Y-547752D01*
X447425Y-547835D01*
X447611Y-547793D01*
X447771Y-547668D01*
X447878Y-547502D01*
G01X449198Y-547543D02*
X449331Y-547710D01*
X449518Y-547835D01*
X449678D01*
X449838Y-547752D01*
X449945Y-547627D01*
X449998Y-547460D01*
X449971Y-547210D01*
X449865Y-547085D01*
X449385Y-546835D01*
X449278Y-546543D01*
X449331Y-546335D01*
X449438Y-546210D01*
X449598Y-546168D01*
X449758Y-546210D01*
X449918Y-546335D01*
G01X451398Y-546710D02*
X452251D01*
X452171Y-546418D01*
X452038Y-546252D01*
X451851Y-546168D01*
X451665Y-546210D01*
X451505Y-546335D01*
X451398Y-546627D01*
X451345Y-546877D01*
Y-547127D01*
X451398Y-547377D01*
X451531Y-547627D01*
X451691Y-547793D01*
X451878Y-547835D01*
X452065Y-547752D01*
X452251Y-547502D01*
G01X453518Y-547835D02*
Y-545335D01*
G01Y-546585D02*
X453651Y-546335D01*
X453811Y-546210D01*
X453971Y-546168D01*
X454211Y-546252D01*
X454371Y-546418D01*
X454478Y-546710D01*
Y-547043D01*
X454425Y-547377D01*
X454318Y-547627D01*
X454131Y-547793D01*
X453971Y-547835D01*
X453811Y-547793D01*
X453651Y-547668D01*
X453518Y-547460D01*
G01X456198Y-547835D02*
X456038Y-547793D01*
X455878Y-547627D01*
X455771Y-547335D01*
X455718Y-547002D01*
X455771Y-546668D01*
X455878Y-546377D01*
X456038Y-546210D01*
X456198Y-546168D01*
X456358Y-546210D01*
X456518Y-546377D01*
X456625Y-546668D01*
X456651Y-547002D01*
X456625Y-547335D01*
X456518Y-547627D01*
X456358Y-547793D01*
X456198Y-547835D01*
G01X458878D02*
Y-546168D01*
G01Y-546460D02*
X458771Y-546293D01*
X458611Y-546210D01*
X458425Y-546168D01*
X458238Y-546252D01*
X458078Y-546418D01*
X457971Y-546668D01*
X457918Y-547002D01*
X457971Y-547335D01*
X458078Y-547585D01*
X458238Y-547752D01*
X458425Y-547835D01*
X458611Y-547793D01*
X458771Y-547668D01*
X458878Y-547502D01*
G01X460225Y-547835D02*
Y-546168D01*
G01Y-546502D02*
X460358Y-546335D01*
X460491Y-546210D01*
X460678Y-546168D01*
X460811Y-546210D01*
X460971Y-546335D01*
G01X463278Y-545335D02*
Y-547835D01*
G01Y-547460D02*
X463171Y-547668D01*
X463011Y-547793D01*
X462825Y-547835D01*
X462611Y-547752D01*
X462451Y-547543D01*
X462345Y-547293D01*
X462318Y-547002D01*
X462345Y-546710D01*
X462451Y-546460D01*
X462611Y-546252D01*
X462825Y-546168D01*
X463011Y-546210D01*
X463145Y-546293D01*
X463278Y-546460D01*
G01X466665Y-547835D02*
Y-545335D01*
X467331D01*
X467545Y-545460D01*
X467678Y-545627D01*
X467731Y-545960D01*
X467678Y-546293D01*
X467518Y-546502D01*
X467331Y-546627D01*
X466665D01*
G01X467331D02*
X467731Y-547835D01*
G01X468998Y-546710D02*
X469851D01*
X469771Y-546418D01*
X469638Y-546252D01*
X469451Y-546168D01*
X469265Y-546210D01*
X469105Y-546335D01*
X468998Y-546627D01*
X468945Y-546877D01*
Y-547127D01*
X468998Y-547377D01*
X469131Y-547627D01*
X469291Y-547793D01*
X469478Y-547835D01*
X469665Y-547752D01*
X469851Y-547502D01*
G01X471118Y-546168D02*
X471598Y-547835D01*
X472078Y-546168D01*
G01X473798Y-547918D02*
X473745Y-547877D01*
Y-547793D01*
X473798Y-547752D01*
X473851Y-547793D01*
Y-547877D01*
X473798Y-547918D01*
G01X475545Y-547543D02*
X475731Y-547752D01*
X475945Y-547835D01*
X476158Y-547752D01*
X476345Y-547502D01*
X476478Y-547127D01*
X476531Y-546752D01*
Y-546293D01*
X476478Y-545918D01*
X476345Y-545585D01*
X476185Y-545418D01*
X475998Y-545335D01*
X475785Y-545418D01*
X475625Y-545585D01*
X475518Y-545835D01*
X475465Y-546168D01*
X475518Y-546460D01*
X475651Y-546752D01*
X475811Y-546918D01*
X475998Y-546960D01*
X476211Y-546877D01*
X476371Y-546668D01*
X476531Y-546293D01*
G01X478411Y-546502D02*
X478518Y-546377D01*
X478598Y-546168D01*
X478651Y-545877D01*
X478598Y-545627D01*
X478491Y-545460D01*
X478305Y-545335D01*
X477585D01*
Y-547835D01*
X478465D01*
X478651Y-547668D01*
X478758Y-547418D01*
X478811Y-547127D01*
X478758Y-546835D01*
X478598Y-546585D01*
X478411Y-546502D01*
X477585D01*
G01X-1490433Y-1677216D02*
Y3837819D01*
X4496476D01*
Y-1677216D01*
X-1490433D01*
G01X-7782Y-515685D02*
X-6215D01*
Y-517575D01*
X-6685Y-518205D01*
X-7234Y-518625D01*
X-8017Y-518835D01*
X-8800Y-518625D01*
X-9349Y-518205D01*
X-9819Y-517575D01*
X-10132Y-516840D01*
X-10289Y-516000D01*
Y-515265D01*
X-10132Y-514635D01*
X-9819Y-513900D01*
X-9349Y-513270D01*
X-8879Y-512850D01*
X-8252Y-512535D01*
X-7704D01*
X-7077Y-512745D01*
X-6607Y-513165D01*
G01X-3675Y-512535D02*
Y-517050D01*
X-3362Y-517995D01*
X-2735Y-518625D01*
X-1952Y-518835D01*
X-1169Y-518625D01*
X-542Y-517995D01*
X-229Y-517050D01*
Y-512535D01*
G01X3408D02*
X5288D01*
G01X4348D02*
Y-518835D01*
G01X3408D02*
X5288D01*
G01X9003Y-517995D02*
X9630Y-518520D01*
X10335Y-518835D01*
X10961D01*
X11588Y-518520D01*
X12058Y-517995D01*
X12293Y-517260D01*
X12136Y-516525D01*
X11745Y-515895D01*
X11040Y-515475D01*
X10100Y-515265D01*
X9551Y-514845D01*
X9316Y-514110D01*
X9473Y-513375D01*
X9865Y-512850D01*
X10413Y-512535D01*
X10961D01*
X11510Y-512745D01*
X11980Y-513270D01*
G01X15303Y-518835D02*
Y-512535D01*
G01X18593D02*
Y-518835D01*
G01Y-515685D02*
X15303D01*
G01X21290Y-518835D02*
X23248Y-512535D01*
X25206Y-518835D01*
G01X24501Y-516630D02*
X21995D01*
G01X27746Y-518835D02*
Y-512535D01*
X31350Y-518835D01*
Y-512535D01*
G01X40425Y-518835D02*
Y-512535D01*
X41991D01*
X42618Y-512850D01*
X43088Y-513270D01*
X43480Y-513900D01*
X43793Y-514635D01*
X43871Y-515685D01*
X43793Y-516735D01*
X43480Y-517470D01*
X43088Y-518100D01*
X42618Y-518520D01*
X41991Y-518835D01*
X40425D01*
G01X47508Y-512535D02*
X49388D01*
G01X48448D02*
Y-518835D01*
G01X47508D02*
X49388D01*
G01X53103Y-517995D02*
X53730Y-518520D01*
X54435Y-518835D01*
X55061D01*
X55688Y-518520D01*
X56158Y-517995D01*
X56393Y-517260D01*
X56236Y-516525D01*
X55845Y-515895D01*
X55140Y-515475D01*
X54200Y-515265D01*
X53651Y-514845D01*
X53416Y-514110D01*
X53573Y-513375D01*
X53965Y-512850D01*
X54513Y-512535D01*
X55061D01*
X55610Y-512745D01*
X56080Y-513270D01*
G01X61048Y-512535D02*
Y-518835D01*
G01X59246Y-512535D02*
X62850D01*
G01X67348Y-519045D02*
X67191Y-518940D01*
Y-518730D01*
X67348Y-518625D01*
X67505Y-518730D01*
Y-518940D01*
X67348Y-519045D01*
G01X73491Y-519990D02*
X73805Y-518625D01*
G01X79948Y-512535D02*
Y-518835D01*
G01X78146Y-512535D02*
X81750D01*
G01X84290Y-518835D02*
X86248Y-512535D01*
X88206Y-518835D01*
G01X87501Y-516630D02*
X84995D01*
G01X92548Y-518835D02*
X91921Y-518730D01*
X91373Y-518310D01*
X90903Y-517680D01*
X90590Y-516945D01*
X90433Y-516105D01*
Y-515265D01*
X90590Y-514425D01*
X90903Y-513690D01*
X91373Y-513060D01*
X91921Y-512640D01*
X92548Y-512535D01*
X93175Y-512640D01*
X93723Y-513060D01*
X94193Y-513690D01*
X94506Y-514425D01*
X94663Y-515265D01*
Y-516105D01*
X94506Y-516945D01*
X94193Y-517680D01*
X93723Y-518310D01*
X93175Y-518730D01*
X92548Y-518835D01*
G01X98848D02*
Y-516000D01*
X97281Y-512535D01*
G01X100415D02*
X98848Y-516000D01*
G01X103425Y-512535D02*
Y-517050D01*
X103738Y-517995D01*
X104365Y-518625D01*
X105148Y-518835D01*
X105931Y-518625D01*
X106558Y-517995D01*
X106871Y-517050D01*
Y-512535D01*
G01X109490Y-518835D02*
X111448Y-512535D01*
X113406Y-518835D01*
G01X112701Y-516630D02*
X110195D01*
G01X115946Y-518835D02*
Y-512535D01*
X119550Y-518835D01*
Y-512535D01*
G01X-6529Y-523060D02*
X-6999Y-522745D01*
X-7547Y-522535D01*
X-8174D01*
X-8879Y-522850D01*
X-9427Y-523375D01*
X-9819Y-524005D01*
X-10132Y-525055D01*
X-10210Y-526000D01*
X-10054Y-526945D01*
X-9819Y-527575D01*
X-9349Y-528205D01*
X-8800Y-528625D01*
X-8252Y-528835D01*
X-7704D01*
X-7155Y-528625D01*
X-6685Y-528310D01*
X-6294Y-527890D01*
G01X-2892Y-522535D02*
X-1012D01*
G01X-1952D02*
Y-528835D01*
G01X-2892D02*
X-1012D01*
G01X4348Y-522535D02*
Y-528835D01*
G01X2546Y-522535D02*
X6150D01*
G01X10648Y-528835D02*
Y-526000D01*
X9081Y-522535D01*
G01X12215D02*
X10648Y-526000D01*
G01X21525Y-527575D02*
X21995Y-528310D01*
X22621Y-528730D01*
X23326Y-528835D01*
X23953Y-528730D01*
X24580Y-528205D01*
X24971Y-527575D01*
X25050Y-526945D01*
X24893Y-526210D01*
X24345Y-525685D01*
X23796Y-525475D01*
X23091D01*
G01X23796D02*
X24266Y-525160D01*
X24658Y-524635D01*
X24815Y-524005D01*
X24658Y-523375D01*
X24266Y-522850D01*
X23561Y-522535D01*
X22856Y-522640D01*
X22151Y-523060D01*
G01X27825Y-527575D02*
X28295Y-528310D01*
X28921Y-528730D01*
X29626Y-528835D01*
X30253Y-528730D01*
X30880Y-528205D01*
X31271Y-527575D01*
X31350Y-526945D01*
X31193Y-526210D01*
X30645Y-525685D01*
X30096Y-525475D01*
X29391D01*
G01X30096D02*
X30566Y-525160D01*
X30958Y-524635D01*
X31115Y-524005D01*
X30958Y-523375D01*
X30566Y-522850D01*
X29861Y-522535D01*
X29156Y-522640D01*
X28451Y-523060D01*
G01X34125Y-527575D02*
X34595Y-528310D01*
X35221Y-528730D01*
X35926Y-528835D01*
X36553Y-528730D01*
X37180Y-528205D01*
X37571Y-527575D01*
X37650Y-526945D01*
X37493Y-526210D01*
X36945Y-525685D01*
X36396Y-525475D01*
X35691D01*
G01X36396D02*
X36866Y-525160D01*
X37258Y-524635D01*
X37415Y-524005D01*
X37258Y-523375D01*
X36866Y-522850D01*
X36161Y-522535D01*
X35456Y-522640D01*
X34751Y-523060D01*
G01X41991Y-528835D02*
X42148Y-527470D01*
X42383Y-526315D01*
X42696Y-525265D01*
X43088Y-524110D01*
X43715Y-522535D01*
X40581D01*
G01X48291Y-528835D02*
X48448Y-527470D01*
X48683Y-526315D01*
X48996Y-525265D01*
X49388Y-524110D01*
X50015Y-522535D01*
X46881D01*
G01X54591Y-529990D02*
X54905Y-528625D01*
G01X61048Y-522535D02*
Y-528835D01*
G01X59246Y-522535D02*
X62850D01*
G01X65390Y-528835D02*
X67348Y-522535D01*
X69306Y-528835D01*
G01X68601Y-526630D02*
X66095D01*
G01X72708Y-522535D02*
X74588D01*
G01X73648D02*
Y-528835D01*
G01X72708D02*
X74588D01*
G01X77598Y-522535D02*
X78695Y-528835D01*
X79948Y-522535D01*
X81201Y-528835D01*
X82298Y-522535D01*
G01X84290Y-528835D02*
X86248Y-522535D01*
X88206Y-528835D01*
G01X87501Y-526630D02*
X84995D01*
G01X90746Y-528835D02*
Y-522535D01*
X94350Y-528835D01*
Y-522535D01*
G01X104756Y-530935D02*
X103973Y-529885D01*
X103581Y-528835D01*
Y-524635D01*
X103973Y-523585D01*
X104756Y-522535D01*
G01X116181Y-528835D02*
Y-522535D01*
X118140D01*
X118766Y-522850D01*
X119158Y-523270D01*
X119315Y-524110D01*
X119158Y-524950D01*
X118688Y-525475D01*
X118140Y-525790D01*
X116181D01*
G01X118140D02*
X119315Y-528835D01*
G01X124048Y-529045D02*
X123891Y-528940D01*
Y-528730D01*
X124048Y-528625D01*
X124205Y-528730D01*
Y-528940D01*
X124048Y-529045D01*
G01X130348Y-528835D02*
X129721Y-528730D01*
X129173Y-528310D01*
X128703Y-527680D01*
X128390Y-526945D01*
X128233Y-526105D01*
Y-525265D01*
X128390Y-524425D01*
X128703Y-523690D01*
X129173Y-523060D01*
X129721Y-522640D01*
X130348Y-522535D01*
X130975Y-522640D01*
X131523Y-523060D01*
X131993Y-523690D01*
X132306Y-524425D01*
X132463Y-525265D01*
Y-526105D01*
X132306Y-526945D01*
X131993Y-527680D01*
X131523Y-528310D01*
X130975Y-528730D01*
X130348Y-528835D01*
G01X136648Y-529045D02*
X136491Y-528940D01*
Y-528730D01*
X136648Y-528625D01*
X136805Y-528730D01*
Y-528940D01*
X136648Y-529045D01*
G01X144671Y-523060D02*
X144201Y-522745D01*
X143653Y-522535D01*
X143026D01*
X142321Y-522850D01*
X141773Y-523375D01*
X141381Y-524005D01*
X141068Y-525055D01*
X140990Y-526000D01*
X141146Y-526945D01*
X141381Y-527575D01*
X141851Y-528205D01*
X142400Y-528625D01*
X142948Y-528835D01*
X143496D01*
X144045Y-528625D01*
X144515Y-528310D01*
X144906Y-527890D01*
G01X149248Y-529045D02*
X149091Y-528940D01*
Y-528730D01*
X149248Y-528625D01*
X149405Y-528730D01*
Y-528940D01*
X149248Y-529045D01*
G01X155940Y-530935D02*
X156723Y-529885D01*
X157115Y-528835D01*
Y-524635D01*
X156723Y-523585D01*
X155940Y-522535D01*
G01X-10054Y-508835D02*
Y-502535D01*
X-6450Y-508835D01*
Y-502535D01*
G01X-1952Y-508835D02*
X-2579Y-508730D01*
X-3127Y-508310D01*
X-3597Y-507680D01*
X-3910Y-506945D01*
X-4067Y-506105D01*
Y-505265D01*
X-3910Y-504425D01*
X-3597Y-503690D01*
X-3127Y-503060D01*
X-2579Y-502640D01*
X-1952Y-502535D01*
X-1325Y-502640D01*
X-777Y-503060D01*
X-307Y-503690D01*
X6Y-504425D01*
X163Y-505265D01*
Y-506105D01*
X6Y-506945D01*
X-307Y-507680D01*
X-777Y-508310D01*
X-1325Y-508730D01*
X-1952Y-508835D01*
G01X4348Y-509045D02*
X4191Y-508940D01*
Y-508730D01*
X4348Y-508625D01*
X4505Y-508730D01*
Y-508940D01*
X4348Y-509045D01*
G01X9160Y-503585D02*
X9630Y-502955D01*
X10178Y-502640D01*
X10805Y-502535D01*
X11588Y-502745D01*
X12136Y-503270D01*
X12293Y-503900D01*
X12215Y-504530D01*
X11901Y-505055D01*
X10335Y-506105D01*
X9630Y-506840D01*
X9160Y-507890D01*
X9003Y-508835D01*
X12293D01*
G01X16948D02*
Y-502535D01*
X16008Y-503795D01*
G01Y-508835D02*
X17888D01*
G01X23248D02*
Y-502535D01*
X22308Y-503795D01*
G01Y-508835D02*
X24188D01*
G01X29391Y-509990D02*
X29705Y-508625D01*
G01X33498Y-502535D02*
X34595Y-508835D01*
X35848Y-502535D01*
X37101Y-508835D01*
X38198Y-502535D01*
G01X43715Y-508835D02*
X40581D01*
Y-502535D01*
X43715D01*
G01X42461Y-505580D02*
X40581D01*
G01X46646Y-508835D02*
Y-502535D01*
X50250Y-508835D01*
Y-502535D01*
G01X53103Y-508835D02*
Y-502535D01*
G01X56393D02*
Y-508835D01*
G01Y-505685D02*
X53103D01*
G01X59325Y-502535D02*
Y-507050D01*
X59638Y-507995D01*
X60265Y-508625D01*
X61048Y-508835D01*
X61831Y-508625D01*
X62458Y-507995D01*
X62771Y-507050D01*
Y-502535D01*
G01X65390Y-508835D02*
X67348Y-502535D01*
X69306Y-508835D01*
G01X68601Y-506630D02*
X66095D01*
G01X78460Y-503585D02*
X78930Y-502955D01*
X79478Y-502640D01*
X80105Y-502535D01*
X80888Y-502745D01*
X81436Y-503270D01*
X81593Y-503900D01*
X81515Y-504530D01*
X81201Y-505055D01*
X79635Y-506105D01*
X78930Y-506840D01*
X78460Y-507890D01*
X78303Y-508835D01*
X81593D01*
G01X84446D02*
Y-502535D01*
X88050Y-508835D01*
Y-502535D01*
G01X90825Y-508835D02*
Y-502535D01*
X92391D01*
X93018Y-502850D01*
X93488Y-503270D01*
X93880Y-503900D01*
X94193Y-504635D01*
X94271Y-505685D01*
X94193Y-506735D01*
X93880Y-507470D01*
X93488Y-508100D01*
X93018Y-508520D01*
X92391Y-508835D01*
X90825D01*
G01X103581D02*
Y-502535D01*
X105540D01*
X106166Y-502850D01*
X106558Y-503270D01*
X106715Y-504110D01*
X106558Y-504950D01*
X106088Y-505475D01*
X105540Y-505790D01*
X103581D01*
G01X105540D02*
X106715Y-508835D01*
G01X109725D02*
Y-502535D01*
X111291D01*
X111918Y-502850D01*
X112388Y-503270D01*
X112780Y-503900D01*
X113093Y-504635D01*
X113171Y-505685D01*
X113093Y-506735D01*
X112780Y-507470D01*
X112388Y-508100D01*
X111918Y-508520D01*
X111291Y-508835D01*
X109725D01*
G01X117748Y-509045D02*
X117591Y-508940D01*
Y-508730D01*
X117748Y-508625D01*
X117905Y-508730D01*
Y-508940D01*
X117748Y-509045D01*
G01X14048Y-498135D02*
X11528Y-497718D01*
X9323Y-496052D01*
X7433Y-493552D01*
X6173Y-490635D01*
X5543Y-487302D01*
Y-483968D01*
X6173Y-480635D01*
X7433Y-477718D01*
X9323Y-475219D01*
X11528Y-473552D01*
X14048Y-473135D01*
X16568Y-473552D01*
X18773Y-475219D01*
X20663Y-477718D01*
X21923Y-480635D01*
X22553Y-483968D01*
Y-487302D01*
X21923Y-490635D01*
X20663Y-493552D01*
X18773Y-496052D01*
X16568Y-497718D01*
X14048Y-498135D01*
G01X16568Y-491468D02*
X20348Y-498135D01*
G01X33893Y-481469D02*
Y-493135D01*
X35153Y-496052D01*
X37043Y-497718D01*
X39248Y-498135D01*
X41453Y-497718D01*
X43343Y-496052D01*
X44603Y-493135D01*
G01Y-498135D02*
Y-481469D01*
G01X70118Y-498135D02*
Y-481469D01*
G01Y-484385D02*
X68858Y-482719D01*
X66968Y-481885D01*
X64763Y-481469D01*
X62558Y-482302D01*
X60668Y-483968D01*
X59408Y-486469D01*
X58778Y-489802D01*
X59408Y-493135D01*
X60668Y-495636D01*
X62558Y-497302D01*
X64763Y-498135D01*
X66968Y-497718D01*
X68858Y-496469D01*
X70118Y-494802D01*
G01X84293Y-498135D02*
Y-481469D01*
G01Y-485635D02*
X85553Y-483552D01*
X87443Y-481885D01*
X89963Y-481469D01*
X92168Y-481885D01*
X94058Y-483552D01*
X95003Y-486469D01*
Y-498135D01*
G01X114848Y-473135D02*
Y-498135D01*
G01X110438Y-481469D02*
X119258D01*
G01X145718Y-498135D02*
Y-481469D01*
G01Y-484385D02*
X144458Y-482719D01*
X142568Y-481885D01*
X140363Y-481469D01*
X138158Y-482302D01*
X136268Y-483968D01*
X135008Y-486469D01*
X134378Y-489802D01*
X135008Y-493135D01*
X136268Y-495636D01*
X138158Y-497302D01*
X140363Y-498135D01*
X142568Y-497718D01*
X144458Y-496469D01*
X145718Y-494802D01*
G01X185398Y-477835D02*
Y-485835D01*
X189398D01*
G01X197198D02*
Y-480502D01*
G01Y-481435D02*
X196798Y-480902D01*
X196198Y-480635D01*
X195498Y-480502D01*
X194798Y-480768D01*
X194198Y-481302D01*
X193798Y-482102D01*
X193598Y-483168D01*
X193798Y-484235D01*
X194198Y-485035D01*
X194798Y-485568D01*
X195498Y-485835D01*
X196198Y-485702D01*
X196798Y-485302D01*
X197198Y-484769D01*
G01X201298Y-488235D02*
X201898Y-488502D01*
X202698Y-488235D01*
X203198Y-487702D01*
X203598Y-487035D01*
X204198Y-484902D01*
X205498Y-480502D01*
G01X202298D02*
X204198Y-484902D01*
G01X209898Y-482235D02*
X213098D01*
X212798Y-481302D01*
X212298Y-480768D01*
X211598Y-480502D01*
X210898Y-480635D01*
X210298Y-481035D01*
X209898Y-481968D01*
X209698Y-482769D01*
Y-483568D01*
X209898Y-484368D01*
X210398Y-485168D01*
X210998Y-485702D01*
X211698Y-485835D01*
X212398Y-485568D01*
X213098Y-484769D01*
G01X217998Y-485835D02*
Y-480502D01*
G01Y-481568D02*
X218498Y-481035D01*
X218998Y-480635D01*
X219698Y-480502D01*
X220198Y-480635D01*
X220798Y-481035D01*
G01X211398Y-535835D02*
Y-532235D01*
X209398Y-527835D01*
G01X213398D02*
X211398Y-532235D01*
G01X217698Y-530502D02*
Y-534235D01*
X218098Y-535168D01*
X218698Y-535702D01*
X219398Y-535835D01*
X220098Y-535702D01*
X220698Y-535168D01*
X221098Y-534235D01*
G01Y-535835D02*
Y-530502D01*
G01X225698Y-535835D02*
Y-530502D01*
G01Y-531835D02*
X226098Y-531168D01*
X226698Y-530635D01*
X227498Y-530502D01*
X228198Y-530635D01*
X228798Y-531168D01*
X229098Y-532102D01*
Y-535835D01*
G01X237198D02*
Y-530502D01*
G01Y-531435D02*
X236798Y-530902D01*
X236198Y-530635D01*
X235498Y-530502D01*
X234798Y-530768D01*
X234198Y-531302D01*
X233798Y-532102D01*
X233598Y-533168D01*
X233798Y-534235D01*
X234198Y-535035D01*
X234798Y-535568D01*
X235498Y-535835D01*
X236198Y-535702D01*
X236798Y-535302D01*
X237198Y-534769D01*
G01X217698Y-502835D02*
X220098D01*
G01X218898D02*
Y-510835D01*
G01X217698D02*
X220098D01*
G01X224598D02*
Y-502835D01*
X229198Y-510835D01*
Y-502835D01*
G01X232998Y-504168D02*
X233598Y-503368D01*
X234298Y-502968D01*
X235098Y-502835D01*
X236098Y-503102D01*
X236798Y-503768D01*
X236998Y-504568D01*
X236898Y-505369D01*
X236498Y-506035D01*
X234498Y-507368D01*
X233598Y-508302D01*
X232998Y-509635D01*
X232798Y-510835D01*
X236998D01*
G01X238898Y-485835D02*
X239598Y-485702D01*
X240398Y-485302D01*
X240898Y-484635D01*
X241098Y-483702D01*
X240898Y-482769D01*
X240298Y-481968D01*
X239398Y-481568D01*
X238398D01*
X237798Y-481302D01*
X237298Y-480635D01*
X237098Y-479702D01*
X237398Y-478768D01*
X238098Y-478102D01*
X238898Y-477835D01*
X239698Y-478102D01*
X240398Y-478768D01*
X240698Y-479702D01*
X240498Y-480635D01*
X239998Y-481302D01*
X239398Y-481568D01*
X238398D01*
X237498Y-481968D01*
X236898Y-482769D01*
X236698Y-483702D01*
X236898Y-484635D01*
X237398Y-485302D01*
X238198Y-485702D01*
X238898Y-485835D01*
G01X311998Y-529168D02*
X312598Y-528368D01*
X313298Y-527968D01*
X314098Y-527835D01*
X315098Y-528102D01*
X315798Y-528768D01*
X315998Y-529568D01*
X315898Y-530369D01*
X315498Y-531035D01*
X313498Y-532368D01*
X312598Y-533302D01*
X311998Y-534635D01*
X311798Y-535835D01*
X315998D01*
G01X321898Y-527835D02*
X321098Y-528102D01*
X320498Y-528768D01*
X320098Y-529568D01*
X319798Y-530635D01*
X319698Y-531835D01*
X319798Y-533035D01*
X320098Y-534102D01*
X320498Y-534902D01*
X321098Y-535568D01*
X321898Y-535835D01*
X322698Y-535568D01*
X323298Y-534902D01*
X323698Y-534102D01*
X323998Y-533035D01*
X324098Y-531835D01*
X323998Y-530635D01*
X323698Y-529568D01*
X323298Y-528768D01*
X322698Y-528102D01*
X321898Y-527835D01*
G01X327998Y-529168D02*
X328598Y-528368D01*
X329298Y-527968D01*
X330098Y-527835D01*
X331098Y-528102D01*
X331798Y-528768D01*
X331998Y-529568D01*
X331898Y-530369D01*
X331498Y-531035D01*
X329498Y-532368D01*
X328598Y-533302D01*
X327998Y-534635D01*
X327798Y-535835D01*
X331998D01*
G01X335698Y-534235D02*
X336298Y-535168D01*
X337098Y-535702D01*
X337998Y-535835D01*
X338798Y-535702D01*
X339598Y-535035D01*
X340098Y-534235D01*
X340198Y-533435D01*
X339998Y-532502D01*
X339298Y-531835D01*
X338598Y-531568D01*
X337698D01*
G01X338598D02*
X339198Y-531168D01*
X339698Y-530502D01*
X339898Y-529702D01*
X339698Y-528902D01*
X339198Y-528235D01*
X338298Y-527835D01*
X337398Y-527968D01*
X336498Y-528502D01*
G01X344098Y-536102D02*
X347698Y-527835D01*
G01X353898D02*
X353098Y-528102D01*
X352498Y-528768D01*
X352098Y-529568D01*
X351798Y-530635D01*
X351698Y-531835D01*
X351798Y-533035D01*
X352098Y-534102D01*
X352498Y-534902D01*
X353098Y-535568D01*
X353898Y-535835D01*
X354698Y-535568D01*
X355298Y-534902D01*
X355698Y-534102D01*
X355998Y-533035D01*
X356098Y-531835D01*
X355998Y-530635D01*
X355698Y-529568D01*
X355298Y-528768D01*
X354698Y-528102D01*
X353898Y-527835D01*
G01X361898Y-535835D02*
Y-527835D01*
X360698Y-529435D01*
G01Y-535835D02*
X363098D01*
G01X368098Y-536102D02*
X371698Y-527835D01*
G01X377898D02*
X377098Y-528102D01*
X376498Y-528768D01*
X376098Y-529568D01*
X375798Y-530635D01*
X375698Y-531835D01*
X375798Y-533035D01*
X376098Y-534102D01*
X376498Y-534902D01*
X377098Y-535568D01*
X377898Y-535835D01*
X378698Y-535568D01*
X379298Y-534902D01*
X379698Y-534102D01*
X379998Y-533035D01*
X380098Y-531835D01*
X379998Y-530635D01*
X379698Y-529568D01*
X379298Y-528768D01*
X378698Y-528102D01*
X377898Y-527835D01*
G01X384198Y-534902D02*
X384898Y-535568D01*
X385698Y-535835D01*
X386498Y-535568D01*
X387198Y-534769D01*
X387698Y-533568D01*
X387898Y-532368D01*
Y-530902D01*
X387698Y-529702D01*
X387198Y-528635D01*
X386598Y-528102D01*
X385898Y-527835D01*
X385098Y-528102D01*
X384498Y-528635D01*
X384098Y-529435D01*
X383898Y-530502D01*
X384098Y-531435D01*
X384598Y-532368D01*
X385198Y-532902D01*
X385898Y-533035D01*
X386698Y-532769D01*
X387298Y-532102D01*
X387898Y-530902D01*
G01X311698Y-510835D02*
Y-502835D01*
X313698D01*
X314498Y-503235D01*
X315098Y-503768D01*
X315598Y-504568D01*
X315998Y-505502D01*
X316098Y-506835D01*
X315998Y-508168D01*
X315598Y-509102D01*
X315098Y-509902D01*
X314498Y-510435D01*
X313698Y-510835D01*
X311698D01*
G01X319398D02*
X321898Y-502835D01*
X324398Y-510835D01*
G01X323498Y-508035D02*
X320298D01*
G01X329898Y-502835D02*
X329098Y-503102D01*
X328498Y-503768D01*
X328098Y-504568D01*
X327798Y-505635D01*
X327698Y-506835D01*
X327798Y-508035D01*
X328098Y-509102D01*
X328498Y-509902D01*
X329098Y-510568D01*
X329898Y-510835D01*
X330698Y-510568D01*
X331298Y-509902D01*
X331698Y-509102D01*
X331998Y-508035D01*
X332098Y-506835D01*
X331998Y-505635D01*
X331698Y-504568D01*
X331298Y-503768D01*
X330698Y-503102D01*
X329898Y-502835D01*
G01X335998Y-510835D02*
Y-502835D01*
X339798D01*
G01X338398Y-506702D02*
X335998D01*
G01X345898Y-502835D02*
X345098Y-503102D01*
X344498Y-503768D01*
X344098Y-504568D01*
X343798Y-505635D01*
X343698Y-506835D01*
X343798Y-508035D01*
X344098Y-509102D01*
X344498Y-509902D01*
X345098Y-510568D01*
X345898Y-510835D01*
X346698Y-510568D01*
X347298Y-509902D01*
X347698Y-509102D01*
X347998Y-508035D01*
X348098Y-506835D01*
X347998Y-505635D01*
X347698Y-504568D01*
X347298Y-503768D01*
X346698Y-503102D01*
X345898Y-502835D01*
G01X353898D02*
Y-510835D01*
G01X351598Y-502835D02*
X356198D01*
G01X363898Y-510835D02*
X359898D01*
Y-502835D01*
X363898D01*
G01X362298Y-506702D02*
X359898D01*
G01X370698Y-506568D02*
X371098Y-506168D01*
X371398Y-505502D01*
X371598Y-504568D01*
X371398Y-503768D01*
X370998Y-503235D01*
X370298Y-502835D01*
X367598D01*
Y-510835D01*
X370898D01*
X371598Y-510302D01*
X371998Y-509502D01*
X372198Y-508568D01*
X371998Y-507635D01*
X371398Y-506835D01*
X370698Y-506568D01*
X367598D01*
G01X376698Y-502835D02*
X379098D01*
G01X377898D02*
Y-510835D01*
G01X376698D02*
X379098D01*
G01X383998D02*
Y-502835D01*
X387798D01*
G01X386398Y-506702D02*
X383998D01*
G01X393898Y-502835D02*
X393098Y-503102D01*
X392498Y-503768D01*
X392098Y-504568D01*
X391798Y-505635D01*
X391698Y-506835D01*
X391798Y-508035D01*
X392098Y-509102D01*
X392498Y-509902D01*
X393098Y-510568D01*
X393898Y-510835D01*
X394698Y-510568D01*
X395298Y-509902D01*
X395698Y-509102D01*
X395998Y-508035D01*
X396098Y-506835D01*
X395998Y-505635D01*
X395698Y-504568D01*
X395298Y-503768D01*
X394698Y-503102D01*
X393898Y-502835D01*
G01X329498Y-485835D02*
Y-477835D01*
X333298D01*
G01X331898Y-481702D02*
X329498D01*
G01X339398Y-477835D02*
X338598Y-478102D01*
X337998Y-478768D01*
X337598Y-479568D01*
X337298Y-480635D01*
X337198Y-481835D01*
X337298Y-483035D01*
X337598Y-484102D01*
X337998Y-484902D01*
X338598Y-485568D01*
X339398Y-485835D01*
X340198Y-485568D01*
X340798Y-484902D01*
X341198Y-484102D01*
X341498Y-483035D01*
X341598Y-481835D01*
X341498Y-480635D01*
X341198Y-479568D01*
X340798Y-478768D01*
X340198Y-478102D01*
X339398Y-477835D01*
G01X347398D02*
Y-485835D01*
G01X345098Y-477835D02*
X349698D01*
G01X352398Y-488502D02*
X358398D01*
G01X361898Y-482235D02*
X365098D01*
X364798Y-481302D01*
X364298Y-480768D01*
X363598Y-480502D01*
X362898Y-480635D01*
X362298Y-481035D01*
X361898Y-481968D01*
X361698Y-482769D01*
Y-483568D01*
X361898Y-484368D01*
X362398Y-485168D01*
X362998Y-485702D01*
X363698Y-485835D01*
X364398Y-485568D01*
X365098Y-484769D01*
G01X369898Y-480502D02*
X372898Y-485835D01*
G01Y-480502D02*
X369898Y-485835D01*
G01X377598Y-488502D02*
Y-480502D01*
G01Y-481702D02*
X378098Y-481035D01*
X378598Y-480635D01*
X379398Y-480502D01*
X380098Y-480635D01*
X380798Y-481302D01*
X381098Y-482235D01*
X381198Y-483168D01*
X381098Y-484102D01*
X380798Y-485035D01*
X380198Y-485568D01*
X379398Y-485835D01*
X378698Y-485702D01*
X377998Y-485302D01*
X377598Y-484769D01*
G01X389198Y-485835D02*
Y-480502D01*
G01Y-481435D02*
X388798Y-480902D01*
X388198Y-480635D01*
X387498Y-480502D01*
X386798Y-480768D01*
X386198Y-481302D01*
X385798Y-482102D01*
X385598Y-483168D01*
X385798Y-484235D01*
X386198Y-485035D01*
X386798Y-485568D01*
X387498Y-485835D01*
X388198Y-485702D01*
X388798Y-485302D01*
X389198Y-484769D01*
G01X393698Y-485835D02*
Y-480502D01*
G01Y-481835D02*
X394098Y-481168D01*
X394698Y-480635D01*
X395498Y-480502D01*
X396198Y-480635D01*
X396798Y-481168D01*
X397098Y-482102D01*
Y-485835D01*
G01X405198Y-477835D02*
Y-485835D01*
G01Y-484635D02*
X404798Y-485302D01*
X404198Y-485702D01*
X403498Y-485835D01*
X402698Y-485568D01*
X402098Y-484902D01*
X401698Y-484102D01*
X401598Y-483168D01*
X401698Y-482235D01*
X402098Y-481435D01*
X402698Y-480768D01*
X403498Y-480502D01*
X404198Y-480635D01*
X404698Y-480902D01*
X405198Y-481435D01*
G01X409898Y-482235D02*
X413098D01*
X412798Y-481302D01*
X412298Y-480768D01*
X411598Y-480502D01*
X410898Y-480635D01*
X410298Y-481035D01*
X409898Y-481968D01*
X409698Y-482769D01*
Y-483568D01*
X409898Y-484368D01*
X410398Y-485168D01*
X410998Y-485702D01*
X411698Y-485835D01*
X412398Y-485568D01*
X413098Y-484769D01*
G01X417998Y-485835D02*
Y-480502D01*
G01Y-481568D02*
X418498Y-481035D01*
X418998Y-480635D01*
X419698Y-480502D01*
X420198Y-480635D01*
X420798Y-481035D01*
G01X424398Y-488502D02*
X430398D01*
G01X433598Y-485835D02*
Y-477835D01*
G01Y-481835D02*
X434098Y-481035D01*
X434698Y-480635D01*
X435298Y-480502D01*
X436198Y-480768D01*
X436798Y-481302D01*
X437198Y-482235D01*
Y-483302D01*
X436998Y-484368D01*
X436598Y-485168D01*
X435898Y-485702D01*
X435298Y-485835D01*
X434698Y-485702D01*
X434098Y-485302D01*
X433598Y-484635D01*
G01X445198Y-477835D02*
Y-485835D01*
G01Y-484635D02*
X444798Y-485302D01*
X444198Y-485702D01*
X443498Y-485835D01*
X442698Y-485568D01*
X442098Y-484902D01*
X441698Y-484102D01*
X441598Y-483168D01*
X441698Y-482235D01*
X442098Y-481435D01*
X442698Y-480768D01*
X443498Y-480502D01*
X444198Y-480635D01*
X444698Y-480902D01*
X445198Y-481435D01*
G01X400398Y-538835D02*
Y-530835D01*
X399198Y-532435D01*
G01Y-538835D02*
X401598D01*
G01X406498Y-535502D02*
X407198Y-534568D01*
X407798Y-534035D01*
X408598Y-533768D01*
X409298Y-534035D01*
X409798Y-534568D01*
X410198Y-535368D01*
X410298Y-536302D01*
X410198Y-537102D01*
X409798Y-537902D01*
X409198Y-538568D01*
X408498Y-538835D01*
X407698Y-538568D01*
X406998Y-537769D01*
X406598Y-536568D01*
X406498Y-535235D01*
X406698Y-533502D01*
X406998Y-532568D01*
X407498Y-531635D01*
X408198Y-530968D01*
X408898Y-530835D01*
X409598Y-531102D01*
X410098Y-531768D01*
G01X416398Y-539102D02*
X416198Y-538968D01*
Y-538702D01*
X416398Y-538568D01*
X416598Y-538702D01*
Y-538968D01*
X416398Y-539102D01*
G01X422498Y-535502D02*
X423198Y-534568D01*
X423798Y-534035D01*
X424598Y-533768D01*
X425298Y-534035D01*
X425798Y-534568D01*
X426198Y-535368D01*
X426298Y-536302D01*
X426198Y-537102D01*
X425798Y-537902D01*
X425198Y-538568D01*
X424498Y-538835D01*
X423698Y-538568D01*
X422998Y-537769D01*
X422598Y-536568D01*
X422498Y-535235D01*
X422698Y-533502D01*
X422998Y-532568D01*
X423498Y-531635D01*
X424198Y-530968D01*
X424898Y-530835D01*
X425598Y-531102D01*
X426098Y-531768D01*
G01X445398Y-538835D02*
Y-530835D01*
X444198Y-532435D01*
G01Y-538835D02*
X446598D01*
G01X453198D02*
X453398Y-537102D01*
X453698Y-535635D01*
X454098Y-534302D01*
X454598Y-532835D01*
X455398Y-530835D01*
X451398D01*
G01X461398Y-539102D02*
X461198Y-538968D01*
Y-538702D01*
X461398Y-538568D01*
X461598Y-538702D01*
Y-538968D01*
X461398Y-539102D01*
G01X467498Y-532168D02*
X468098Y-531368D01*
X468798Y-530968D01*
X469598Y-530835D01*
X470598Y-531102D01*
X471298Y-531768D01*
X471498Y-532568D01*
X471398Y-533369D01*
X470998Y-534035D01*
X468998Y-535368D01*
X468098Y-536302D01*
X467498Y-537635D01*
X467298Y-538835D01*
X471498D01*
G01X465498Y-513835D02*
Y-505835D01*
X469298D01*
G01X467898Y-509702D02*
X465498D01*
G54D13*
X51043Y60709D03*
X153405D03*
X190325Y455492D03*
Y503760D03*
Y583957D03*
Y636752D03*
X255767Y60709D03*
X279360Y368760D03*
Y421555D03*
Y501752D03*
Y550020D03*
X358129Y60709D03*
X508130D03*
X610492D03*
X647411Y455492D03*
Y503760D03*
Y583957D03*
Y636752D03*
X712854Y60709D03*
X736446Y368760D03*
Y421555D03*
Y501752D03*
Y550020D03*
X815216Y60709D03*
X965216D03*
X1067578D03*
X1104498Y455492D03*
Y503760D03*
Y583957D03*
Y636752D03*
X1169940Y60709D03*
X1193533Y368760D03*
Y421555D03*
Y501752D03*
Y550020D03*
X1272302Y60709D03*
X1422303D03*
X1524665D03*
X1561585Y455492D03*
Y503760D03*
Y583957D03*
Y636752D03*
X1627027Y60709D03*
X1650620Y368760D03*
Y421555D03*
Y501752D03*
Y550020D03*
X1729389Y60709D03*
G54D22*
X563706Y1056423D03*
X559518Y1066535D03*
X563706Y1076647D03*
X583930Y1056423D03*
X573818Y1052235D03*
X583930Y1076647D03*
X588118Y1066535D03*
X573818Y1080835D03*
X760433Y1480906D03*
X756274Y1490945D03*
X760433Y1500984D03*
X780511Y1480906D03*
X770472Y1476747D03*
Y1505143D03*
X780511Y1500984D03*
X784670Y1490945D03*
X1477879Y1056423D03*
X1473691Y1066535D03*
X1477879Y1076647D03*
X1498103Y1056423D03*
X1487991Y1052235D03*
X1498103Y1076647D03*
X1487991Y1080835D03*
X1502291Y1066535D03*
G54D32*
G01X25819Y527726D02*
Y527965D01*
X27969Y530115D01*
Y570346D01*
X24223Y574092D01*
Y611227D01*
X32204Y619208D01*
Y633052D01*
X35706Y636554D01*
X59062D01*
X64692Y642184D01*
G01X25819Y544726D02*
Y544807D01*
X22432Y548194D01*
Y620057D01*
X27686Y625311D01*
G01X194063Y577716D02*
X195779Y576000D01*
X201299D01*
X203050Y577751D01*
X206450D01*
X221693Y592994D01*
Y594982D01*
G01X222289Y590895D02*
X209739Y578345D01*
Y556748D01*
X204674Y551683D01*
G01X376881Y518564D02*
X363265Y532180D01*
X343288D01*
X329753Y545715D01*
Y547768D01*
X327456Y550065D01*
G01X358491Y377173D02*
Y375507D01*
X389880Y344118D01*
Y336203D01*
X397283Y328800D01*
X401899D01*
X404800Y331701D01*
Y346500D01*
X412912Y354612D01*
Y362156D01*
X416656Y365900D01*
X437651D01*
X442100Y370349D01*
Y373420D01*
X448323Y379643D01*
G01X372300Y750000D02*
X426400D01*
X436679Y760279D01*
Y792579D01*
X459000Y814900D01*
Y831900D01*
X474700Y847600D01*
X479700D01*
G01X365850Y773950D02*
X405650D01*
X426300Y794600D01*
Y797400D01*
G01X381237Y371076D02*
X383991Y368322D01*
X402360D01*
X412282Y378244D01*
X430344D01*
X453726Y401626D01*
Y449210D01*
X444511Y458425D01*
X432855D01*
X429673Y461607D01*
G01X400993Y331589D02*
X398378D01*
X396958Y333009D01*
Y335202D01*
X400400Y338644D01*
Y349190D01*
X403400Y352190D01*
Y366802D01*
X413032Y376434D01*
X431734D01*
X455988Y400688D01*
Y444303D01*
X476580Y464895D01*
Y476720D01*
X475047Y478253D01*
Y571586D01*
X473520Y573113D01*
Y632863D01*
X490635Y649978D01*
X502379D01*
X515487Y663086D01*
Y666711D01*
X517418Y668642D01*
X519803D01*
X521868Y666577D01*
G01X400993Y335589D02*
X402576Y337172D01*
Y348625D01*
X405400Y351449D01*
Y366241D01*
X413783Y374624D01*
X432624D01*
X457897Y399897D01*
Y443512D01*
X478390Y464005D01*
Y477470D01*
X476857Y479003D01*
Y572336D01*
X475330Y573863D01*
Y632067D01*
X491431Y648168D01*
X504106D01*
X518812Y662874D01*
G01X411007Y356743D02*
X408775Y358975D01*
Y367056D01*
X414533Y372814D01*
X434115D01*
X453269Y391968D01*
X453271D01*
X460230Y398927D01*
Y442545D01*
X480200Y462515D01*
Y478220D01*
X478667Y479753D01*
Y573086D01*
X477140Y574613D01*
Y631278D01*
X492220Y646358D01*
X505022D01*
X525318Y666654D01*
Y682541D01*
X521540Y686319D01*
G01X426138Y355079D02*
X418036D01*
X410688Y347731D01*
Y344736D01*
G01X472399Y839566D02*
X462052Y829219D01*
Y813797D01*
X438489Y790234D01*
Y742763D01*
X424993Y729267D01*
Y728291D01*
G01D02*
X461209D01*
X472595Y716905D01*
Y664595D01*
X456469Y648469D01*
Y638302D01*
G01X459245Y807152D02*
X440238Y788145D01*
Y752413D01*
X474516Y718135D01*
Y663256D01*
X470300Y659040D01*
Y571777D01*
X471827Y570250D01*
Y524716D01*
X459645Y512534D01*
Y509486D01*
G01X450852Y372054D02*
X453000Y374202D01*
Y387143D01*
X454604Y388747D01*
X454605D01*
X463450Y397592D01*
Y441210D01*
X486690Y464450D01*
Y574850D01*
X482090Y579450D01*
Y592615D01*
X486844Y597369D01*
X506001D01*
X515980Y607348D01*
X517886D01*
X520683Y605479D01*
X520770Y605443D01*
G01X455885Y367702D02*
Y387467D01*
X465260Y396842D01*
Y440460D01*
X488500Y463700D01*
Y575600D01*
X483900Y580200D01*
Y591864D01*
X487595Y595559D01*
X506886D01*
X516770Y605443D01*
G01X448323Y379643D02*
X450322Y381642D01*
Y387026D01*
X453854Y390558D01*
X453856D01*
X461640Y398342D01*
Y441960D01*
X484880Y465200D01*
Y574100D01*
X480280Y578700D01*
Y593366D01*
X486093Y599179D01*
X505251D01*
X516288Y610216D01*
X521956D01*
X524770Y607402D01*
Y605637D01*
G01X468558Y499669D02*
X473237Y504348D01*
Y570836D01*
X471710Y572363D01*
Y658003D01*
X476200Y662493D01*
Y719428D01*
X441902Y753726D01*
Y785908D01*
X473654Y817660D01*
Y821234D01*
G01X482905Y527726D02*
Y528694D01*
X480397Y531202D01*
Y573803D01*
X478870Y575330D01*
Y630809D01*
X492461Y644400D01*
X519562D01*
X521778Y642184D01*
G01X651149Y577716D02*
X655749Y582316D01*
Y647874D01*
X657994Y650119D01*
X658064D01*
G01X661760Y551683D02*
X666825Y556748D01*
Y583816D01*
X658233Y592408D01*
Y646449D01*
G01X797318Y1471242D02*
X790572D01*
X772759Y1453429D01*
Y1451934D01*
X763900Y1443075D01*
Y1438300D01*
X763400Y1437800D01*
Y1430216D01*
X774383Y1419233D01*
X780311D01*
X783694Y1415850D01*
Y1410977D01*
G01X804919Y1489247D02*
Y1488114D01*
X770977Y1454172D01*
Y1452432D01*
X762363Y1443818D01*
Y1439000D01*
X761800Y1438437D01*
Y1429767D01*
X775369Y1416198D01*
X778685D01*
G01X765713Y1437365D02*
X773874Y1445526D01*
Y1447174D01*
X774848Y1448148D01*
X779979D01*
X783236Y1451405D01*
Y1453291D01*
X789432Y1459487D01*
Y1461617D01*
X788252Y1462797D01*
Y1464451D01*
X789190Y1465389D01*
X792794D01*
X794005Y1464178D01*
G01X796000Y553101D02*
X796135Y553236D01*
Y615590D01*
X784813Y626912D01*
X778860D01*
G01X797083Y1467883D02*
X797579Y1467387D01*
Y1463980D01*
X792696Y1459097D01*
X791604D01*
X788668Y1456161D01*
Y1449768D01*
X786995Y1448095D01*
X782783D01*
X778962Y1444274D01*
X775443D01*
X768910Y1437741D01*
G01X885884Y255118D02*
Y257225D01*
X881213Y261896D01*
Y263478D01*
X882700Y264965D01*
Y280000D01*
X876400Y286300D01*
X873700D01*
X844300Y315700D01*
Y342300D01*
X836659Y349941D01*
X823459D01*
X798821Y374579D01*
X794400Y385253D01*
Y400699D01*
X800490Y406789D01*
Y442990D01*
X804100Y446600D01*
Y494100D01*
X830238Y520238D01*
Y535487D01*
X830600Y537306D01*
Y630800D01*
X827900Y633500D01*
Y648558D01*
X810672Y665786D01*
Y727508D01*
X813902Y730738D01*
G01X825971Y345101D02*
X822200D01*
X799506Y367795D01*
X792300Y385191D01*
Y401700D01*
X798680Y408080D01*
Y443980D01*
X800100Y445400D01*
Y455300D01*
X801600Y456800D01*
Y494300D01*
X822764Y515464D01*
Y646839D01*
X805826Y663777D01*
Y740179D01*
X789404Y756601D01*
Y876704D01*
X818200Y905500D01*
X885001D01*
X887301Y907800D01*
X894449D01*
X919163Y883086D01*
G01X883118Y262687D02*
X884510Y264079D01*
Y280750D01*
X877150Y288110D01*
X874450D01*
X846110Y316450D01*
Y343050D01*
X837409Y351751D01*
X824349D01*
X800451Y375649D01*
X796400Y385428D01*
Y400100D01*
X802300Y406000D01*
Y442200D01*
X806200Y446100D01*
Y493601D01*
X832048Y519449D01*
Y535234D01*
X832500Y537508D01*
Y632201D01*
X829900Y634801D01*
Y649118D01*
X812482Y666536D01*
Y726483D01*
X817403Y731404D01*
Y733773D01*
X815700Y735476D01*
Y744809D01*
X813653Y746856D01*
G01X827500Y750000D02*
X828389Y749111D01*
Y736572D01*
X830020Y734941D01*
Y724063D01*
X821532Y715575D01*
Y671603D01*
X855894Y637241D01*
Y620802D01*
X840172Y605080D01*
Y524571D01*
X808200Y492599D01*
Y408700D01*
X798370Y398870D01*
Y385601D01*
X802027Y376772D01*
X824886Y353913D01*
X839088D01*
X842620Y350381D01*
X873634D01*
X888678Y335337D01*
Y281628D01*
X886496Y279446D01*
Y268968D01*
G01X789581Y405011D02*
Y408039D01*
X794790Y413248D01*
Y445950D01*
X796290Y447450D01*
Y457150D01*
X797980Y458840D01*
Y495800D01*
X819144Y516964D01*
Y645339D01*
X802206Y662277D01*
Y738679D01*
X785784Y755101D01*
Y887184D01*
X810700Y912100D01*
X815001D01*
X815501Y911600D01*
X868489D01*
X870543Y913654D01*
Y919982D01*
X870934Y920373D01*
X882297D01*
X884628Y918042D01*
G01X880628D02*
X878705Y916119D01*
Y912790D01*
X877987Y912072D01*
X873527D01*
X871155Y909700D01*
X814799D01*
X814299Y910200D01*
X811700D01*
X787594Y886094D01*
Y755851D01*
X804016Y739429D01*
Y663027D01*
X820954Y646089D01*
Y516214D01*
X799790Y495050D01*
Y458090D01*
X798100Y456400D01*
Y446700D01*
X796600Y445200D01*
Y412209D01*
X793893Y409502D01*
G01X919163Y879937D02*
Y880811D01*
X896374Y903600D01*
X818600D01*
X791030Y876030D01*
Y757275D01*
X807452Y740853D01*
Y664451D01*
X824390Y647513D01*
Y535990D01*
X827280Y533100D01*
X827291D01*
G01X849267Y892567D02*
X848534Y893300D01*
X841177D01*
X837520Y896957D01*
X833274D01*
X831848Y895531D01*
Y893300D01*
X828648Y890100D01*
X824537D01*
X810567Y876130D01*
X808950D01*
X794250Y861430D01*
Y760407D01*
X813678Y740979D01*
G01X848322Y888421D02*
X847970Y888773D01*
X844824Y890077D01*
X837056D01*
X835800Y888821D01*
X830599D01*
X829461Y887683D01*
X824681D01*
X811318Y874320D01*
X809700D01*
X796060Y860680D01*
Y764449D01*
X813653Y746856D01*
G01X837276Y883459D02*
Y884639D01*
X835454Y886461D01*
X832299D01*
X831003Y885165D01*
Y883745D01*
X827436Y880178D01*
X819737D01*
X812069Y872510D01*
X810450D01*
X797870Y859930D01*
Y765334D01*
X817811Y745393D01*
Y736059D01*
X819600Y734270D01*
Y731076D01*
X817127Y728506D01*
X814292Y725671D01*
Y667286D01*
X831900Y649678D01*
Y636800D01*
X835000Y633700D01*
Y536803D01*
X834282Y536085D01*
G01X916014Y879937D02*
Y881867D01*
X895702Y902179D01*
X819179D01*
X792440Y875440D01*
Y757860D01*
X808862Y741438D01*
Y665036D01*
X825800Y648098D01*
Y541149D01*
X828382Y538567D01*
Y535572D01*
X828272Y535462D01*
G01X850544Y1447559D02*
X843273Y1440288D01*
Y1430873D01*
X832879Y1420479D01*
X803414D01*
X796509Y1427384D01*
Y1441990D01*
X794999Y1443500D01*
X793299D01*
X791198Y1441399D01*
X790754D01*
G01X845306Y1430692D02*
X833614Y1419000D01*
X800824D01*
X791366Y1428458D01*
Y1438871D01*
X793994Y1441499D01*
G01X850900Y888359D02*
Y888075D01*
X848320Y885495D01*
X842421D01*
X838448Y881522D01*
X836278D01*
X834178Y879422D01*
X829623D01*
X828569Y878368D01*
X820489D01*
X812821Y870700D01*
X811200D01*
X799680Y859180D01*
Y766085D01*
X819621Y746144D01*
Y742679D01*
X822000Y740300D01*
Y735128D01*
X821500Y734628D01*
Y730224D01*
X816102Y724826D01*
Y668036D01*
X833800Y650338D01*
Y638299D01*
X838000Y634099D01*
Y532449D01*
X836172Y530621D01*
X833953D01*
G01X817584Y764219D02*
X817146D01*
X812500Y768865D01*
Y801300D01*
X822300Y811100D01*
Y833100D01*
X821800Y833600D01*
Y844300D01*
X825000Y847500D01*
Y853552D01*
X830948Y859500D01*
X836875D01*
X838775Y861400D01*
X851881D01*
X854779Y858502D01*
Y851054D01*
X851239Y847514D01*
Y847459D01*
G01X848200Y883400D02*
Y882899D01*
X846732Y881431D01*
X843468D01*
X839563Y877526D01*
X830430D01*
X829462Y876558D01*
X821239D01*
X813571Y868890D01*
X811950D01*
X801490Y858430D01*
Y766835D01*
X821431Y746894D01*
Y743430D01*
X824000Y740861D01*
Y735841D01*
X826400Y733441D01*
Y725563D01*
X817912Y717075D01*
Y668788D01*
X836360Y650340D01*
Y639890D01*
X845797Y630453D01*
X853989D01*
G01X848384Y879459D02*
Y878880D01*
X842904Y873400D01*
X836151D01*
X833851Y875700D01*
X832499D01*
X828899Y872100D01*
X825901D01*
X824401Y873600D01*
X820841D01*
X814321Y867080D01*
X812700D01*
X803300Y857680D01*
Y767586D01*
X823241Y747645D01*
Y744181D01*
X825900Y741522D01*
Y736501D01*
X828210Y734191D01*
Y724813D01*
X819722Y716325D01*
Y669878D01*
X838472Y651128D01*
Y640765D01*
X846284Y632953D01*
X853989D01*
G01X824500Y756000D02*
X822274D01*
X820200Y758074D01*
Y764500D01*
X814310Y770390D01*
Y800510D01*
X827000Y813200D01*
Y816300D01*
X824600Y818700D01*
Y834700D01*
X823800Y835500D01*
Y842201D01*
X826900Y845301D01*
Y852792D01*
X831629Y857521D01*
X838178D01*
X839027Y856672D01*
X845164D01*
X845836Y856000D01*
Y855959D01*
X846336Y855459D01*
G01X898533Y334498D02*
X895710Y337321D01*
X889360D01*
X874570Y352111D01*
X874464D01*
X874384Y352191D01*
X844161D01*
X841720Y354632D01*
Y357712D01*
X841759Y357751D01*
Y396640D01*
X827702Y410697D01*
Y413315D01*
X827703Y413316D01*
Y457004D01*
X828800Y458101D01*
Y472600D01*
X823800Y477600D01*
X821900D01*
X819700Y479800D01*
Y485600D01*
X824600Y490500D01*
Y506439D01*
X841982Y523821D01*
Y604330D01*
X857704Y620052D01*
Y637991D01*
X830800Y664895D01*
Y664953D01*
X830790Y664963D01*
Y670549D01*
X830800Y670559D01*
Y671951D01*
X832223Y673374D01*
Y721123D01*
X836177Y725077D01*
Y733481D01*
X834500Y735158D01*
Y755698D01*
X817930Y772268D01*
Y782270D01*
X824260Y788600D01*
X825830D01*
X826135Y788905D01*
X827805D01*
X837690Y798790D01*
Y814649D01*
X838799Y815758D01*
Y826237D01*
X836839Y828197D01*
Y831301D01*
G01X848384Y835459D02*
X848188Y835263D01*
Y828102D01*
X845661Y825575D01*
Y777035D01*
X838818Y770192D01*
Y755079D01*
X836400Y752661D01*
Y743903D01*
X838678Y741625D01*
Y736159D01*
X838006Y735487D01*
Y724346D01*
X834033Y720373D01*
Y671232D01*
X832600Y669799D01*
Y665713D01*
X859514Y638799D01*
Y619302D01*
X843792Y603580D01*
Y523071D01*
X826500Y505779D01*
Y489100D01*
X824800Y487400D01*
Y479300D01*
X830900Y473200D01*
Y457299D01*
X829513Y455912D01*
Y443587D01*
X833700Y439400D01*
Y407259D01*
X843570Y397389D01*
Y357002D01*
X843530Y356962D01*
Y355382D01*
X844911Y354001D01*
X866197D01*
X872158Y359962D01*
G01X845435Y356172D02*
Y397965D01*
X845380Y398020D01*
Y398139D01*
X836782Y406737D01*
Y469918D01*
X826700Y480000D01*
Y485300D01*
X828800Y487400D01*
Y505100D01*
X845700Y522000D01*
Y602927D01*
X864100Y621327D01*
Y663399D01*
X861346Y666153D01*
Y678805D01*
X861306Y678845D01*
Y683295D01*
X859583Y685018D01*
Y693143D01*
X860766Y694326D01*
Y729206D01*
X866800Y735240D01*
Y753600D01*
X863200Y757200D01*
Y764399D01*
X866900Y768099D01*
Y771200D01*
X862810Y775290D01*
Y783354D01*
X859520Y786644D01*
Y788907D01*
X859791Y789561D01*
X861000Y790770D01*
Y800700D01*
X854200Y807500D01*
Y816640D01*
X848335Y822505D01*
Y823391D01*
X848224Y823502D01*
G01X836894Y824401D02*
Y816413D01*
X835880Y815399D01*
Y799540D01*
X827055Y790715D01*
X825385D01*
X825080Y790410D01*
X823510D01*
X816120Y783020D01*
Y771518D01*
X823710Y763928D01*
Y762405D01*
X822595Y761290D01*
Y759710D01*
X823710Y758595D01*
X825290D01*
X826405Y759710D01*
X827928D01*
X832690Y754948D01*
Y734408D01*
X834240Y732858D01*
Y725723D01*
X826600Y718083D01*
Y679689D01*
X829496Y676793D01*
G01X851184Y851459D02*
X849242Y849517D01*
X845516D01*
X842041Y846042D01*
Y816440D01*
X839500Y813899D01*
Y793787D01*
X831980Y786267D01*
Y786210D01*
X830865Y785095D01*
X830808D01*
X830213Y784500D01*
X823901D01*
X823806Y784405D01*
X823710D01*
X822595Y783290D01*
Y775905D01*
X824500Y774000D01*
G01Y782500D02*
X833500D01*
X843851Y792851D01*
Y838926D01*
X848384Y843459D01*
G01X824342Y792315D02*
X822595Y794062D01*
Y806235D01*
X832260Y815900D01*
Y824540D01*
X827852Y828948D01*
Y843653D01*
X830000Y845801D01*
Y849001D01*
X834499Y853500D01*
X847689D01*
X848404Y854215D01*
Y858193D01*
X847138Y859459D01*
G01X848384Y863459D02*
Y864617D01*
X847677Y865324D01*
X837281D01*
X833313Y861356D01*
X829863D01*
X824007Y855500D01*
X823000D01*
X819900Y852400D01*
Y832301D01*
X820405Y831796D01*
Y812040D01*
X818500Y810135D01*
G01X848384Y851459D02*
X844758D01*
X842699Y849400D01*
X836400D01*
X836000Y849800D01*
X834299D01*
X832252Y847753D01*
Y827108D01*
X834070Y825290D01*
Y813970D01*
X830945Y810845D01*
Y810137D01*
X832047Y809035D01*
Y808285D01*
X831361Y807599D01*
X830611D01*
X828959Y809251D01*
X828251D01*
X824500Y805500D01*
Y800500D01*
G01X817845Y817879D02*
X817942Y817976D01*
Y855798D01*
X822944Y860800D01*
X826747D01*
X828284Y862337D01*
Y865396D01*
X832287Y869399D01*
X847414D01*
X848384Y868429D01*
Y867459D01*
G01X912864Y879937D02*
X902695Y890106D01*
X897129D01*
X886535Y900700D01*
X822200D01*
X820500Y899000D01*
Y893691D01*
X817139Y890330D01*
G01X818031Y907747D02*
X872259D01*
X874412Y909900D01*
X896069D01*
X921318Y884651D01*
G01X887148Y249670D02*
X885382D01*
X882853Y252199D01*
Y257695D01*
X879403Y261145D01*
Y264229D01*
X880890Y265716D01*
Y278870D01*
X875456Y284304D01*
X873011D01*
X842240Y315075D01*
Y324854D01*
G01X851184Y835459D02*
X853049Y833594D01*
Y827004D01*
X856600Y823453D01*
Y807660D01*
X863430Y800830D01*
Y792342D01*
X864700Y791072D01*
Y791070D01*
X866480Y789290D01*
Y787710D01*
X864700Y785930D01*
Y778995D01*
X869000Y774695D01*
Y765800D01*
X866100Y762900D01*
Y756900D01*
X868600Y754400D01*
Y754360D01*
X868610Y754350D01*
Y734310D01*
X862577Y728277D01*
Y692564D01*
X861583Y691570D01*
Y686591D01*
X863832Y684342D01*
Y666769D01*
X866100Y664501D01*
Y620766D01*
X847700Y602366D01*
Y521099D01*
X836300Y509699D01*
Y473400D01*
X838700Y471000D01*
Y407379D01*
X847190Y398889D01*
Y398770D01*
X847245Y398715D01*
Y362483D01*
X848879Y360849D01*
G01X852569Y356712D02*
Y360899D01*
X849055Y364413D01*
Y399465D01*
X849000Y399520D01*
Y399639D01*
X840600Y408039D01*
Y471900D01*
X838200Y474300D01*
Y509000D01*
X849600Y520400D01*
Y601705D01*
X868300Y620405D01*
Y665300D01*
X867910Y665690D01*
Y665803D01*
X866400Y667313D01*
Y701250D01*
X870520Y705370D01*
Y711962D01*
X869117Y713365D01*
Y720498D01*
X871059Y722440D01*
Y729559D01*
X879700Y738200D01*
X884980D01*
X886881Y740101D01*
Y751619D01*
X879900Y758600D01*
Y775489D01*
X874700Y788044D01*
Y794605D01*
X871297Y798008D01*
Y799599D01*
X871940Y800242D01*
Y800256D01*
X872500Y800816D01*
Y813283D01*
X870783Y815000D01*
Y819746D01*
X867000Y823529D01*
Y863199D01*
X858740Y871459D01*
X851184D01*
G01X856069Y356426D02*
X857004Y357361D01*
Y361165D01*
X850900Y367269D01*
Y400399D01*
X843725Y407574D01*
Y458337D01*
X846000Y460612D01*
Y474400D01*
X844400Y476000D01*
X843000D01*
X840200Y478800D01*
Y508201D01*
X851500Y519501D01*
Y601044D01*
X870300Y619844D01*
Y652127D01*
X876814Y658641D01*
Y669519D01*
X878538Y671243D01*
Y699451D01*
X872891Y705098D01*
Y712760D01*
X870927Y714724D01*
Y719748D01*
X873139Y721960D01*
Y728939D01*
X880500Y736300D01*
X886000D01*
X888700Y739000D01*
Y753000D01*
X887100Y754600D01*
Y772699D01*
X882900Y776899D01*
Y777139D01*
X882890Y777149D01*
Y787211D01*
X880055Y790046D01*
X878878D01*
X877235Y791689D01*
Y794013D01*
X878878Y795656D01*
X878934D01*
X879377Y796099D01*
Y798901D01*
X878000Y800278D01*
Y815089D01*
X869000Y824089D01*
Y864051D01*
X857592Y875459D01*
X851184D01*
G01X879916Y808965D02*
Y801380D01*
X881268Y800028D01*
Y797232D01*
X882900Y795600D01*
Y790400D01*
X884700Y788600D01*
Y777899D01*
X889200Y773399D01*
Y755500D01*
X890600Y754100D01*
Y738000D01*
X886900Y734300D01*
X881400D01*
X876600Y729500D01*
Y711600D01*
X877825Y710375D01*
Y704657D01*
X881300Y701182D01*
Y659208D01*
X872600Y650508D01*
Y619583D01*
X853500Y600483D01*
Y518700D01*
X847942Y513142D01*
Y459743D01*
X845900Y457701D01*
Y412092D01*
X854009Y403983D01*
X856200Y398693D01*
Y372900D01*
X860829Y368271D01*
X869370D01*
X900900Y336741D01*
Y324465D01*
X890824Y314389D01*
Y314370D01*
X890741Y314287D01*
Y279686D01*
X888591Y277536D01*
Y252763D01*
X893544Y247810D01*
Y242430D01*
X887215Y236101D01*
Y210527D01*
X899573Y198169D01*
Y158195D01*
G01X849500Y794500D02*
Y787220D01*
X855120Y781600D01*
Y748761D01*
X857294Y746587D01*
Y733414D01*
X854380Y730500D01*
Y727500D01*
X849810Y722930D01*
Y702650D01*
X847440Y700280D01*
Y666304D01*
X853982Y659762D01*
Y657506D01*
G01X848444Y657756D02*
Y661493D01*
X845630Y664307D01*
Y701030D01*
X848000Y703400D01*
Y723680D01*
X852420Y728100D01*
Y748807D01*
X853310Y749697D01*
Y780850D01*
X847471Y786689D01*
Y798971D01*
X848000Y799500D01*
X849500D01*
G01Y776500D02*
Y771700D01*
X843927Y766127D01*
Y751209D01*
X841000Y748282D01*
Y735970D01*
X840488Y735458D01*
Y735409D01*
X839996Y734917D01*
Y723496D01*
X838200Y721700D01*
Y708553D01*
X835843Y706196D01*
Y670144D01*
X834598Y668899D01*
Y666584D01*
X837272Y663910D01*
G01X849500Y781500D02*
X850100D01*
X851500Y780100D01*
Y771140D01*
X845737Y765377D01*
Y750459D01*
X843200Y747922D01*
Y735610D01*
X842298Y734708D01*
Y734659D01*
X841825Y734186D01*
Y722725D01*
X840200Y721100D01*
Y667097D01*
X839636Y666533D01*
G01X849500Y758500D02*
X848800Y757800D01*
Y737216D01*
X843996Y732412D01*
Y732299D01*
X843923Y732226D01*
Y721623D01*
X842010Y719710D01*
Y666207D01*
X840195Y664392D01*
Y661400D01*
X842352Y659243D01*
G01X849500Y763500D02*
X849799D01*
X851405Y761894D01*
Y750352D01*
X850610Y749557D01*
Y736466D01*
X845806Y731662D01*
Y720906D01*
X843820Y718920D01*
Y663994D01*
X842640Y662814D01*
G01X849500Y817500D02*
X848000D01*
X847471Y816971D01*
Y805429D01*
X852000Y800900D01*
Y793280D01*
X851377Y792657D01*
Y787903D01*
X856930Y782350D01*
Y751970D01*
X862714Y746186D01*
Y736274D01*
X856190Y729750D01*
Y726750D01*
X851700Y722260D01*
Y688700D01*
X849955Y686955D01*
Y667002D01*
X856706Y660251D01*
Y650214D01*
X855300Y646819D01*
G01X859165Y848728D02*
X855930Y845493D01*
X846615D01*
X846239Y845869D01*
Y847490D01*
G01X845306Y1438269D02*
Y1430692D01*
G01D02*
X856615Y1419383D01*
X880269D01*
X892244Y1431358D01*
Y1440859D01*
G01X836704Y1440849D02*
X834445Y1443108D01*
Y1456368D01*
X835474Y1457397D01*
G01X874649Y545296D02*
X867801D01*
X859990Y553107D01*
Y604412D01*
X879135Y623557D01*
Y632552D01*
G01X849500Y812500D02*
Y806400D01*
X855500Y800400D01*
Y788104D01*
X861000Y782604D01*
Y772900D01*
X859200Y771100D01*
Y768500D01*
X861102Y766598D01*
Y751297D01*
X864524Y747875D01*
Y735524D01*
X858000Y729000D01*
Y726000D01*
X853741Y721741D01*
Y718135D01*
X854300Y717576D01*
X855541D01*
X856100Y717017D01*
Y716225D01*
X855541Y715666D01*
X854300D01*
X853741Y715107D01*
Y714315D01*
X854300Y713756D01*
X855541D01*
X856100Y713197D01*
Y712405D01*
X855541Y711846D01*
X854300D01*
X853741Y711287D01*
Y710495D01*
X854300Y709936D01*
X855541D01*
X856100Y709377D01*
Y708585D01*
X855541Y708026D01*
X854300D01*
X853741Y707467D01*
Y706675D01*
X854300Y706116D01*
X855541D01*
X856100Y705557D01*
Y704765D01*
X855541Y704206D01*
X854300D01*
X853741Y703647D01*
Y702855D01*
X854300Y702296D01*
X855541D01*
X856100Y701737D01*
Y700945D01*
X855541Y700386D01*
X854300D01*
X853741Y699827D01*
Y687341D01*
X852083Y685683D01*
Y667434D01*
X858516Y661001D01*
Y649854D01*
X858501Y649815D01*
X861663Y646653D01*
G01X851184Y843459D02*
X855500Y839143D01*
Y827113D01*
X858945Y823668D01*
Y823555D01*
X861000Y821500D01*
X862679D01*
X867179Y817000D01*
Y813710D01*
X869040Y811849D01*
Y805934D01*
X866700Y803594D01*
Y795399D01*
X869649Y792450D01*
Y788795D01*
X874683Y776643D01*
Y758012D01*
X870600Y753929D01*
Y732700D01*
X864387Y726487D01*
Y691814D01*
X864307Y691734D01*
Y691592D01*
X864029Y691314D01*
Y688970D01*
G01X858988Y898307D02*
X860973Y896322D01*
X883066D01*
X889253Y890135D01*
Y881500D01*
G01X850544Y1447559D02*
Y1427556D01*
X857100Y1421000D01*
X879300D01*
X885387Y1427087D01*
Y1444229D01*
X890794Y1449636D01*
X892244D01*
G01X887916Y808965D02*
Y804148D01*
X889900Y802164D01*
Y798922D01*
X891332Y797490D01*
Y795008D01*
X892700Y793640D01*
Y788601D01*
X895200Y786101D01*
Y786026D01*
X895345Y785881D01*
Y783141D01*
X892910Y780706D01*
Y757150D01*
X894500Y755560D01*
Y731301D01*
X884400Y721201D01*
Y712492D01*
X887600Y709292D01*
Y702058D01*
X890300Y699358D01*
Y660398D01*
X881600Y651698D01*
Y623461D01*
X864700Y606561D01*
Y553898D01*
X866811Y551787D01*
X873238D01*
X878000Y547025D01*
Y535500D01*
X916500Y497000D01*
X923777D01*
X952300Y468477D01*
Y402837D01*
X934189Y384726D01*
X909486D01*
X901218Y376458D01*
Y346679D01*
X902849Y345048D01*
Y323854D01*
X892634Y313639D01*
Y278942D01*
X890573Y276881D01*
Y258639D01*
X895360Y253852D01*
Y252248D01*
X895064Y251952D01*
Y250186D01*
G01X878220Y845293D02*
X873100Y840173D01*
Y825900D01*
X877606Y821394D01*
X882125D01*
X889719Y813800D01*
X892100D01*
X894000Y811900D01*
Y805763D01*
X897904Y801859D01*
Y799596D01*
X902400Y795100D01*
Y784099D01*
X896130Y777829D01*
Y758485D01*
X897880Y756735D01*
Y721946D01*
X891341Y715407D01*
Y715180D01*
X891100Y714939D01*
Y702300D01*
X893400Y700000D01*
Y670299D01*
X894366Y669333D01*
Y660765D01*
X883900Y650299D01*
Y623200D01*
X870183Y609483D01*
Y558004D01*
X880171Y548016D01*
Y536048D01*
X917322Y498897D01*
X924476D01*
X955373Y468000D01*
X956400D01*
X957900Y466500D01*
Y462801D01*
X954500Y459401D01*
Y402005D01*
X932406Y379911D01*
X909323D01*
X907116Y377704D01*
Y376122D01*
X909322Y373916D01*
Y362839D01*
X903136Y356653D01*
Y348261D01*
X904911Y346486D01*
Y323279D01*
X895032Y313400D01*
Y283956D01*
X898055Y280933D01*
X913351D01*
X916453Y277831D01*
Y167975D01*
G01X879135Y632552D02*
Y652336D01*
X888300Y661501D01*
Y698297D01*
X884971Y701626D01*
Y709229D01*
X879555Y714645D01*
Y729655D01*
X882200Y732300D01*
X888200D01*
X892500Y736600D01*
Y755000D01*
X891100Y756400D01*
Y774399D01*
X886600Y778899D01*
Y789400D01*
X884900Y791100D01*
Y794700D01*
X886200Y796000D01*
Y798531D01*
X883916Y800815D01*
G01X870035Y801032D02*
X868600Y799597D01*
Y796059D01*
X872620Y792039D01*
Y787136D01*
X876600Y777520D01*
Y755012D01*
X876570Y754982D01*
Y752242D01*
X876600Y752212D01*
Y751372D01*
X874142Y748914D01*
G01X893241Y704656D02*
Y713710D01*
X899290Y719759D01*
Y757320D01*
X897700Y758910D01*
Y777100D01*
X903900Y783300D01*
Y798500D01*
X904600Y799200D01*
Y802595D01*
X902711Y804484D01*
X899279D01*
X897879Y805884D01*
Y811321D01*
X893471Y815729D01*
X889919D01*
X879794Y825854D01*
Y829906D01*
X875000Y834700D01*
Y838800D01*
X879785Y843585D01*
G01X885126Y889742D02*
X879042D01*
X871300Y882000D01*
Y824901D01*
X877724Y818477D01*
X881042D01*
X887919Y811600D01*
X889100D01*
X890000Y810700D01*
Y805513D01*
X893900Y801613D01*
Y795516D01*
X894900Y794516D01*
Y789900D01*
X897635Y787165D01*
Y781636D01*
X894720Y778721D01*
Y757900D01*
X896470Y756150D01*
Y729005D01*
X889525Y722060D01*
G01X881370Y845293D02*
Y842570D01*
X876500Y837700D01*
Y835200D01*
X882128Y829572D01*
Y826272D01*
X890400Y818000D01*
X894324D01*
X902004Y810320D01*
Y807556D01*
X906400Y803160D01*
Y797400D01*
X905400Y796400D01*
Y782173D01*
X899110Y775883D01*
Y759495D01*
X900700Y757905D01*
Y717792D01*
X896114Y713206D01*
Y706356D01*
X907238Y695232D01*
Y685762D01*
X911417Y681583D01*
X923688D01*
X925011Y680260D01*
X928703D01*
X928704Y680261D01*
G01X913858Y721289D02*
Y722744D01*
X943348Y752234D01*
Y776052D01*
X925410Y793990D01*
X922817D01*
X918881Y797926D01*
Y798020D01*
X918880Y798021D01*
Y802017D01*
X916832Y804065D01*
X909967D01*
X905879Y808153D01*
Y814983D01*
X900799Y820063D01*
X890937D01*
X884460Y826540D01*
Y830244D01*
X883800Y830904D01*
Y836700D01*
X882900Y837600D01*
Y841600D01*
G01X895050Y828548D02*
Y829547D01*
X897118Y831615D01*
Y842143D01*
G01X886100Y841200D02*
X889800Y837500D01*
Y832193D01*
X888168Y830561D01*
Y827340D01*
X891275Y824233D01*
X903365D01*
X910898Y816700D01*
X918750D01*
X924455Y810995D01*
Y801356D01*
X926976Y798835D01*
Y796630D01*
X936751Y786855D01*
X936757D01*
X946168Y777444D01*
Y777438D01*
X947400Y776206D01*
Y733862D01*
X951151Y730111D01*
G01X902841Y703665D02*
Y714127D01*
X907069Y718355D01*
X916792D01*
X920061Y721624D01*
Y725327D01*
X945400Y750666D01*
Y776211D01*
X944758Y776853D01*
Y776859D01*
X936172Y785445D01*
X936166D01*
X925739Y795872D01*
X922930D01*
X920291Y798511D01*
Y803963D01*
X918014Y806240D01*
X910022D01*
X907328Y808934D01*
Y817769D01*
X903045Y822052D01*
X891270D01*
X886087Y827235D01*
Y831687D01*
X887930Y833530D01*
Y836971D01*
X884519Y840382D01*
Y842143D01*
G01X1049087Y856033D02*
Y861431D01*
X1044398Y866120D01*
X1033189D01*
X1022100Y877209D01*
Y879690D01*
X1016885Y884905D01*
X1016880D01*
X1012900Y888885D01*
Y893841D01*
X989182Y917559D01*
X988149D01*
X987367Y918341D01*
X985269Y919210D01*
X984490D01*
X971469Y932231D01*
X970869D01*
X963200Y939900D01*
X916500D01*
X896553Y919953D01*
Y918042D01*
G01X892628Y915242D02*
Y918527D01*
X915701Y941600D01*
X973075D01*
X1011200Y903475D01*
Y898861D01*
X1014830Y895231D01*
Y889070D01*
X1023800Y880100D01*
Y877504D01*
X1033774Y867530D01*
X1045338D01*
X1051123Y861745D01*
Y843146D01*
X1052500Y841769D01*
Y841200D01*
G01X1053909Y855472D02*
Y861005D01*
X1045974Y868940D01*
X1034359D01*
X1025400Y877899D01*
Y880499D01*
X1021985Y883914D01*
Y888421D01*
X1016792Y893614D01*
Y895264D01*
X1012610Y899446D01*
Y904060D01*
X973660Y943010D01*
X973590D01*
X973500Y943100D01*
X914400D01*
X890533Y919233D01*
Y917252D01*
X888628Y915347D01*
Y915242D01*
G01X888400Y994579D02*
X890121Y996300D01*
X893999D01*
X914331Y1016632D01*
Y1107899D01*
X918700Y1112268D01*
Y1304699D01*
X929101Y1315100D01*
X991702D01*
X1002250Y1325648D01*
X1004147Y1330227D01*
X1004148Y1330229D01*
X1037870Y1363950D01*
Y1409750D01*
X1050370Y1422250D01*
Y1471150D01*
X1043570Y1477950D01*
Y1502050D01*
X1083370Y1541850D01*
Y1586278D01*
X1078461Y1591187D01*
Y1632761D01*
X1086700Y1641000D01*
X1102900D01*
X1105474Y1638426D01*
G01X894660Y994330D02*
X920700Y1020370D01*
Y1303848D01*
X929776Y1312924D01*
X992086D01*
X1003786Y1324624D01*
X1005683Y1329203D01*
X1005731Y1329251D01*
X1005732Y1329253D01*
X1039680Y1363200D01*
Y1409000D01*
X1052180Y1421500D01*
Y1471900D01*
X1045380Y1478700D01*
Y1501300D01*
X1085180Y1541100D01*
Y1587029D01*
X1080271Y1591938D01*
Y1630972D01*
X1087512Y1638213D01*
X1089474D01*
G01X946970Y786366D02*
X941906D01*
X941359Y786913D01*
X941346Y786911D01*
X931293Y796964D01*
Y808174D01*
X912177Y827290D01*
Y830633D01*
X908100Y834710D01*
Y838100D01*
G01X950699Y779711D02*
X946551D01*
X929883Y796379D01*
Y807562D01*
X919208Y818237D01*
X912626D01*
X904000Y826863D01*
Y842728D01*
X906565Y845293D01*
G01X957579Y744168D02*
X959470Y746059D01*
Y788630D01*
X956500Y791600D01*
X953500D01*
X951800Y793300D01*
Y797900D01*
X949536Y800164D01*
Y810937D01*
X946924Y813549D01*
X932687D01*
X929821Y816415D01*
Y817805D01*
X929812Y817814D01*
Y818089D01*
X911279Y836622D01*
Y838289D01*
G01X985921Y805135D02*
Y806808D01*
X983300Y809429D01*
Y817245D01*
X980395Y820150D01*
Y822739D01*
X981000Y823344D01*
X981039D01*
X984110Y826415D01*
Y826443D01*
X984600Y826933D01*
Y840027D01*
X979505Y845122D01*
X974574D01*
X968100Y851596D01*
Y860434D01*
X970295Y862629D01*
Y875805D01*
X949434Y896666D01*
X935733D01*
X933199Y899200D01*
X923100D01*
X912628Y909672D01*
Y915242D01*
G01X1013151Y756726D02*
Y770473D01*
X984000Y799624D01*
Y806282D01*
X977100Y813182D01*
Y816801D01*
X977073Y816828D01*
Y819227D01*
X975760Y820540D01*
Y822105D01*
X978409Y824754D01*
X980454D01*
X982700Y827000D01*
Y827028D01*
X983190Y827518D01*
Y839210D01*
X978700Y843700D01*
X974449D01*
X974439Y843710D01*
X973991D01*
X965413Y852288D01*
Y878639D01*
X949115Y894937D01*
X934963D01*
X932200Y897700D01*
X922001D01*
X908628Y911073D01*
Y915242D01*
G01Y918042D02*
X914723Y924137D01*
Y929722D01*
X917091Y932090D01*
X959783D01*
X960369Y931504D01*
X965596D01*
X969300Y927800D01*
X969791D01*
X982795Y914796D01*
X984127D01*
X985179Y914360D01*
X986210Y913329D01*
X987427D01*
X1008226Y892530D01*
Y887574D01*
X1014300Y881500D01*
Y873502D01*
X1015421Y872381D01*
X1020525D01*
X1034427Y858479D01*
X1035121D01*
X1046045Y847555D01*
Y841217D01*
G01X900628Y915242D02*
X902758Y917372D01*
Y923631D01*
X917617Y938490D01*
X958953D01*
X960424Y937019D01*
Y935439D01*
X961539Y934324D01*
X966777D01*
X970481Y930620D01*
X970961D01*
X983965Y917616D01*
X985041D01*
X986529Y917000D01*
X987380Y916149D01*
X988597D01*
X1011046Y893700D01*
Y888744D01*
X1016295Y883495D01*
X1016300D01*
X1020288Y879507D01*
Y877013D01*
X1029801Y867500D01*
X1029814D01*
X1032604Y864710D01*
X1043648D01*
X1046400Y861958D01*
Y856006D01*
X1049417Y852989D01*
Y838734D01*
X1050358Y837793D01*
G01X1040822Y841339D02*
Y850777D01*
X1034530Y857069D01*
X1033842D01*
X1019940Y870971D01*
X1014836D01*
X1012890Y872917D01*
Y880796D01*
X1006816Y886870D01*
Y891945D01*
X986842Y911919D01*
X985625D01*
X984446Y913098D01*
X983751Y913386D01*
X982210D01*
X969696Y925900D01*
X969000D01*
X965200Y929700D01*
X959500D01*
X959194Y930006D01*
X923838D01*
X922723Y928891D01*
Y926824D01*
X921699Y925800D01*
X920386D01*
X912628Y918042D01*
G01X1044390Y861210D02*
X1043069Y859889D01*
X1035012D01*
X1018878Y876023D01*
Y878922D01*
X1015715Y882085D01*
X1015710D01*
X1009636Y888159D01*
Y893115D01*
X988012Y914739D01*
X986795D01*
X985941Y915593D01*
X984461Y916206D01*
X983380D01*
X970376Y929210D01*
X969890D01*
X966186Y932914D01*
X960954D01*
X960368Y933500D01*
X914622D01*
X904838Y923716D01*
Y918042D01*
G01X930754Y1310564D02*
X922599Y1302409D01*
Y1019187D01*
X897825Y994413D01*
G01X960376Y392807D02*
Y467124D01*
X957500Y470000D01*
X955600D01*
X927900Y497700D01*
Y662500D01*
X927500Y662900D01*
Y667501D01*
X929744Y669745D01*
X951001D01*
X994300Y713044D01*
Y787199D01*
X982600Y798899D01*
Y799029D01*
X982590Y799039D01*
Y805697D01*
X975690Y812597D01*
Y816216D01*
X975663Y816243D01*
Y818642D01*
X974350Y819955D01*
Y823250D01*
X977600Y826500D01*
X980000D01*
X981600Y828100D01*
Y838700D01*
X978010Y842290D01*
X973864D01*
X973854Y842300D01*
X973338D01*
X964003Y851635D01*
Y878054D01*
X948530Y893527D01*
X931781D01*
X929787Y891533D01*
X927610D01*
X922313Y886236D01*
G01X922626Y633772D02*
X920090Y636308D01*
Y666714D01*
G01X928353Y686342D02*
Y688254D01*
X961600Y721501D01*
Y730100D01*
X962045Y730545D01*
Y736856D01*
X960880Y738021D01*
Y798628D01*
X960650Y798858D01*
Y798864D01*
X955310Y804204D01*
Y813086D01*
X952786Y815610D01*
X949790D01*
X948371Y817029D01*
X941971D01*
X940442Y818558D01*
Y822941D01*
X936183Y827200D01*
X931600D01*
X930800Y826400D01*
X928900D01*
X924100Y831200D01*
Y844000D01*
G01X923900Y858600D02*
X923000Y859500D01*
X918201D01*
X914450Y863251D01*
G01X927916Y817015D02*
Y815250D01*
X931427Y811739D01*
X946174D01*
X947500Y810413D01*
Y793500D01*
X948000Y793000D01*
Y788400D01*
X953178Y783222D01*
Y776393D01*
X950029Y773244D01*
Y734671D01*
X953200Y731500D01*
X955900D01*
X959700Y727700D01*
Y723700D01*
X958400Y722400D01*
X928358D01*
X926961Y723797D01*
G01X957487Y798553D02*
X953900Y802140D01*
Y812501D01*
X952201Y814200D01*
X948700D01*
X947700Y815200D01*
X937593D01*
X918554Y834239D01*
X918498D01*
X917558Y835179D01*
Y840368D01*
G01X924845Y862356D02*
X929288D01*
X931248Y860396D01*
Y855548D01*
X928800Y853100D01*
Y839676D01*
X933576Y834900D01*
X939810D01*
X947430Y827280D01*
X948930D01*
X949980Y826230D01*
Y824831D01*
X950035Y824776D01*
Y824774D01*
X952403Y822406D01*
X953361Y822009D01*
X955201D01*
X957810Y819400D01*
Y814576D01*
X958130Y814256D01*
Y805374D01*
X963470Y800034D01*
Y800028D01*
X963700Y799798D01*
Y741722D01*
X970839Y734583D01*
Y729923D01*
G01X920700Y863100D02*
X922300Y861500D01*
X923500D01*
X924600Y860400D01*
X926259D01*
X927300Y859359D01*
Y842300D01*
X926200Y841200D01*
Y834900D01*
X927800Y833300D01*
X936600D01*
X937576Y832324D01*
Y829824D01*
X939400Y828000D01*
X940889D01*
X946527Y822362D01*
X950439D01*
X951649Y821152D01*
X952985Y820599D01*
X954616D01*
X956400Y818815D01*
Y813991D01*
X956720Y813671D01*
Y804789D01*
X962060Y799449D01*
Y799443D01*
X962290Y799213D01*
Y741137D01*
X962700Y740727D01*
Y740697D01*
X967145Y736252D01*
Y724337D01*
X965042Y722234D01*
G01X930217Y871033D02*
X939600Y861650D01*
Y847400D01*
X946400Y840600D01*
Y837500D01*
X946000Y837100D01*
Y835000D01*
X949200Y831800D01*
X959600D01*
X960300Y831100D01*
Y825335D01*
X962131Y823504D01*
Y818171D01*
X963246Y817056D01*
X964653D01*
X966800Y814909D01*
Y807301D01*
X970480Y803621D01*
Y796281D01*
X967500Y793301D01*
Y781394D01*
X970535Y778359D01*
Y760853D01*
X967200Y757518D01*
Y740542D01*
X972800Y734942D01*
Y728100D01*
X968589Y723889D01*
Y722434D01*
G01X967562Y802982D02*
X964763Y805781D01*
X963280D01*
X961200Y807861D01*
Y817107D01*
X960721Y817586D01*
Y820479D01*
X956371Y824829D01*
X954271D01*
X953757Y825042D01*
X952855Y825944D01*
Y827345D01*
X950100Y830100D01*
X948600D01*
X940600Y838100D01*
X937400D01*
X935000Y840500D01*
Y854222D01*
X934500Y854722D01*
Y864000D01*
X928612Y869888D01*
Y870488D01*
G01X925462D02*
X932900Y863050D01*
Y855000D01*
X930200Y852300D01*
Y840400D01*
X934000Y836600D01*
X940105D01*
X948015Y828690D01*
X949515D01*
X951390Y826815D01*
Y825416D01*
X951445Y825361D01*
Y825359D01*
X953095Y823709D01*
X953796Y823419D01*
X955786D01*
X959311Y819894D01*
Y817001D01*
X959540Y816772D01*
Y807060D01*
X966808Y799792D01*
X968094D01*
G01X928612Y873638D02*
X935963D01*
X941500Y868101D01*
Y848600D01*
X948400Y841700D01*
Y840300D01*
X953000Y835700D01*
X954434D01*
X955440Y835900D01*
X957852D01*
X961871Y831881D01*
Y825784D01*
X967300Y820355D01*
Y816404D01*
X968300Y815404D01*
Y808100D01*
X971890Y804510D01*
Y795490D01*
X969200Y792800D01*
Y781899D01*
X972000Y779099D01*
Y759499D01*
X968900Y756399D01*
Y741710D01*
X974300Y736310D01*
Y725856D01*
X971081Y722637D01*
G01X930200Y875300D02*
X935300D01*
X936366Y876366D01*
X939516D01*
X943000Y872882D01*
Y850100D01*
X952800Y840300D01*
X955502D01*
X963200Y832602D01*
Y832547D01*
X963281Y832466D01*
Y826369D01*
X968710Y820940D01*
Y816989D01*
X969710Y815989D01*
Y808685D01*
X973300Y805095D01*
Y794601D01*
X970861Y792162D01*
Y783317D01*
X974100Y780078D01*
Y759500D01*
X970645Y756045D01*
Y742514D01*
X978352Y734807D01*
Y730766D01*
G01X967337Y828901D02*
Y830460D01*
X963080Y834717D01*
Y839315D01*
X961695Y840700D01*
X959500D01*
X949400Y850800D01*
X948200D01*
X944600Y854400D01*
Y874392D01*
X938592Y880400D01*
X932225D01*
X928612Y876787D01*
G01X925462Y886236D02*
X927526Y888300D01*
X929700D01*
X930826Y887174D01*
Y886236D01*
X931562Y885500D01*
X939899D01*
X942599Y882800D01*
X953101D01*
X962200Y873701D01*
Y857826D01*
X962231Y857795D01*
Y850369D01*
X967000Y845600D01*
Y845494D01*
X967404Y845090D01*
Y836677D01*
X973044Y831037D01*
Y824231D01*
X972920Y824107D01*
Y822715D01*
X972940Y822695D01*
Y818744D01*
X974253Y817431D01*
Y815658D01*
X974280Y815631D01*
Y812012D01*
X981180Y805112D01*
Y794813D01*
X976186Y789819D01*
G01X988371Y764143D02*
X987128Y762900D01*
X982599D01*
X980900Y764599D01*
Y775273D01*
X972271Y783902D01*
Y791571D01*
X974900Y794200D01*
Y805800D01*
X971335Y809365D01*
Y816359D01*
X970120Y817574D01*
Y821525D01*
X970100Y821545D01*
Y825277D01*
X970224Y825401D01*
Y829867D01*
X964490Y835601D01*
Y839900D01*
X960090Y844300D01*
X957900D01*
X950900Y851300D01*
Y856900D01*
X946100Y861700D01*
Y875001D01*
X939001Y882100D01*
X930600D01*
X930100Y881600D01*
G01X983786Y765647D02*
Y774543D01*
X973681Y784648D01*
Y790680D01*
X979300Y796299D01*
Y804997D01*
X972745Y811552D01*
Y816944D01*
X971530Y818159D01*
Y822110D01*
X971510Y822130D01*
Y824692D01*
X971634Y824816D01*
Y830452D01*
X965900Y836186D01*
Y844599D01*
X960821Y849678D01*
Y857210D01*
X959665Y858366D01*
X954870D01*
X953866Y859370D01*
X952523D01*
X947900Y863993D01*
Y875400D01*
X939500Y883800D01*
X929326D01*
X928612Y883086D01*
G01X924628Y915242D02*
X934155Y905715D01*
X948086D01*
X950700Y903101D01*
Y902000D01*
X975575Y877125D01*
Y868071D01*
X979715Y863931D01*
Y854186D01*
X983400Y850501D01*
Y844099D01*
X986399Y841100D01*
X988900D01*
X990826Y839174D01*
Y803574D01*
X1004200Y790200D01*
X1007162D01*
X1007796Y789566D01*
X1035611D01*
X1043016Y782161D01*
G01X974437Y849140D02*
X978305Y853008D01*
Y863346D01*
X973700Y867951D01*
Y876699D01*
X946094Y904305D01*
X937408D01*
X935803Y902700D01*
X930199D01*
X920628Y912271D01*
Y915242D01*
G01X916628D02*
Y913072D01*
X928800Y900900D01*
X934082D01*
X936782Y898200D01*
X950100D01*
X972000Y876300D01*
Y862301D01*
X970299Y860600D01*
Y853773D01*
G01X920628Y918042D02*
X926763Y924177D01*
X965524D01*
X967301Y922400D01*
X968600D01*
X980818Y910182D01*
Y908981D01*
X982399Y907400D01*
X987371D01*
X1002910Y891861D01*
Y886786D01*
X1009900Y879796D01*
Y868887D01*
X1016669Y862118D01*
X1024601D01*
X1032470Y854249D01*
X1033360D01*
X1035688Y851921D01*
Y841112D01*
X1040237Y836563D01*
X1043626D01*
G01X1041100Y838500D02*
X1040300D01*
X1038678Y840122D01*
Y850926D01*
X1033945Y855659D01*
X1033055D01*
X1025186Y863528D01*
X1017254D01*
X1011310Y869472D01*
Y880381D01*
X1005406Y886285D01*
Y891360D01*
X986257Y910509D01*
X985040D01*
X983854Y911695D01*
X983175Y911976D01*
X981625D01*
X969701Y923900D01*
X968100D01*
X966413Y925587D01*
X924173D01*
X916628Y918042D01*
G01X1037527Y836486D02*
X1034278Y839735D01*
Y851222D01*
X1032661Y852839D01*
X1031885D01*
X1024016Y860708D01*
X1016084D01*
X1008200Y868592D01*
Y879501D01*
X1001500Y886201D01*
Y891276D01*
X987310Y905466D01*
X978334D01*
X976800Y907000D01*
Y911401D01*
X967301Y920900D01*
X966200D01*
X964333Y922767D01*
X929353D01*
X924628Y918042D01*
G01X1004577Y853679D02*
Y866722D01*
X1001700Y869599D01*
Y878699D01*
X992300Y888099D01*
Y891599D01*
X990833Y893066D01*
X988233D01*
X985594Y895705D01*
Y900679D01*
X983741Y902532D01*
X981970D01*
X980382Y900944D01*
X978802D01*
X978746Y901000D01*
X976331D01*
X961631Y915700D01*
X959399D01*
X953742Y921357D01*
X931943D01*
X928628Y918042D01*
G01X994094Y829000D02*
X994100D01*
X998300Y833200D01*
Y837300D01*
X991800Y843800D01*
Y847900D01*
X986000Y853700D01*
Y864367D01*
X982185Y868182D01*
Y870922D01*
X977400Y875707D01*
Y878599D01*
X956100Y899899D01*
Y903400D01*
X951500Y908000D01*
X934463D01*
X928628Y913835D01*
Y915242D01*
G01X916932Y994405D02*
X918927Y996400D01*
X927292D01*
X928395Y995297D01*
Y992705D01*
X941224Y979876D01*
Y979428D01*
X957374Y963278D01*
X957554D01*
X1024395Y896437D01*
Y892400D01*
X1035500Y881295D01*
Y877845D01*
X1038057Y875288D01*
X1038363D01*
G01X924956Y994321D02*
X926985Y992292D01*
Y991672D01*
X974237Y944420D01*
X974245D01*
X1014020Y904645D01*
Y900079D01*
X1018603Y895496D01*
Y893846D01*
X1024949Y887500D01*
X1027300D01*
X1033900Y880900D01*
Y873352D01*
X1034400Y872852D01*
X1044800D01*
X1045300Y872352D01*
G01X939992Y527726D02*
Y527965D01*
X942142Y530115D01*
Y570346D01*
X938396Y574092D01*
Y611227D01*
X947794Y620625D01*
Y642674D01*
X953775Y648655D01*
X972394D01*
X978865Y642184D01*
G01X941859Y625311D02*
X936605Y620057D01*
Y548194D01*
X939992Y544807D01*
Y544726D01*
G01X929690Y666593D02*
Y637480D01*
X941859Y625311D01*
G01X936628Y915242D02*
X940470Y911400D01*
X952600D01*
X959200Y904800D01*
Y900856D01*
X969366Y890690D01*
X974111D01*
X984659Y880142D01*
Y874213D01*
X994620Y864252D01*
Y845575D01*
X998895Y841300D01*
X1007400D01*
X1009100Y839600D01*
X1012000D01*
X1013000Y840600D01*
X1023700D01*
X1033500Y830800D01*
X1043425D01*
G01X932628Y915242D02*
Y912172D01*
X935200Y909600D01*
X952199D01*
X957600Y904199D01*
Y900461D01*
X968781Y889280D01*
X973525D01*
X983249Y879553D01*
Y873251D01*
X993210Y863290D01*
Y844990D01*
X998600Y839600D01*
X1006800D01*
X1010700Y835700D01*
X1026300D01*
X1038854Y823146D01*
X1051550D01*
G01X940628Y915242D02*
X942570Y913300D01*
X952901D01*
X960700Y905501D01*
Y901351D01*
X969951Y892100D01*
X975200D01*
X986100Y881200D01*
X989528D01*
X992215Y878513D01*
Y876190D01*
X995580Y872825D01*
Y867331D01*
X996030Y866881D01*
Y846160D01*
X998990Y843200D01*
X1005800D01*
X1008900Y846300D01*
X1022100D01*
X1024000Y848200D01*
X1029000D01*
X1029900Y847300D01*
Y837100D01*
X1033987Y833013D01*
X1045086D01*
X1047099Y831000D01*
X1050700D01*
X1052488Y832788D01*
X1053392D01*
G01X936628Y918042D02*
X952675D01*
X963900Y906817D01*
Y902399D01*
X971199Y895100D01*
X976700D01*
X987200Y884600D01*
X990118D01*
X995035Y879683D01*
Y877360D01*
X998400Y873995D01*
Y868501D01*
X998850Y868051D01*
Y848350D01*
X1000600Y846600D01*
X1004700D01*
X1011800Y853700D01*
X1028386D01*
X1031813Y850273D01*
G01X932628Y918042D02*
X934533Y919947D01*
X953053D01*
X959300Y913700D01*
X961636D01*
X975936Y899400D01*
X977406D01*
X977411Y899405D01*
X978991D01*
X980106Y898290D01*
Y898233D01*
X981227Y897112D01*
X982192D01*
X987648Y891656D01*
X989244D01*
X990819Y890081D01*
Y889485D01*
X990859Y889445D01*
Y887541D01*
X1000100Y878300D01*
Y868800D01*
X1001400Y867500D01*
Y867496D01*
X1001410Y867486D01*
Y850306D01*
X1001187Y850084D01*
G01X981857Y605637D02*
X983196D01*
X987150Y609591D01*
X998180D01*
X1010991Y622402D01*
Y642299D01*
X995337Y657953D01*
X963244D01*
X954526Y666671D01*
G01X953240Y876834D02*
X954272D01*
X955343Y875763D01*
Y866850D01*
G01X947029Y915242D02*
X953258D01*
X962400Y906100D01*
Y901904D01*
X970614Y893690D01*
X975709D01*
X986599Y882800D01*
X989923D01*
X993625Y879098D01*
Y876775D01*
X996990Y873410D01*
Y867916D01*
X997440Y867466D01*
Y846745D01*
X999285Y844900D01*
X1005500D01*
X1008500Y847900D01*
X1014300D01*
X1017300Y850900D01*
X1028400D01*
X1031600Y847700D01*
Y837700D01*
X1034800Y834500D01*
X1046916D01*
X1048314Y833102D01*
G01X1100233Y1588000D02*
X1096200Y1583967D01*
Y1571699D01*
X1086990Y1562489D01*
Y1540350D01*
X1047190Y1500550D01*
Y1479450D01*
X1053990Y1472650D01*
Y1420750D01*
X1041490Y1408250D01*
Y1362450D01*
X1007220Y1328181D01*
X1007219Y1328179D01*
X1005322Y1323600D01*
X990922Y1309200D01*
X984221D01*
X970986Y1295965D01*
X948259D01*
G01X968094Y799792D02*
X966000Y797698D01*
Y780899D01*
X969125Y777774D01*
Y766709D01*
X965983Y763567D01*
G01X1086904Y1599004D02*
X1093408Y1592500D01*
X1100200D01*
X1102300Y1590400D01*
Y1586800D01*
X1098200Y1582700D01*
Y1570800D01*
X1088800Y1561400D01*
Y1539600D01*
X1049000Y1499800D01*
Y1480200D01*
X1055800Y1473400D01*
Y1420000D01*
X1043300Y1407500D01*
Y1361700D01*
X1008755Y1327155D01*
X1006858Y1322576D01*
X991167Y1306885D01*
X984498D01*
X974985Y1297372D01*
Y1290950D01*
G01X1021885Y698974D02*
Y764188D01*
X987900Y798173D01*
Y807700D01*
X984800Y810800D01*
Y818700D01*
X982300Y821200D01*
G01X984817Y1303297D02*
Y1302952D01*
X979001Y1288925D01*
G01X1118847Y551683D02*
X1123912Y556748D01*
Y583816D01*
X1115320Y592408D01*
Y646449D01*
G01X1108236Y577716D02*
X1112836Y582316D01*
Y647874D01*
X1115081Y650119D01*
X1115151D01*
G01X1235930Y626229D02*
X1240512Y621647D01*
X1247165D01*
X1253087Y615725D01*
Y553101D01*
G01X1285302Y885783D02*
Y886699D01*
X1280301Y891700D01*
X1278199D01*
X1262700Y876201D01*
Y762643D01*
X1285804Y739539D01*
Y706860D01*
X1268285Y689341D01*
Y542995D01*
X1250565Y525275D01*
Y472898D01*
X1249154Y471487D01*
Y380327D01*
X1259991Y369490D01*
Y340691D01*
G01X1329504Y836170D02*
Y835304D01*
X1327800Y833600D01*
Y829900D01*
X1328400Y829300D01*
Y818601D01*
X1325041Y815242D01*
Y808129D01*
X1323000Y806088D01*
Y785500D01*
X1322100Y784600D01*
Y737601D01*
X1323800Y735901D01*
Y728247D01*
X1354524Y697523D01*
Y685831D01*
X1343697Y675004D01*
X1340104D01*
X1331300Y666200D01*
Y620600D01*
X1335300Y616600D01*
Y608550D01*
X1337500Y606350D01*
Y572100D01*
X1336095Y570695D01*
Y552000D01*
X1322658Y538563D01*
X1282073D01*
X1258940Y515430D01*
Y469225D01*
X1255262Y465547D01*
Y404890D01*
X1253254Y402882D01*
Y382026D01*
X1263976Y371304D01*
Y342544D01*
X1266600Y339920D01*
Y325600D01*
X1261659Y320659D01*
Y318258D01*
G01X1326400Y833100D02*
Y819725D01*
X1321053Y814378D01*
Y807804D01*
X1319000Y805751D01*
Y737500D01*
X1322000Y734500D01*
Y726993D01*
X1331600Y717393D01*
Y710245D01*
X1343546Y698299D01*
Y698242D01*
X1344661Y697127D01*
X1344718D01*
X1353000Y688845D01*
Y686387D01*
X1346113Y679500D01*
X1333700D01*
X1329600Y675400D01*
Y589759D01*
X1332900Y586459D01*
Y583400D01*
X1334500Y581800D01*
Y558591D01*
X1316202Y540293D01*
X1279059D01*
X1257025Y518259D01*
Y474805D01*
X1250884Y468664D01*
Y381044D01*
X1262400Y369528D01*
Y339900D01*
X1260500Y338000D01*
X1256000D01*
G01X1308220Y889253D02*
Y895669D01*
X1307800Y896089D01*
Y913838D01*
X1306900Y914738D01*
Y931900D01*
X1303084Y935716D01*
Y936993D01*
X1308415Y942324D01*
Y943975D01*
X1317700Y953260D01*
Y976567D01*
X1310063Y984204D01*
Y1021487D01*
X1303550Y1028000D01*
X1296308D01*
X1284908Y1016600D01*
X1247800D01*
X1246000Y1014800D01*
G01X1252500Y1014288D02*
X1286088D01*
X1297900Y1026100D01*
X1300700D01*
X1302300Y1024500D01*
Y978900D01*
X1291858Y968458D01*
Y964649D01*
X1293522Y962985D01*
Y959054D01*
X1291600Y957132D01*
Y935400D01*
X1297700Y929300D01*
Y926400D01*
X1296135Y924835D01*
X1290835D01*
X1288600Y922600D01*
Y908069D01*
X1294500Y902169D01*
Y892553D01*
X1295600Y891453D01*
Y873900D01*
X1293500Y871800D01*
G01X1264088Y320382D02*
X1267382D01*
X1269000Y322000D01*
Y325500D01*
X1268133Y326367D01*
Y341220D01*
X1265706Y343647D01*
Y372021D01*
X1254984Y382743D01*
Y402165D01*
X1257318Y404499D01*
Y463941D01*
X1260670Y467293D01*
Y513888D01*
X1283615Y536833D01*
X1323445D01*
X1340000Y553388D01*
Y561182D01*
X1341500Y562682D01*
Y575266D01*
X1339700Y577066D01*
Y581600D01*
X1342600Y584500D01*
Y587500D01*
X1340300Y589800D01*
Y610300D01*
X1337200Y613400D01*
Y617099D01*
X1333288Y621011D01*
Y627555D01*
X1337200Y631467D01*
Y642735D01*
X1333288Y646647D01*
Y665835D01*
X1340553Y673100D01*
X1343819D01*
X1356254Y685535D01*
Y698056D01*
X1330300Y724010D01*
Y737279D01*
X1326239Y741340D01*
Y783599D01*
X1327000Y784360D01*
Y804963D01*
X1329028Y806991D01*
Y813193D01*
X1330207Y814372D01*
Y830678D01*
X1332815Y833286D01*
G01X1281733Y949475D02*
X1275960Y943702D01*
Y935352D01*
X1277460Y933852D01*
Y927253D01*
X1270461Y920254D01*
Y912906D01*
X1266711Y909156D01*
Y888058D01*
X1261290Y882637D01*
Y751692D01*
X1278255Y734727D01*
Y722241D01*
G01X1279460Y884487D02*
X1265700Y870727D01*
Y783001D01*
X1278101Y770600D01*
X1281001D01*
X1284500Y767101D01*
Y765199D01*
X1282877Y763576D01*
X1279539D01*
G01X1279460Y889487D02*
X1264216Y874243D01*
Y779985D01*
X1278125Y766076D01*
X1282539D01*
G01Y761076D02*
X1286000Y764537D01*
Y767700D01*
X1281700Y772000D01*
Y774500D01*
X1277000D01*
X1267200Y784300D01*
Y869323D01*
X1272364Y874487D01*
X1274460D01*
X1279460Y879487D01*
G01X1279539Y758576D02*
X1283177D01*
X1287600Y762999D01*
Y768301D01*
X1283110Y772791D01*
Y785415D01*
X1269111Y799414D01*
Y843634D01*
X1271594Y846117D01*
Y851609D01*
X1268987Y854216D01*
Y865586D01*
X1275474Y872073D01*
X1277046D01*
X1279460Y874487D01*
G01Y854487D02*
X1277234Y852261D01*
Y799271D01*
X1296342Y780163D01*
Y761909D01*
X1283009Y748576D01*
X1279539D01*
G01X1282539Y756076D02*
X1283475D01*
X1289200Y761801D01*
Y768900D01*
X1284520Y773580D01*
Y786000D01*
X1273004Y797516D01*
Y857759D01*
X1277436Y862191D01*
Y867463D01*
X1279460Y869487D01*
G01X1282539Y751076D02*
X1283513D01*
X1293690Y761253D01*
Y772582D01*
X1291841Y774431D01*
X1290314D01*
X1287340Y777405D01*
Y787170D01*
X1275824Y798686D01*
Y855851D01*
X1279460Y859487D01*
G01X1279539Y753576D02*
X1283377D01*
X1291300Y761499D01*
Y768999D01*
X1285930Y774369D01*
Y786585D01*
X1274414Y798101D01*
Y857136D01*
X1279460Y862182D01*
Y864487D01*
G01X1326355Y867665D02*
X1323853Y865163D01*
X1312521D01*
X1304504Y857146D01*
X1295624D01*
X1291317Y852839D01*
Y840458D01*
X1289410Y838551D01*
Y832850D01*
X1287600Y831040D01*
Y816923D01*
X1284205Y813528D01*
Y799416D01*
X1301399Y782222D01*
Y662258D01*
X1302558Y661099D01*
Y610134D01*
X1317833Y594859D01*
X1319731D01*
X1329000Y585590D01*
Y582446D01*
X1331280Y580166D01*
Y568142D01*
X1328216Y565078D01*
X1325852D01*
X1324500Y563726D01*
Y559281D01*
X1326993Y556788D01*
G01X1318490Y872390D02*
X1315032D01*
X1312468Y874954D01*
X1302554D01*
X1287408Y859808D01*
Y841708D01*
X1283200Y837500D01*
Y833999D01*
X1278900Y829699D01*
Y799601D01*
X1297752Y780749D01*
Y761656D01*
X1297724Y761628D01*
Y666744D01*
X1292055Y661075D01*
Y599845D01*
X1315305Y576595D01*
X1325095D01*
X1327000Y578500D01*
G01X1318660Y869239D02*
X1317999Y869900D01*
X1315400D01*
X1312238Y873062D01*
X1307849D01*
X1289225Y854438D01*
Y840926D01*
X1287600Y839301D01*
Y833600D01*
X1283500Y829500D01*
Y824472D01*
X1284118Y823854D01*
Y821817D01*
X1283187Y820886D01*
Y818710D01*
X1284302Y817595D01*
Y816185D01*
X1282395Y814278D01*
Y798666D01*
X1299562Y781499D01*
Y760906D01*
X1299534Y760878D01*
Y665994D01*
X1293865Y660325D01*
Y603135D01*
X1316491Y580509D01*
X1328191D01*
X1329200Y579500D01*
Y575503D01*
X1327043Y573346D01*
G01X1329504Y867665D02*
X1324839Y863000D01*
X1313176D01*
X1303400Y853224D01*
Y851400D01*
X1300710Y848710D01*
Y846794D01*
X1291220Y837304D01*
Y832100D01*
X1289500Y830380D01*
Y813859D01*
X1286015Y810374D01*
Y800166D01*
X1305456Y780725D01*
Y664143D01*
X1308400Y661199D01*
Y612072D01*
X1321228Y599244D01*
Y595922D01*
X1331000Y586150D01*
Y583006D01*
X1333090Y580916D01*
Y566825D01*
X1328765Y562500D01*
X1327000D01*
G01X1299717Y1024136D02*
X1300000Y1023853D01*
Y979770D01*
X1294741Y974511D01*
Y974454D01*
X1293626Y973339D01*
X1293569D01*
X1287400Y967170D01*
Y926900D01*
X1286302Y925802D01*
Y903597D01*
X1284930Y902225D01*
Y898188D01*
X1283400Y896658D01*
Y891301D01*
X1289225Y885476D01*
Y880075D01*
X1293500Y875800D01*
G01X1292836Y975244D02*
X1284009Y966417D01*
Y947351D01*
X1278100Y941442D01*
Y938212D01*
X1281500Y934812D01*
Y925900D01*
X1282000Y925400D01*
Y916201D01*
X1279000Y913201D01*
Y902038D01*
X1282184Y898854D01*
G01X1292631Y979845D02*
X1287070D01*
X1271493Y964268D01*
Y930989D01*
X1272661Y929821D01*
Y929858D01*
G01X1312800Y856643D02*
X1311643D01*
X1302520Y847520D01*
Y846044D01*
X1299028Y842552D01*
Y837348D01*
X1291310Y829630D01*
Y813109D01*
X1287825Y809624D01*
Y800916D01*
X1307351Y781390D01*
Y708149D01*
X1316912Y698588D01*
X1323912D01*
X1327000Y695500D01*
G01X1317706Y846800D02*
X1311805D01*
X1306850Y841845D01*
Y823650D01*
X1297029Y813829D01*
X1295183D01*
X1293061Y811707D01*
Y798240D01*
X1309225Y782076D01*
Y713375D01*
X1314000Y708600D01*
X1321595D01*
X1328905Y701290D01*
Y700595D01*
X1340299Y689201D01*
Y686243D01*
G01X1296770Y828775D02*
X1300775D01*
X1304330Y832330D01*
Y845406D01*
X1311517Y852593D01*
X1317580D01*
X1320055Y855068D01*
G01X1307707Y979870D02*
Y973320D01*
X1309000Y972027D01*
Y957918D01*
X1293500Y942418D01*
Y937101D01*
X1300000Y930601D01*
Y903402D01*
X1301657Y901745D01*
Y899129D01*
G01X1318900Y878688D02*
X1312612D01*
X1303100Y888200D01*
Y894574D01*
X1303865Y895339D01*
Y901303D01*
X1303128Y902040D01*
Y905294D01*
X1304100Y906266D01*
Y921246D01*
X1302500Y922846D01*
Y931268D01*
X1298800Y934968D01*
Y938496D01*
X1313100Y952796D01*
Y978256D01*
X1307561Y983795D01*
Y986951D01*
G01X1311283Y370801D02*
X1313865Y368219D01*
X1355462D01*
X1365232Y377989D01*
Y420088D01*
X1360719Y424601D01*
G01X1327000Y605000D02*
X1323600Y608400D01*
Y678900D01*
X1328181Y683481D01*
X1340175D01*
X1341032Y684338D01*
X1341089D01*
X1342204Y685453D01*
Y685510D01*
X1342300Y685606D01*
Y689760D01*
X1330715Y701345D01*
Y702040D01*
X1325135Y707620D01*
Y710670D01*
X1325095Y710710D01*
Y712290D01*
X1325135Y712330D01*
Y715670D01*
X1325095Y715710D01*
Y717505D01*
X1320005Y722595D01*
X1318210D01*
X1318170Y722635D01*
X1316165D01*
X1311095Y727705D01*
Y811599D01*
X1321100Y821604D01*
Y834170D01*
X1321630Y834700D01*
G01X1324900Y833900D02*
Y822103D01*
X1316960Y814163D01*
Y808236D01*
X1315000Y806276D01*
Y729400D01*
X1317995Y726405D01*
X1319790D01*
X1320905Y725290D01*
Y725233D01*
X1327733Y718405D01*
X1327790D01*
X1328905Y717290D01*
Y717233D01*
X1329600Y716538D01*
Y705715D01*
X1332525Y702790D01*
Y702095D01*
X1347577Y687043D01*
X1350929D01*
G01X1311061Y889361D02*
X1311500Y889800D01*
Y926304D01*
X1317070Y931874D01*
Y935784D01*
X1323769Y942483D01*
Y953136D01*
X1328233Y957600D01*
X1344351D01*
X1345458Y958707D01*
X1396869D01*
G01X1339966Y832534D02*
Y821435D01*
X1345003Y816398D01*
Y809206D01*
X1347000Y807209D01*
Y786800D01*
X1342700Y782500D01*
Y744200D01*
X1343200Y743700D01*
X1345601D01*
X1364400Y724901D01*
Y667399D01*
X1352930Y655929D01*
Y560271D01*
X1356869Y556332D01*
Y498109D01*
X1384682Y470296D01*
Y375765D01*
X1381182Y372265D01*
Y331986D01*
X1350554Y301358D01*
Y230587D01*
X1328831Y208864D01*
G01X1335803Y833021D02*
X1332208Y829426D01*
Y817071D01*
X1333000Y816279D01*
Y807521D01*
X1330968Y805489D01*
Y785881D01*
X1328082Y782995D01*
Y742612D01*
X1332200Y738494D01*
Y724105D01*
X1357664Y698641D01*
Y698527D01*
X1357800Y698391D01*
Y679687D01*
X1348227Y670114D01*
X1344993D01*
X1334936Y660057D01*
Y649844D01*
X1340500Y644280D01*
Y636200D01*
X1342800Y633900D01*
Y631200D01*
X1338657Y627057D01*
Y620692D01*
X1342467Y616882D01*
Y612625D01*
X1346600Y608492D01*
Y586900D01*
X1344332Y584632D01*
Y559467D01*
X1350700Y553099D01*
Y495856D01*
X1377762Y468794D01*
Y427332D01*
X1375171Y424741D01*
G01X1335803Y829871D02*
X1333800Y827868D01*
Y819358D01*
X1337100Y816058D01*
Y808494D01*
X1334981Y806375D01*
Y785579D01*
X1333800Y784398D01*
Y737600D01*
X1340837Y730563D01*
X1343533D01*
X1343733Y730363D01*
X1343790D01*
X1344905Y729248D01*
Y729191D01*
X1359394Y714702D01*
Y679286D01*
X1359234Y679126D01*
Y677798D01*
X1354274Y672838D01*
Y666074D01*
X1348700Y660500D01*
Y557600D01*
X1352300Y554000D01*
Y496251D01*
X1379172Y469379D01*
Y469151D01*
X1379412Y468911D01*
Y425142D01*
X1375108Y420838D01*
G01X1337378Y893900D02*
Y894977D01*
X1338001Y895600D01*
Y916356D01*
X1340500Y918855D01*
Y934054D01*
X1353736Y947290D01*
X1361719D01*
X1363965Y945044D01*
Y942671D01*
X1361843Y940549D01*
Y936126D01*
X1362886Y935083D01*
X1384166D01*
X1419524Y970441D01*
Y971763D01*
X1420401Y972639D01*
X1448376Y1000615D01*
Y1020320D01*
X1456433Y1028377D01*
X1459683D01*
G01X1327929Y894000D02*
Y895165D01*
X1327381Y895713D01*
Y902820D01*
X1326187Y904014D01*
Y921972D01*
X1328500Y924285D01*
Y931800D01*
X1327021Y933279D01*
Y938437D01*
X1331913Y943329D01*
Y945844D01*
X1337369Y951300D01*
X1364067D01*
X1368000Y947367D01*
Y941698D01*
X1365948Y939646D01*
Y939475D01*
G01X1369948Y943603D02*
Y949489D01*
X1365737Y953700D01*
X1337137D01*
X1330052Y946615D01*
Y944100D01*
X1325705Y939753D01*
X1325704D01*
X1325205Y939254D01*
Y932423D01*
X1326103Y931525D01*
Y927964D01*
X1323259Y925120D01*
Y904273D01*
X1325943Y901589D01*
Y893274D01*
X1326355Y892862D01*
G01X1331079Y894000D02*
Y896378D01*
X1329352Y898105D01*
Y903617D01*
X1328635Y904334D01*
Y917732D01*
X1332500Y921597D01*
Y927859D01*
X1331496Y928863D01*
Y932145D01*
X1333132Y933781D01*
G01X1323000Y934075D02*
X1321620Y932695D01*
Y895200D01*
G01X1402064Y965913D02*
Y955780D01*
X1383165Y936881D01*
X1364361D01*
X1363462Y937780D01*
Y940081D01*
X1365700Y942319D01*
Y945717D01*
X1362203Y949214D01*
X1348612D01*
X1336500Y937102D01*
Y919319D01*
X1333136Y915955D01*
Y902558D01*
X1331078Y900500D01*
G01X1329834Y988132D02*
X1329680Y987978D01*
Y967425D01*
X1321256Y959001D01*
Y943815D01*
G01X1348419Y265222D02*
Y301670D01*
X1379452Y332703D01*
Y372982D01*
X1382952Y376482D01*
Y470031D01*
X1355300Y497683D01*
Y555566D01*
X1351520Y559346D01*
Y658256D01*
X1357380Y664116D01*
Y666868D01*
X1362900Y672388D01*
Y722238D01*
X1345558Y739580D01*
X1343421D01*
X1341000Y742001D01*
Y785277D01*
X1343000Y787277D01*
Y807195D01*
X1340934Y809261D01*
Y817880D01*
X1338026Y820788D01*
Y833175D01*
X1335803Y835398D01*
Y836170D01*
G01Y826500D02*
Y820305D01*
X1339000Y817108D01*
Y739589D01*
X1361100Y717489D01*
Y677217D01*
X1355684Y671801D01*
Y665383D01*
X1350110Y659809D01*
Y558489D01*
X1353800Y554799D01*
Y497000D01*
X1380822Y469978D01*
Y401511D01*
X1377024Y397713D01*
G01X1341032Y834432D02*
X1341744Y833720D01*
Y822297D01*
X1348909Y815132D01*
Y809798D01*
X1350905Y807802D01*
Y779163D01*
X1348745Y773947D01*
Y744556D01*
X1366234Y727067D01*
Y666634D01*
X1358279Y658679D01*
Y498694D01*
X1386371Y470602D01*
Y420347D01*
X1387125Y419593D01*
Y417312D01*
G01X1393177Y424804D02*
X1391714Y426267D01*
X1389240Y432238D01*
Y469728D01*
X1359689Y499279D01*
Y658090D01*
X1368364Y666765D01*
Y728481D01*
X1351004Y745841D01*
Y774122D01*
X1354905Y783539D01*
Y808221D01*
X1352969Y810157D01*
Y813643D01*
X1343668Y822944D01*
Y830900D01*
G01X1345252Y833021D02*
Y829537D01*
X1345779Y829010D01*
Y823919D01*
X1357045Y812653D01*
Y809044D01*
X1359000Y807089D01*
Y788478D01*
X1352734Y773355D01*
Y746834D01*
X1370094Y729474D01*
Y665994D01*
X1361099Y656999D01*
Y499864D01*
X1390998Y469965D01*
X1391130Y469569D01*
Y431447D01*
X1392020Y429297D01*
X1393208Y428109D01*
G01X1393336Y431100D02*
Y469623D01*
X1362749Y500210D01*
Y655748D01*
X1371824Y664823D01*
Y730191D01*
X1354464Y747551D01*
Y772525D01*
X1363000Y793132D01*
Y806267D01*
X1361000Y808267D01*
Y812600D01*
X1360057Y813543D01*
X1358657D01*
X1347509Y824691D01*
Y839277D01*
G01X1345252Y845619D02*
X1348700Y842171D01*
Y833199D01*
X1362833Y819066D01*
X1367034D01*
X1373000Y813100D01*
Y807977D01*
X1375200Y805777D01*
Y801692D01*
X1403038Y773854D01*
Y742520D01*
X1391597Y731079D01*
Y691615D01*
X1386595Y686613D01*
Y679683D01*
X1384911Y677999D01*
Y674120D01*
X1377647Y666856D01*
Y663547D01*
X1368019Y653919D01*
Y502281D01*
X1399251Y471049D01*
Y417845D01*
X1399276Y417820D01*
Y405945D01*
X1396528Y403197D01*
Y397454D01*
G01X1349976Y829000D02*
X1361769Y817207D01*
X1364693D01*
X1369004Y812896D01*
Y810701D01*
X1371000Y808705D01*
Y802333D01*
X1399395Y773938D01*
Y750695D01*
X1375310Y726610D01*
Y663810D01*
X1366609Y655109D01*
Y501244D01*
X1397500Y470353D01*
Y406616D01*
X1393575Y402691D01*
Y397310D01*
G01X1350000Y825500D02*
X1360044Y815456D01*
X1362644D01*
X1365000Y813100D01*
Y808877D01*
X1367000Y806877D01*
Y797286D01*
X1356194Y771201D01*
Y748268D01*
X1373554Y730908D01*
Y664354D01*
X1364479Y655279D01*
Y500927D01*
X1395633Y469773D01*
Y407740D01*
X1390553Y402660D01*
Y397436D01*
G01X1399571Y397418D02*
X1400820Y398667D01*
Y471475D01*
X1371471Y500824D01*
Y651171D01*
X1377600Y657300D01*
X1382100D01*
X1402384Y677584D01*
Y735028D01*
X1402344Y735068D01*
Y736648D01*
X1403459Y737763D01*
X1403516D01*
X1404600Y738847D01*
Y774900D01*
X1377098Y802402D01*
Y812532D01*
X1368747Y820883D01*
X1363817D01*
X1349900Y834800D01*
Y844121D01*
X1345252Y848769D01*
G01X1361948Y943603D02*
X1358569D01*
X1355372Y940406D01*
Y937566D01*
X1356521Y936417D01*
Y921106D01*
X1349512Y914097D01*
Y882371D01*
X1351550Y880333D01*
Y880263D01*
G01X1362573Y834600D02*
X1362300Y834327D01*
Y828201D01*
X1364812Y825689D01*
X1369864D01*
X1378153Y817400D01*
X1379400D01*
X1383400Y813400D01*
Y804001D01*
X1384430Y802971D01*
Y802914D01*
X1385545Y801799D01*
X1385602D01*
X1423001Y764400D01*
X1433900D01*
X1435000Y765500D01*
G01X1418000Y729000D02*
X1414768Y732232D01*
Y762198D01*
X1407000Y769966D01*
Y776201D01*
X1381701Y801500D01*
X1380669D01*
X1378508Y803661D01*
Y813205D01*
X1368813Y822900D01*
X1364900D01*
X1361194Y826606D01*
Y832506D01*
X1359424Y834276D01*
Y835100D01*
G01X1384800Y858678D02*
X1397714Y845764D01*
Y843802D01*
X1399900Y841616D01*
Y832830D01*
X1403850Y828880D01*
Y824250D01*
X1417800Y810300D01*
X1419464D01*
X1422964Y806800D01*
X1423601D01*
X1423611Y806790D01*
X1428010D01*
X1452300Y782500D01*
X1455300D01*
X1460384Y777416D01*
Y758754D01*
X1457293Y755663D01*
Y693392D01*
X1433529Y669628D01*
Y660564D01*
G01X1364148Y867665D02*
X1368576Y863237D01*
X1390163D01*
X1404200Y849200D01*
Y846900D01*
X1403500Y846200D01*
Y842200D01*
X1404100Y841600D01*
Y838400D01*
X1403000Y837300D01*
Y833915D01*
X1405580Y831335D01*
Y824519D01*
X1418251Y811848D01*
X1420548D01*
X1424196Y808200D01*
X1432700D01*
X1437519Y803381D01*
Y800781D01*
X1441896Y796404D01*
X1442209D01*
X1442210Y796405D01*
X1443790D01*
X1443791Y796404D01*
X1450692D01*
X1451733Y795363D01*
X1451790D01*
X1452905Y794248D01*
Y794191D01*
X1455293Y791803D01*
X1455323D01*
X1456438Y790688D01*
Y790658D01*
X1462192Y784904D01*
Y754992D01*
X1461200Y754000D01*
Y730670D01*
X1462990Y728880D01*
Y727444D01*
X1462721Y727175D01*
Y727174D01*
X1459023Y723476D01*
Y692823D01*
X1440792Y674592D01*
Y664193D01*
X1432599Y656000D01*
X1418800D01*
X1411000Y663800D01*
X1395200D01*
X1385000Y653600D01*
Y648300D01*
X1374919Y638219D01*
Y556593D01*
X1374999Y556513D01*
Y520862D01*
X1385396Y510465D01*
Y488894D01*
X1403085Y471205D01*
Y460565D01*
G01X1384400Y878600D02*
X1386877D01*
X1397914Y889637D01*
Y895914D01*
X1402000Y900000D01*
G01X1367298Y867665D02*
X1369029Y865934D01*
X1389465D01*
X1407512Y847887D01*
Y824588D01*
X1414200Y817900D01*
X1423400D01*
X1424800Y816500D01*
X1435966D01*
X1441736Y810730D01*
Y808932D01*
X1444282Y806386D01*
X1450714D01*
X1463602Y793498D01*
Y754202D01*
X1462700Y753300D01*
Y731165D01*
X1464400Y729465D01*
Y726463D01*
X1460753Y722816D01*
Y692210D01*
X1442522Y673979D01*
Y663007D01*
X1433635Y654120D01*
X1417680D01*
X1409500Y662300D01*
X1395900D01*
X1386800Y653200D01*
Y647600D01*
X1376329Y637129D01*
Y557178D01*
X1379119Y554388D01*
X1383556D01*
G01X1404760Y915186D02*
X1402724Y917222D01*
X1390514D01*
X1367321Y907615D01*
X1359424Y899718D01*
Y893800D01*
G01X1385021Y872389D02*
X1386092Y871318D01*
X1397982D01*
X1411352Y857948D01*
Y827448D01*
X1412665Y826135D01*
X1412670D01*
X1412710Y826095D01*
X1416373D01*
X1418103Y824365D01*
X1427522D01*
X1429355Y822532D01*
X1436569D01*
X1445470Y813631D01*
X1447884D01*
X1467304Y794211D01*
Y753453D01*
X1466100Y752249D01*
Y732642D01*
X1467900Y730842D01*
Y725070D01*
X1464213Y721383D01*
Y690451D01*
X1458200Y684438D01*
Y675672D01*
X1432823Y650295D01*
X1409768D01*
X1409767Y650296D01*
X1408269D01*
X1407773Y649800D01*
X1401601D01*
X1386562Y634761D01*
Y630830D01*
X1380929Y625197D01*
Y579931D01*
X1381686Y579174D01*
Y563114D01*
X1384346Y560454D01*
Y560243D01*
X1382766D01*
X1381651Y559128D01*
Y557548D01*
X1382766Y556433D01*
X1384347D01*
X1385341Y555439D01*
Y555298D01*
X1385461Y555178D01*
Y553598D01*
X1385341Y553478D01*
Y518025D01*
X1383907Y516591D01*
G01X1382994Y856080D02*
X1384920D01*
X1395800Y845200D01*
Y843259D01*
X1398100Y840959D01*
Y826689D01*
X1403319Y821470D01*
Y818981D01*
X1403769Y818531D01*
X1405023Y818012D01*
X1408089D01*
X1421501Y804600D01*
X1427560D01*
X1427755Y804405D01*
X1427790D01*
X1451233Y780962D01*
X1453939D01*
X1458734Y776167D01*
Y759473D01*
X1455563Y756302D01*
Y694363D01*
X1432114Y670914D01*
X1398714D01*
X1381900Y654100D01*
Y649500D01*
X1373419Y641019D01*
Y518152D01*
X1383343Y508228D01*
G01X1373597Y833021D02*
Y829002D01*
X1389075Y813524D01*
Y808227D01*
X1392402Y804900D01*
Y804509D01*
X1392442Y804469D01*
Y802889D01*
X1392402Y802849D01*
Y801598D01*
X1425365Y768635D01*
X1426170D01*
X1426210Y768595D01*
X1427790D01*
X1427830Y768635D01*
X1433135D01*
X1435000Y770500D01*
G01X1406867Y783273D02*
X1388600Y801540D01*
Y804200D01*
X1387265Y805535D01*
Y812734D01*
X1377199Y822800D01*
X1375313D01*
X1372300Y825813D01*
Y831168D01*
X1370447Y833021D01*
G01X1418000Y701000D02*
X1420900D01*
X1431497Y711597D01*
Y726991D01*
X1435340Y730834D01*
Y750107D01*
X1437500Y752267D01*
Y771741D01*
X1431784Y777457D01*
X1419943D01*
X1396600Y800800D01*
Y804601D01*
X1392980Y808221D01*
Y813020D01*
X1377140Y828860D01*
Y832627D01*
X1373597Y836170D01*
G01X1384155Y844045D02*
X1387509Y840691D01*
Y823899D01*
X1396600Y814808D01*
Y810952D01*
X1408152Y799400D01*
X1412200D01*
X1430406Y781194D01*
X1433507D01*
X1443400Y771301D01*
Y722686D01*
X1446538Y719548D01*
G01X1378100Y837300D02*
X1378900Y836500D01*
X1381699D01*
X1385000Y833199D01*
Y823848D01*
X1394790Y814058D01*
Y810201D01*
X1400600Y804391D01*
Y799801D01*
X1421017Y779384D01*
X1432417D01*
X1441365Y770436D01*
Y702018D01*
X1448991Y694392D01*
G01X1384595Y847204D02*
X1389800Y841999D01*
Y824168D01*
X1400500Y813468D01*
Y810000D01*
X1409200Y801300D01*
X1413505D01*
X1431705Y783100D01*
X1437038D01*
X1448824Y771314D01*
Y765528D01*
X1451976Y762376D01*
Y693844D01*
G01X1384317Y853483D02*
X1394029Y843771D01*
Y825060D01*
X1400897Y818192D01*
X1404737Y816602D01*
X1407398D01*
X1423635Y800365D01*
X1429310D01*
X1451400Y778275D01*
Y776899D01*
X1453024Y775275D01*
X1455849D01*
X1457324Y773800D01*
Y761689D01*
X1455291Y759656D01*
G01X1381056Y850343D02*
X1381530Y849869D01*
X1384731D01*
X1392200Y842400D01*
Y824328D01*
X1399872Y816656D01*
X1408256Y813184D01*
X1422244Y799196D01*
Y798555D01*
X1422693Y798106D01*
X1429009D01*
X1449500Y777615D01*
Y774939D01*
X1450798Y773641D01*
Y768075D01*
X1455159Y763714D01*
G01X1384260Y875540D02*
X1388612D01*
X1401072Y888000D01*
X1405500D01*
G01X1384100Y869239D02*
X1388293D01*
X1392333Y865199D01*
X1397600D01*
X1409622Y853177D01*
Y824779D01*
X1412501Y821900D01*
X1427663D01*
X1428963Y820600D01*
X1436000D01*
X1443627Y812973D01*
Y810090D01*
X1445781Y807936D01*
X1451506D01*
X1465574Y793868D01*
Y753986D01*
X1464400Y752812D01*
Y731912D01*
X1465900Y730412D01*
Y725516D01*
X1462483Y722099D01*
Y691493D01*
X1455761Y684771D01*
Y683448D01*
G01X1384121Y881848D02*
X1385619Y883346D01*
X1387259D01*
X1395920Y892007D01*
Y897920D01*
X1402000Y904000D01*
X1405500D01*
G01X1401000Y925789D02*
X1402538Y924251D01*
X1447649D01*
X1465424Y906476D01*
Y854576D01*
X1485700Y834300D01*
X1488578D01*
X1495973Y826905D01*
X1496030D01*
X1497145Y825790D01*
Y825733D01*
X1499300Y823578D01*
Y792162D01*
X1498405Y791267D01*
Y791210D01*
X1497290Y790095D01*
X1497233D01*
X1490811Y783673D01*
Y737831D01*
X1490400Y737420D01*
Y731205D01*
X1487600Y728405D01*
Y717253D01*
X1483515Y713168D01*
Y694845D01*
X1481900Y693230D01*
Y685859D01*
X1481800Y685331D01*
X1480020Y683551D01*
Y682024D01*
X1474596Y676600D01*
Y672005D01*
X1474007Y671416D01*
Y671190D01*
X1470297Y667480D01*
X1470071D01*
X1468991Y666400D01*
X1456608D01*
X1435073Y644865D01*
X1413193D01*
X1413190Y644864D01*
X1411547Y643221D01*
Y642448D01*
X1407899Y638800D01*
X1404401D01*
X1393740Y628139D01*
Y557047D01*
X1393700Y557007D01*
Y555427D01*
X1393740Y555387D01*
Y521572D01*
X1404127Y511185D01*
Y478908D01*
X1408800Y474235D01*
Y468700D01*
X1413700Y463800D01*
Y460200D01*
X1408900Y455400D01*
Y417599D01*
X1413230Y413269D01*
Y407424D01*
X1416347Y404307D01*
Y397295D01*
X1413239Y394187D01*
X1411420D01*
X1397251Y380018D01*
Y365375D01*
X1402921Y359705D01*
Y322403D01*
G01X1413500Y856000D02*
X1452326D01*
X1480280Y828046D01*
X1487152D01*
X1488500Y826698D01*
Y824715D01*
X1487567Y823782D01*
Y815990D01*
X1489300Y814257D01*
Y806201D01*
X1484697Y801598D01*
Y747525D01*
X1482498Y745326D01*
Y745213D01*
X1481980Y744695D01*
Y719701D01*
X1480579Y718300D01*
X1473800D01*
X1471620Y716120D01*
Y709262D01*
X1471900Y708982D01*
Y705300D01*
X1470800Y704200D01*
Y675983D01*
X1470387Y675570D01*
Y672690D01*
X1468797Y671100D01*
X1456188D01*
X1433573Y648485D01*
X1409018D01*
X1408233Y647700D01*
X1402061D01*
X1388372Y634011D01*
Y630080D01*
X1385800Y627508D01*
Y561560D01*
X1386156Y561204D01*
Y560387D01*
X1387151Y559392D01*
Y556048D01*
X1387271Y555928D01*
Y552848D01*
X1388300Y551819D01*
Y499979D01*
X1397625Y490654D01*
Y479226D01*
X1405000Y471851D01*
Y413877D01*
X1407844Y411033D01*
G01X1413500Y872000D02*
X1425400Y860100D01*
X1457500D01*
X1463614Y853986D01*
Y853826D01*
X1484950Y832490D01*
X1487828D01*
X1492120Y828198D01*
Y823215D01*
X1492100Y823195D01*
Y822999D01*
X1491187Y822086D01*
Y819654D01*
X1491210Y819631D01*
Y818091D01*
X1493290Y816011D01*
Y802405D01*
X1493330Y802365D01*
Y800785D01*
X1493290Y800745D01*
Y799255D01*
X1493330Y799215D01*
Y797635D01*
X1493290Y797595D01*
Y797485D01*
X1493265Y797460D01*
Y795880D01*
X1493290Y795855D01*
Y792290D01*
X1488317Y787317D01*
Y746025D01*
X1486118Y743826D01*
Y743713D01*
X1485600Y743195D01*
Y718201D01*
X1481735Y714336D01*
Y713948D01*
X1481705Y713918D01*
Y702896D01*
X1472700Y693891D01*
Y672669D01*
X1472197Y672166D01*
Y671940D01*
X1469547Y669290D01*
X1469321D01*
X1468831Y668800D01*
X1456448D01*
X1434323Y646675D01*
X1409768D01*
X1408693Y645600D01*
X1402700D01*
X1390182Y633082D01*
Y629330D01*
X1387610Y626758D01*
Y562310D01*
X1387967Y561953D01*
Y561136D01*
X1388836Y560267D01*
Y560210D01*
X1389951Y559095D01*
X1390008D01*
X1390712Y558391D01*
Y520063D01*
X1401900Y508875D01*
Y477900D01*
X1406900Y472900D01*
Y415732D01*
X1410500Y412132D01*
Y400287D01*
X1408254Y398041D01*
G01X1397079Y527726D02*
Y523119D01*
X1407293Y512905D01*
Y504107D01*
X1411193Y500207D01*
Y486795D01*
X1415823Y482165D01*
G01X1435952Y642184D02*
X1418203D01*
X1412573Y636554D01*
X1406966D01*
X1403464Y633052D01*
Y622740D01*
X1397659Y616935D01*
Y571916D01*
X1401062Y568513D01*
Y538919D01*
X1399400Y537257D01*
Y530286D01*
X1397079Y527965D01*
Y527726D01*
G01X1406910Y491982D02*
X1408994Y489898D01*
Y477328D01*
X1410903Y475419D01*
Y470419D01*
G01X1415823Y482165D02*
X1416875Y481113D01*
Y468854D01*
X1418440Y467289D01*
X1428728D01*
X1431484Y470045D01*
G01X1413500Y828000D02*
X1413900Y828400D01*
X1426205D01*
X1426210Y828405D01*
X1427790D01*
X1427795Y828400D01*
X1435738D01*
X1438172Y825966D01*
Y823720D01*
X1446106Y815786D01*
X1448150D01*
X1469034Y794902D01*
Y753024D01*
X1467600Y751590D01*
Y733137D01*
X1469310Y731427D01*
Y723811D01*
X1465623Y720124D01*
Y689048D01*
X1460111Y683536D01*
G01X1413500Y848000D02*
X1417085Y844415D01*
X1432385D01*
X1447382Y829418D01*
X1455896D01*
X1459371Y825943D01*
Y817629D01*
X1481530Y795470D01*
Y755385D01*
X1481570Y755345D01*
Y753765D01*
X1481530Y753725D01*
Y748429D01*
X1477792Y744691D01*
Y736330D01*
X1477752Y736290D01*
Y734710D01*
X1477792Y734670D01*
Y722852D01*
X1479759Y720885D01*
G01X1413500Y840000D02*
X1420843D01*
X1421343Y840500D01*
X1434117D01*
X1450516Y824101D01*
X1454210D01*
X1456804Y821507D01*
Y817495D01*
X1479665Y794634D01*
Y754555D01*
G01X1413500Y836000D02*
X1422387D01*
X1422982Y836595D01*
X1427790D01*
X1427895Y836700D01*
X1435494D01*
X1435789Y836405D01*
X1435790D01*
X1451197Y820998D01*
Y820312D01*
X1452312Y819197D01*
X1452349D01*
X1477000Y794546D01*
Y755001D01*
X1477100Y754901D01*
Y751601D01*
X1474811Y749312D01*
Y745321D01*
X1475500Y744632D01*
Y722801D01*
X1471021Y718322D01*
Y718265D01*
X1469906Y717150D01*
X1469849D01*
X1467600Y714901D01*
Y676887D01*
X1468372Y676115D01*
Y673812D01*
G01X1413500Y832000D02*
X1422674D01*
X1423174Y832500D01*
X1436945D01*
X1454508Y814937D01*
X1454565D01*
X1455680Y813822D01*
Y813765D01*
X1470978Y798467D01*
Y752653D01*
X1473320Y750311D01*
Y744817D01*
X1474090Y744047D01*
Y724029D01*
X1469116Y719055D01*
G01X1413500Y864000D02*
X1419690Y857810D01*
X1452963D01*
X1453123Y857650D01*
X1453236D01*
X1476386Y834500D01*
X1480380D01*
X1484200Y830680D01*
X1487078D01*
X1490310Y827448D01*
Y823965D01*
X1489377Y823032D01*
Y818904D01*
X1489400Y818881D01*
Y816717D01*
X1491300Y814817D01*
Y804088D01*
X1490692Y803480D01*
X1490635D01*
X1489520Y802365D01*
Y802308D01*
X1488862Y801650D01*
Y791362D01*
X1486507Y789007D01*
Y746775D01*
X1484308Y744576D01*
Y744463D01*
X1483790Y743945D01*
Y718951D01*
X1479794Y714955D01*
Y709388D01*
G01X1487050Y809413D02*
X1444463Y852000D01*
X1413500D01*
G01X1486386Y825296D02*
X1474551D01*
X1445805Y854042D01*
X1435212D01*
G01X1734069Y1749208D02*
X1440636D01*
X1436666Y1745238D01*
Y1743178D01*
X1440636Y1739208D01*
X1734069D01*
G01X1574880Y645891D02*
Y635243D01*
X1571755Y632118D01*
Y593060D01*
X1580999Y583816D01*
Y557258D01*
X1577862Y554121D01*
G01X1565323Y577716D02*
X1569923Y582316D01*
Y633149D01*
X1571888Y635114D01*
Y649380D01*
G01X1758881Y995633D02*
X1757370Y994122D01*
Y985201D01*
X1749799Y977630D01*
X1732745D01*
X1661040Y905925D01*
Y773597D01*
X1656112Y768669D01*
G01X1753860Y997271D02*
Y985254D01*
X1748406Y979800D01*
X1731735D01*
X1659141Y907206D01*
Y775703D01*
X1657042Y773604D01*
G01X1692028Y550137D02*
X1695762D01*
X1708925Y536974D01*
Y461719D01*
X1716310Y454334D01*
G01X1693000Y626912D02*
X1698987D01*
X1710174Y615725D01*
Y553101D01*
G54D23*
X843012Y1592787D03*
Y1602787D03*
Y1612787D03*
Y1622787D03*
X853012Y1592787D03*
Y1602787D03*
Y1612787D03*
Y1622787D03*
X878012Y1592787D03*
Y1602787D03*
Y1612787D03*
Y1622787D03*
X888012Y1592787D03*
Y1602787D03*
Y1612787D03*
Y1622787D03*
X913012Y1592787D03*
Y1602787D03*
Y1612787D03*
Y1622787D03*
X923012Y1592787D03*
Y1602787D03*
Y1612787D03*
Y1622787D03*
X948012Y1592787D03*
Y1602787D03*
Y1612787D03*
Y1622787D03*
X958012Y1592787D03*
Y1602787D03*
Y1612787D03*
Y1622787D03*
X983012Y1592787D03*
X993012D03*
X983012Y1602787D03*
Y1612787D03*
X993012Y1602787D03*
Y1612787D03*
X983012Y1622787D03*
X993012D03*
X1018012Y1592787D03*
X1028012D03*
X1018012Y1602787D03*
Y1612787D03*
X1028012Y1602787D03*
Y1612787D03*
X1018012Y1622787D03*
X1028012D03*
G54D14*
G01X427052Y1019384D02*
X403254D01*
X385048Y1037590D01*
Y1120372D01*
X375215Y1130205D01*
Y1146275D01*
X384835Y1155895D01*
X396255D01*
X402098Y1150052D01*
X431641D01*
X433216Y1148477D01*
G01X498727Y1128759D02*
Y1125961D01*
X492024Y1119258D01*
Y1112777D01*
X490178Y1110931D01*
X481692D01*
X475882Y1105121D01*
X467231D01*
X465431Y1106921D01*
Y1109510D01*
X462254Y1112687D01*
X458868D01*
X456277Y1110096D01*
X448961D01*
X443798Y1104933D01*
X434331D01*
X432671Y1106593D01*
X432032Y1108136D01*
Y1111266D01*
X427977Y1115321D01*
Y1127721D01*
X429348Y1129092D01*
G01X810148Y1374884D02*
Y1388436D01*
X789684Y1408900D01*
Y1413224D01*
X780385Y1422523D01*
Y1442115D01*
X783529Y1445259D01*
X791898D01*
X795968Y1449329D01*
Y1457109D01*
X800112Y1461253D01*
Y1467120D01*
X803929Y1470937D01*
Y1473856D01*
X802092Y1475693D01*
X799314D01*
G01X1006222Y980337D02*
X976898D01*
X965671Y991564D01*
G01X1013991Y1360842D02*
X1015813Y1359020D01*
G01X1340665Y1028923D02*
X1307889D01*
X1301873Y1034939D01*
G01D02*
Y1122995D01*
X1289967Y1134901D01*
Y1146853D01*
X1299009Y1155895D01*
X1310193D01*
X1316036Y1150052D01*
X1345815D01*
X1347390Y1148477D01*
G01X1409425Y1129238D02*
Y1123460D01*
X1407389Y1121424D01*
Y1114360D01*
X1404086Y1111057D01*
X1394514D01*
X1388536Y1105079D01*
X1381430D01*
X1379925Y1106584D01*
Y1108507D01*
X1375702Y1112730D01*
X1372507D01*
X1370856Y1111079D01*
X1363833D01*
X1357519Y1104765D01*
X1348063D01*
X1347240Y1105588D01*
X1346595Y1107146D01*
X1346494Y1107652D01*
Y1109939D01*
X1341801Y1114632D01*
Y1119417D01*
X1347300Y1124916D01*
Y1128332D01*
G01X1426000Y761000D02*
X1420127Y755127D01*
Y751183D01*
X1426000Y745310D01*
Y717000D01*
G01X1468869Y1018469D02*
Y1005359D01*
X1452482Y988972D01*
Y971134D01*
X1439031Y957683D01*
G01X1789363Y969160D02*
X1773455D01*
X1769697Y965402D01*
Y936083D01*
X1760768Y927154D01*
Y920330D01*
X1769697Y911401D01*
Y860275D01*
X1745612Y836190D01*
Y511190D01*
X1761243Y495559D01*
Y487724D01*
X1758401Y484882D01*
X79512Y1372385D03*
X76112D03*
Y1384297D03*
X79512D03*
X88352Y1348187D03*
X91752D03*
Y1360099D03*
X88352D03*
X100592Y1384297D03*
Y1372385D03*
X91752Y1396583D03*
X88352D03*
X91752Y1408495D03*
X88352D03*
X116232Y1348187D03*
X112832D03*
Y1360099D03*
X116232D03*
X103992Y1372385D03*
Y1384297D03*
X116232Y1396583D03*
X112832D03*
Y1408495D03*
X116232D03*
X125072Y1384297D03*
X128472D03*
X125072Y1372385D03*
X128472D03*
X140712Y1348187D03*
X137312D03*
Y1360099D03*
X140712D03*
X149552Y1384297D03*
Y1372385D03*
X140712Y1396583D03*
X137312D03*
X140712Y1408495D03*
X137312D03*
X165192Y1348187D03*
X161792D03*
X165192Y1360099D03*
X161792D03*
X152952Y1384297D03*
Y1372385D03*
X165192Y1396583D03*
X161792D03*
X165192Y1408495D03*
X161792D03*
X177432Y1384297D03*
X174032D03*
Y1372385D03*
X177432D03*
X189672Y1348187D03*
X186272D03*
X189672Y1360099D03*
X186272D03*
X198512Y1384297D03*
Y1372385D03*
X186272Y1396583D03*
X189672D03*
Y1408495D03*
X186272D03*
X201912Y1384297D03*
Y1372385D03*
X202690Y1410991D03*
X211473Y1446675D03*
Y1451631D03*
Y1462631D03*
Y1457675D03*
X216465Y1446675D03*
X229745D03*
X224753D03*
X216465Y1451631D03*
Y1462631D03*
Y1457675D03*
X224753Y1462631D03*
X229745Y1457675D03*
X224753D03*
X229745Y1451631D03*
Y1462631D03*
X224753Y1451631D03*
X245023Y1372385D03*
X241623D03*
Y1384297D03*
X245023D03*
X253863Y1348187D03*
X257263D03*
X253863Y1360099D03*
X257263D03*
X253863Y1396583D03*
X257263D03*
Y1408495D03*
X253863D03*
X278343Y1348187D03*
Y1360099D03*
X269503Y1372385D03*
X266103D03*
Y1384297D03*
X269503D03*
X278343Y1396583D03*
Y1408495D03*
X281743Y1348187D03*
Y1360099D03*
X293983Y1372385D03*
X290583Y1384297D03*
X293983D03*
X290583Y1372385D03*
X281743Y1396583D03*
Y1408495D03*
X302823Y1348187D03*
X306223D03*
Y1360099D03*
X302823D03*
Y1396583D03*
X306223D03*
X302823Y1408495D03*
X306223D03*
X327303Y1348187D03*
Y1360099D03*
X315063Y1372385D03*
X318463Y1384297D03*
X315063D03*
X318463Y1372385D03*
X327303Y1396583D03*
Y1408495D03*
X330703Y1348187D03*
Y1360099D03*
X339543Y1372385D03*
X342943D03*
Y1384297D03*
X339543D03*
X330703Y1396583D03*
Y1408495D03*
X351783Y1348187D03*
X355183D03*
Y1360099D03*
X351783D03*
Y1396583D03*
X355183D03*
X351783Y1408495D03*
X355183D03*
X364023Y1372385D03*
X367423Y1384297D03*
X364023D03*
X367423Y1372385D03*
X408523Y1332967D03*
X404657D03*
X440402Y1372385D03*
Y1384297D03*
X435881Y1394934D03*
Y1398800D03*
X452642Y1348187D03*
X456042D03*
Y1360099D03*
X452642D03*
X443802Y1372385D03*
Y1384297D03*
X452642Y1396583D03*
X456042D03*
X452642Y1408495D03*
X456042D03*
X454125Y1481267D03*
Y1491890D03*
Y1496621D03*
Y1578898D03*
Y1568275D03*
Y1563544D03*
Y1583629D03*
Y1609607D03*
Y1614338D03*
X464882Y1372385D03*
X468282D03*
X464882Y1384297D03*
X468282D03*
X471448Y1609607D03*
Y1614338D03*
X462786Y1613938D03*
Y1618669D03*
X480522Y1348187D03*
X477122D03*
X480522Y1360099D03*
X477122D03*
X489362Y1372385D03*
Y1384297D03*
X480522Y1396583D03*
X477122D03*
Y1408495D03*
X480522D03*
X488771Y1609607D03*
Y1614338D03*
X480109Y1613938D03*
Y1618669D03*
X501602Y1348187D03*
X505002D03*
X501602Y1360099D03*
X505002D03*
X492762Y1372385D03*
Y1384297D03*
X505002Y1396583D03*
X501602D03*
X505002Y1408495D03*
X501602D03*
X506093Y1609607D03*
X497432Y1613938D03*
Y1618669D03*
X506093Y1614338D03*
X517242Y1372385D03*
X513842D03*
X517242Y1384297D03*
X513842D03*
X514755Y1613938D03*
Y1618669D03*
X529482Y1348187D03*
X526082D03*
X529482Y1360099D03*
X526082D03*
X538322Y1384297D03*
Y1372385D03*
X526082Y1396583D03*
X529482D03*
Y1408495D03*
X526082D03*
X553962Y1348187D03*
X550562D03*
X553962Y1360099D03*
X550562D03*
X541722Y1372385D03*
Y1384297D03*
X553962Y1396583D03*
X550562D03*
X553962Y1408495D03*
X550562D03*
X566202Y1372385D03*
Y1384297D03*
X562802D03*
Y1372385D03*
X650768Y1348187D03*
Y1360099D03*
X638528Y1372385D03*
X641928D03*
X638528Y1384297D03*
X641928D03*
X650768Y1396583D03*
Y1408495D03*
X654168Y1348187D03*
Y1360099D03*
X663008Y1372385D03*
X666408D03*
X663008Y1384297D03*
X666408D03*
X654168Y1396583D03*
Y1408495D03*
X678648Y1348187D03*
X675248D03*
X678648Y1360099D03*
X675248D03*
Y1396583D03*
X678648D03*
Y1408495D03*
X675248D03*
X699728Y1348187D03*
Y1360099D03*
X690888Y1372385D03*
X687488D03*
Y1384297D03*
X690888D03*
X699728Y1396583D03*
Y1408495D03*
X703128Y1348187D03*
Y1360099D03*
X715368Y1372385D03*
X711968D03*
X715368Y1384297D03*
X711968D03*
X703128Y1396583D03*
Y1408495D03*
X727608Y1348187D03*
X724208D03*
Y1360099D03*
X727608D03*
X724208Y1396489D03*
X727608D03*
X724208Y1408401D03*
X727608D03*
X748688Y1348187D03*
Y1360099D03*
X739848Y1372385D03*
X736448D03*
X739848Y1384297D03*
X736448D03*
X752088Y1348187D03*
Y1360099D03*
X764328Y1372385D03*
X760928D03*
X764328Y1384297D03*
X760928D03*
X776568Y1348187D03*
X773168D03*
Y1360099D03*
X776568D03*
X878220Y848442D03*
Y845293D03*
X884519Y848442D03*
X897118Y842143D03*
X881370Y845293D03*
X884519Y842143D03*
Y851592D03*
X890818Y876787D03*
X885126Y889742D03*
X909714Y848442D03*
X906565Y845293D03*
X909714Y851592D03*
X912864Y879937D03*
X916014Y845293D03*
X925462Y873638D03*
X922313Y876787D03*
X928612Y870488D03*
X925462D03*
X922313Y873638D03*
X916014Y876787D03*
X928612Y873638D03*
X925462Y876787D03*
X928612D03*
Y879937D03*
X916014D03*
X919163D03*
X922313Y886236D03*
X925462D03*
X919163Y883086D03*
X925462D03*
X928612D03*
X1058113Y1372385D03*
X1054713D03*
Y1384297D03*
X1058113D03*
X1066953Y1348187D03*
X1070353D03*
X1066953Y1360099D03*
X1070353D03*
Y1396583D03*
X1066953D03*
Y1408495D03*
X1070353D03*
X1091433Y1348187D03*
Y1360099D03*
X1079193Y1372385D03*
X1082593D03*
Y1384297D03*
X1079193D03*
X1091433Y1396583D03*
Y1408495D03*
X1094833Y1348187D03*
Y1360099D03*
X1107073Y1372385D03*
X1103673D03*
X1107073Y1384297D03*
X1103673D03*
X1094833Y1396583D03*
Y1408495D03*
X1115913Y1348187D03*
X1119313D03*
X1115913Y1360099D03*
X1119313D03*
X1115913Y1396583D03*
X1119313D03*
X1115913Y1408495D03*
X1119313D03*
X1140393Y1348187D03*
Y1360099D03*
X1128153Y1384297D03*
X1131553D03*
X1128153Y1372385D03*
X1131553D03*
X1140393Y1396583D03*
Y1408495D03*
X1143793Y1348187D03*
Y1360099D03*
X1156033Y1384297D03*
X1152633D03*
X1156033Y1372385D03*
X1152633D03*
X1143793Y1396583D03*
Y1408495D03*
X1168273Y1348187D03*
X1164873D03*
Y1360099D03*
X1168273D03*
X1164873Y1396583D03*
X1168273D03*
Y1408495D03*
X1164873D03*
X1177113Y1384297D03*
X1180513D03*
X1177113Y1372385D03*
X1180513D03*
X1230326D03*
X1233726D03*
X1230326Y1384297D03*
X1233726D03*
X1245966Y1348187D03*
X1242566D03*
Y1360099D03*
X1245966D03*
X1254806Y1372385D03*
Y1384297D03*
X1245966Y1396583D03*
X1242566D03*
Y1408495D03*
X1245966D03*
X1267046Y1348187D03*
X1270446D03*
Y1360099D03*
X1267046D03*
X1258206Y1372385D03*
Y1384297D03*
X1267046Y1396583D03*
X1270446D03*
Y1408495D03*
X1267046D03*
X1279286Y1372385D03*
X1282686D03*
Y1384297D03*
X1279286D03*
X1291526Y1348187D03*
X1294926D03*
X1291526Y1360099D03*
X1294926D03*
Y1396583D03*
X1291526D03*
Y1408495D03*
X1294926D03*
X1319406Y1348187D03*
X1316006D03*
X1319406Y1360099D03*
X1316006D03*
X1307166Y1372385D03*
X1303766D03*
Y1384297D03*
X1307166D03*
X1319406Y1396583D03*
X1316006D03*
Y1408495D03*
X1319406D03*
X1335803Y829871D03*
Y842470D03*
X1329504Y836170D03*
X1335803Y845619D03*
Y836170D03*
X1329504Y842470D03*
X1335803Y833021D03*
X1323205Y845619D03*
X1326355Y848769D03*
X1323205D03*
X1329504Y855068D03*
X1320055D03*
X1326355Y867665D03*
Y870814D03*
X1323205D03*
X1329504Y867665D03*
X1332654Y877114D03*
X1329504Y873964D03*
X1326355Y889712D03*
Y892862D03*
X1329504Y886562D03*
X1332654Y883413D03*
X1331646Y1384297D03*
Y1372385D03*
X1328246D03*
Y1384297D03*
X1342103Y845619D03*
X1345252Y833021D03*
X1342103Y842470D03*
X1345252Y845619D03*
X1342103Y839320D03*
X1345252Y848769D03*
X1351550Y880263D03*
X1343886Y1348187D03*
X1340486D03*
X1343886Y1360099D03*
X1340486D03*
Y1396583D03*
X1343886D03*
Y1408495D03*
X1340486D03*
X1360999Y848769D03*
Y845619D03*
X1364148Y861367D03*
Y867665D03*
Y870814D03*
X1367298Y867665D03*
X1357849Y886562D03*
X1352726Y1384297D03*
X1356126Y1372385D03*
Y1384297D03*
X1352726Y1372385D03*
X1373597Y845619D03*
Y842470D03*
Y848769D03*
Y833021D03*
X1370447D03*
X1373597Y836170D03*
Y858218D03*
Y851918D03*
X1370447D03*
Y873964D03*
X1376747D03*
X1373597Y870814D03*
X1370447Y883413D03*
X1464770Y1372385D03*
X1461370D03*
X1464770Y1384297D03*
X1461370D03*
X1477010Y1348187D03*
X1473610D03*
Y1360099D03*
X1477010D03*
Y1396583D03*
X1473610D03*
Y1408495D03*
X1477010D03*
X1498090Y1348187D03*
Y1360099D03*
X1489250Y1372385D03*
X1485850D03*
Y1384297D03*
X1489250D03*
X1498090Y1396583D03*
Y1408495D03*
X1501490Y1348187D03*
Y1360099D03*
X1510330Y1372385D03*
X1513730D03*
Y1384297D03*
X1510330D03*
X1501490Y1396583D03*
Y1408495D03*
X1525970Y1348187D03*
X1522570D03*
Y1360099D03*
X1525970D03*
X1522570Y1396583D03*
X1525970D03*
Y1408495D03*
X1522570D03*
X1547050Y1348187D03*
Y1360099D03*
X1538210Y1372385D03*
X1534810D03*
Y1384297D03*
X1538210D03*
X1547050Y1396583D03*
Y1408495D03*
X1550450Y1348187D03*
Y1360099D03*
X1562690Y1372385D03*
X1559290D03*
X1562690Y1384297D03*
X1559290D03*
X1550450Y1396583D03*
Y1408495D03*
X1574930Y1348187D03*
X1571530D03*
X1574930Y1360099D03*
X1571530D03*
Y1396583D03*
X1574930D03*
X1571530Y1408495D03*
X1574930D03*
X1587170Y1372385D03*
X1583770D03*
Y1384297D03*
X1587170D03*
X1611398D03*
Y1372385D03*
X1623638Y1348187D03*
X1627038D03*
X1623638Y1360099D03*
X1627038D03*
X1614798Y1372385D03*
Y1384297D03*
X1627038Y1396583D03*
X1623638D03*
X1627038Y1408495D03*
X1623638D03*
X1635878Y1384297D03*
X1639278D03*
Y1372385D03*
X1635878D03*
X1651518Y1348187D03*
X1648118D03*
X1651518Y1360099D03*
X1648118D03*
X1660358Y1384297D03*
Y1372385D03*
X1651518Y1396583D03*
X1648118D03*
Y1408495D03*
X1651518D03*
X1672598Y1348187D03*
X1675998D03*
Y1360099D03*
X1672598D03*
X1663758Y1384297D03*
Y1372385D03*
X1675998Y1396583D03*
X1672598D03*
X1675998Y1408495D03*
X1672598D03*
X1684838Y1384297D03*
X1688238D03*
X1684838Y1372385D03*
X1688238D03*
X1700478Y1348187D03*
X1697078D03*
Y1360099D03*
X1700478D03*
X1709318Y1384297D03*
Y1372385D03*
X1700478Y1396583D03*
X1697078D03*
Y1408495D03*
X1700478D03*
X1721558Y1348187D03*
X1724958D03*
Y1360099D03*
X1721558D03*
X1712718Y1372385D03*
Y1384297D03*
X1721558Y1396583D03*
X1724958D03*
X1721558Y1408495D03*
X1724958D03*
X1737198Y1384297D03*
X1733798D03*
Y1372385D03*
X1737198D03*
G54D33*
G01X921318Y884651D02*
X921369Y884600D01*
X923450D01*
X923800Y884250D01*
Y879200D01*
X924600Y878400D01*
X927075D01*
X928612Y879937D01*
G01X889253Y881500D02*
Y878352D01*
X890818Y876787D01*
G01X879785Y843585D02*
Y846877D01*
X878220Y848442D01*
G01X882900Y841600D02*
Y846823D01*
X884519Y848442D01*
G01Y851592D02*
X886100Y850011D01*
Y841200D01*
G01X908100Y838100D02*
Y849978D01*
X909714Y851592D01*
G01X911279Y838289D02*
Y846877D01*
X909714Y848442D01*
G01X924100Y844000D02*
X923900Y844200D01*
Y858600D01*
G01X914450Y863251D02*
Y875223D01*
X916014Y876787D01*
G01X917558Y840368D02*
Y843749D01*
X916014Y845293D01*
G01X922313Y876787D02*
X923800Y875300D01*
Y863401D01*
X924845Y862356D01*
G01X922313Y873638D02*
X920700Y872025D01*
Y863100D01*
G01X925462Y873638D02*
X927007Y872093D01*
X929157D01*
X930217Y871033D01*
G01X925462Y876787D02*
X925513D01*
X927000Y875300D01*
X930200D01*
G01X930100Y881600D02*
X926948D01*
X925462Y883086D01*
G01X1329504Y842470D02*
X1327929Y840895D01*
Y835529D01*
X1326400Y834000D01*
Y833100D01*
G01X1332815Y833286D02*
X1334300Y834771D01*
Y844116D01*
X1335803Y845619D01*
G01X1326355Y870814D02*
X1324779Y872390D01*
X1318490D01*
G01X1323205Y870814D02*
X1321630Y869239D01*
X1318660D01*
G01X1329504Y855068D02*
X1327929Y856643D01*
X1312800D01*
G01X1323205Y848769D02*
X1321630Y847194D01*
X1318900D01*
X1318506Y846800D01*
X1317706D01*
G01X1332654Y877114D02*
X1331080Y878688D01*
X1318900D01*
G01X1321630Y834700D02*
Y844044D01*
X1323205Y845619D01*
G01X1326355Y848769D02*
X1324780Y847194D01*
Y834020D01*
X1324900Y833900D01*
G01X1335803Y842470D02*
X1337377Y840896D01*
Y835623D01*
X1339966Y833034D01*
Y832534D01*
G01X1329504Y873964D02*
X1331079Y875539D01*
X1336639D01*
X1337378Y876278D01*
Y893900D01*
G01X1326355Y889712D02*
X1327929Y891286D01*
Y894000D01*
G01X1329504Y886562D02*
X1331079Y888137D01*
Y894000D01*
G01X1321620Y895200D02*
Y885867D01*
X1322500Y884987D01*
X1331080D01*
X1332654Y883413D01*
G01X1342103Y845619D02*
X1340528Y844044D01*
Y834936D01*
X1341032Y834432D01*
G01X1343668Y830900D02*
Y837755D01*
X1342103Y839320D01*
G01X1347509Y839277D02*
Y839991D01*
X1346605Y840895D01*
X1343678D01*
X1342103Y842470D01*
G01X1360999Y848769D02*
X1362573Y847195D01*
Y834600D01*
G01X1359424Y835100D02*
Y844044D01*
X1360999Y845619D01*
G01X1364148Y861367D02*
X1365723Y859792D01*
X1383686D01*
X1384800Y858678D01*
G01X1364148Y870814D02*
X1365723Y872389D01*
Y877823D01*
X1366500Y878600D01*
X1384400D01*
G01X1359424Y893800D02*
Y888137D01*
X1357849Y886562D01*
G01X1376747Y873964D02*
X1378322Y872389D01*
X1385021D01*
G01X1373597Y858218D02*
X1375167Y856648D01*
X1382426D01*
X1382994Y856080D01*
G01X1373597Y845619D02*
X1375171Y844045D01*
X1384155D01*
G01X1373597Y842470D02*
X1372022Y840895D01*
Y838178D01*
X1372456Y837744D01*
X1377656D01*
X1378100Y837300D01*
G01X1373597Y848769D02*
X1375172Y847194D01*
X1384585D01*
X1384595Y847204D01*
G01X1373597Y851918D02*
X1375172Y853493D01*
X1384307D01*
X1384317Y853483D01*
G01X1370447Y851918D02*
X1372022Y850343D01*
X1381056D01*
G01X1370447Y873964D02*
X1372023Y875540D01*
X1384260D01*
G01X1373597Y870814D02*
X1375172Y869239D01*
X1384100D01*
G01X1370447Y883413D02*
X1372022Y881838D01*
X1384111D01*
X1384121Y881848D01*
G54D15*
X109882Y1473977D03*
Y1479095D03*
Y1576339D03*
Y1581457D03*
X127205Y1473977D03*
Y1479095D03*
X118543Y1478308D03*
Y1483426D03*
X127205Y1576339D03*
Y1581457D03*
X118543Y1580670D03*
Y1585788D03*
X144528Y1473977D03*
Y1479095D03*
X135866Y1478308D03*
Y1483426D03*
X144528Y1576339D03*
Y1581457D03*
X135866Y1580670D03*
Y1585788D03*
X161850Y1473977D03*
Y1479095D03*
X153189Y1478308D03*
Y1483426D03*
X161850Y1576339D03*
Y1581457D03*
X153189Y1580670D03*
Y1585788D03*
X170512Y1478308D03*
Y1483426D03*
Y1580670D03*
Y1585788D03*
X283110Y1489331D03*
X291771Y1493662D03*
X283110Y1494449D03*
X291771Y1498780D03*
X283110Y1591693D03*
X291771Y1596024D03*
X283110Y1596811D03*
X291771Y1601142D03*
X300433Y1489331D03*
X309094Y1493662D03*
X300433Y1494449D03*
X309094Y1498780D03*
X300433Y1591693D03*
X309094Y1596024D03*
X300433Y1596811D03*
X309094Y1601142D03*
X317756Y1489331D03*
X326417Y1493662D03*
X317756Y1494449D03*
X326417Y1498780D03*
X317756Y1591693D03*
X326417Y1596024D03*
X317756Y1596811D03*
X326417Y1601142D03*
X335078Y1489331D03*
X343740Y1493662D03*
X335078Y1494449D03*
X343740Y1498780D03*
X335078Y1591693D03*
X343740Y1596024D03*
X335078Y1596811D03*
X343740Y1601142D03*
X456339Y1504685D03*
Y1509804D03*
Y1591693D03*
Y1596811D03*
X473662Y1504685D03*
Y1509804D03*
X465000Y1509016D03*
Y1514134D03*
X473662Y1591693D03*
X465000Y1596024D03*
X473662Y1596811D03*
X465000Y1601142D03*
X490985Y1504685D03*
Y1509804D03*
X482323Y1509016D03*
Y1514134D03*
X490985Y1591693D03*
X482323Y1596024D03*
X490985Y1596811D03*
X482323Y1601142D03*
X499646Y1509016D03*
Y1514134D03*
Y1596024D03*
Y1601142D03*
X508307Y1504685D03*
X516969Y1509016D03*
X508307Y1509804D03*
X516969Y1514134D03*
X508307Y1591693D03*
X516969Y1596024D03*
X508307Y1596811D03*
X516969Y1601142D03*
X629567Y1458622D03*
Y1463741D03*
Y1560985D03*
Y1566103D03*
X646890Y1458622D03*
Y1463741D03*
X638228Y1462953D03*
Y1468071D03*
X646890Y1560985D03*
Y1566103D03*
X638228Y1565315D03*
Y1570434D03*
X664213Y1458622D03*
Y1463741D03*
X655551Y1462953D03*
Y1468071D03*
X664213Y1560985D03*
Y1566103D03*
X655551Y1565315D03*
Y1570434D03*
X681535Y1458622D03*
Y1463741D03*
X672874Y1462953D03*
Y1468071D03*
X681535Y1560985D03*
Y1566103D03*
X672874Y1565315D03*
Y1570434D03*
X690197Y1462953D03*
Y1468071D03*
Y1565315D03*
Y1570434D03*
X1131850Y1473977D03*
X1140511Y1478308D03*
X1131850Y1479095D03*
X1140511Y1483426D03*
X1131850Y1576339D03*
X1140511Y1580670D03*
X1131850Y1581457D03*
X1140511Y1585788D03*
X1149173Y1473977D03*
Y1479095D03*
Y1576339D03*
Y1581457D03*
X1166496Y1473977D03*
Y1479095D03*
X1157834Y1478308D03*
Y1483426D03*
X1166496Y1576339D03*
Y1581457D03*
X1157834Y1580670D03*
Y1585788D03*
X1183818Y1473977D03*
Y1479095D03*
X1175157Y1478308D03*
Y1483426D03*
X1183818Y1576339D03*
Y1581457D03*
X1175157Y1580670D03*
Y1585788D03*
X1192480Y1478308D03*
Y1483426D03*
Y1580670D03*
Y1585788D03*
X1305079Y1489331D03*
X1313740Y1493662D03*
X1305079Y1494449D03*
X1313740Y1498780D03*
X1305079Y1591693D03*
X1313740Y1596024D03*
X1305079Y1596811D03*
X1313740Y1601142D03*
X1322402Y1489331D03*
X1331063Y1493662D03*
X1322402Y1494449D03*
X1331063Y1498780D03*
X1322402Y1591693D03*
X1331063Y1596024D03*
X1322402Y1596811D03*
X1331063Y1601142D03*
X1339725Y1489331D03*
X1348386Y1493662D03*
X1339725Y1494449D03*
X1348386Y1498780D03*
X1339725Y1591693D03*
X1348386Y1596024D03*
X1339725Y1596811D03*
X1348386Y1601142D03*
X1357047Y1489331D03*
X1365709Y1493662D03*
X1357047Y1494449D03*
X1365709Y1498780D03*
X1357047Y1591693D03*
X1365709Y1596024D03*
X1357047Y1596811D03*
X1365709Y1601142D03*
X1478307Y1504685D03*
Y1509804D03*
Y1591693D03*
Y1596811D03*
X1495630Y1504685D03*
Y1509804D03*
X1486968Y1509016D03*
Y1514134D03*
X1495630Y1591693D03*
X1486968Y1596024D03*
X1495630Y1596811D03*
X1486968Y1601142D03*
X1512953Y1504685D03*
Y1509804D03*
X1504291Y1509016D03*
Y1514134D03*
X1512953Y1591693D03*
X1504291Y1596024D03*
X1512953Y1596811D03*
X1504291Y1601142D03*
X1530275Y1504685D03*
Y1509804D03*
X1521614Y1509016D03*
Y1514134D03*
X1530275Y1591693D03*
X1521614Y1596024D03*
X1530275Y1596811D03*
X1521614Y1601142D03*
X1538937Y1509016D03*
Y1514134D03*
Y1596024D03*
Y1601142D03*
X1651535Y1458622D03*
X1660196Y1462953D03*
X1651535Y1463741D03*
X1660196Y1468071D03*
X1651535Y1560985D03*
X1660196Y1565315D03*
X1651535Y1566103D03*
X1660196Y1570434D03*
X1668858Y1458622D03*
Y1463741D03*
Y1560985D03*
Y1566103D03*
X1686181Y1458622D03*
Y1463741D03*
X1677519Y1462953D03*
Y1468071D03*
X1686181Y1560985D03*
Y1566103D03*
X1677519Y1565315D03*
Y1570434D03*
X1703503Y1458622D03*
Y1463741D03*
X1694842Y1462953D03*
Y1468071D03*
X1703503Y1560985D03*
Y1566103D03*
X1694842Y1565315D03*
Y1570434D03*
X1712165Y1462953D03*
Y1468071D03*
Y1565315D03*
Y1570434D03*
G54D24*
X895384Y228740D03*
Y276772D03*
X923336Y226772D03*
Y278740D03*
G54D34*
G01X184904Y1068476D02*
Y1068588D01*
X184724Y1068768D01*
Y1083763D01*
X185133Y1084172D01*
X185770D01*
X186220Y1083722D01*
Y1082677D01*
G01X183794Y1068476D02*
Y1068588D01*
X183974Y1068768D01*
Y1084074D01*
X184822Y1084922D01*
X185770D01*
X186220Y1085372D01*
Y1086417D01*
G01X182480Y1078936D02*
Y1077891D01*
X182030Y1077441D01*
X181268D01*
X180235Y1076408D01*
Y1068580D01*
X180055Y1068400D01*
Y1068288D01*
G01X177424Y1068476D02*
Y1068588D01*
X177244Y1068768D01*
Y1083763D01*
X177653Y1084172D01*
X178290D01*
X178740Y1083722D01*
Y1082677D01*
G01X174999Y1075196D02*
Y1076241D01*
X174549Y1076691D01*
X174098D01*
X173504Y1076097D01*
Y1068580D01*
X173684Y1068400D01*
Y1068288D01*
G01X182480Y1075196D02*
Y1076241D01*
X182030Y1076691D01*
X181579D01*
X180985Y1076097D01*
Y1068580D01*
X181165Y1068400D01*
Y1068288D01*
G01X176314Y1068476D02*
Y1068588D01*
X176494Y1068768D01*
Y1084074D01*
X177342Y1084922D01*
X178290D01*
X178740Y1085372D01*
Y1086417D01*
G01X174999Y1078936D02*
Y1077891D01*
X174549Y1077441D01*
X173787D01*
X172754Y1076408D01*
Y1068580D01*
X172574Y1068400D01*
Y1068288D01*
G01X143088Y1184976D02*
X143200D01*
X143380Y1185156D01*
X164991D01*
X166012Y1186177D01*
Y1186939D01*
X166474Y1187401D01*
X167519D01*
G01X143088Y1186086D02*
X143200D01*
X143380Y1185906D01*
X164680D01*
X165262Y1186488D01*
Y1186939D01*
X164800Y1187401D01*
X163779D01*
G01X140088Y1193566D02*
X140200D01*
X140380Y1193386D01*
X164824D01*
X165274Y1193836D01*
Y1194431D01*
X164824Y1194881D01*
X163779D01*
G01X140288Y1188716D02*
X140400D01*
X140580Y1188896D01*
X172615D01*
X173504Y1189785D01*
Y1190691D01*
X173954Y1191141D01*
X174999D01*
G01X140088Y1192456D02*
X140200D01*
X140380Y1192636D01*
X165135D01*
X166024Y1193525D01*
Y1194431D01*
X166474Y1194881D01*
X167519D01*
G01X140288Y1189826D02*
X140400D01*
X140580Y1189646D01*
X172304D01*
X172754Y1190096D01*
Y1190691D01*
X172304Y1191141D01*
X171259D01*
G01X140388Y1196196D02*
X140500D01*
X140680Y1196376D01*
X172615D01*
X173504Y1197265D01*
Y1198171D01*
X173954Y1198621D01*
X174999D01*
G01X140388Y1201047D02*
X140500D01*
X140680Y1200867D01*
X164824D01*
X165274Y1201317D01*
Y1201912D01*
X164824Y1202362D01*
X163779D01*
G01X140388Y1197306D02*
X140500D01*
X140680Y1197126D01*
X172304D01*
X172754Y1197576D01*
Y1198171D01*
X172304Y1198621D01*
X171259D01*
G01X140388Y1199937D02*
X140500D01*
X140680Y1200117D01*
X165135D01*
X166024Y1201006D01*
Y1201912D01*
X166474Y1202362D01*
X167519D01*
G01X140088Y1204787D02*
X140200D01*
X140380Y1204607D01*
X172304D01*
X172754Y1205057D01*
Y1205652D01*
X172304Y1206102D01*
X171259D01*
G01X140088Y1203677D02*
X140200D01*
X140380Y1203857D01*
X172615D01*
X173504Y1204746D01*
Y1205652D01*
X173954Y1206102D01*
X174999D01*
G01X140388Y1207417D02*
X140500D01*
X140680Y1207597D01*
X165135D01*
X166024Y1208486D01*
Y1209392D01*
X166474Y1209842D01*
X167519D01*
G01X140388Y1212267D02*
X140500D01*
X140680Y1212087D01*
X172304D01*
X172754Y1212537D01*
Y1213132D01*
X172304Y1213582D01*
X171259D01*
G01X140388Y1208527D02*
X140500D01*
X140680Y1208347D01*
X164824D01*
X165274Y1208797D01*
Y1209392D01*
X164824Y1209842D01*
X163779D01*
G01X140488Y1216007D02*
X140600D01*
X140780Y1215827D01*
X164824D01*
X165274Y1216277D01*
Y1216872D01*
X164824Y1217322D01*
X163779D01*
G01X140488Y1214897D02*
X140600D01*
X140780Y1215077D01*
X165135D01*
X166024Y1215966D01*
Y1216872D01*
X166474Y1217322D01*
X167519D01*
G01X140388Y1211157D02*
X140500D01*
X140680Y1211337D01*
X172615D01*
X173504Y1212226D01*
Y1213132D01*
X173954Y1213582D01*
X174999D01*
G01X189960Y1075196D02*
Y1076241D01*
X189510Y1076691D01*
X189059D01*
X188465Y1076097D01*
Y1068580D01*
X188645Y1068400D01*
Y1068288D01*
G01X195015D02*
Y1068400D01*
X195195Y1068580D01*
Y1076408D01*
X196228Y1077441D01*
X196990D01*
X197440Y1077891D01*
Y1078936D01*
G01Y1075196D02*
Y1076241D01*
X196990Y1076691D01*
X196539D01*
X195945Y1076097D01*
Y1068580D01*
X196125Y1068400D01*
Y1068288D01*
G01X189960Y1078936D02*
Y1077891D01*
X189510Y1077441D01*
X188748D01*
X187715Y1076408D01*
Y1068580D01*
X187535Y1068400D01*
Y1068288D01*
G01X199865Y1068476D02*
Y1068588D01*
X199685Y1068768D01*
Y1083763D01*
X200094Y1084172D01*
X200731D01*
X201181Y1083722D01*
Y1082677D01*
G01X198755Y1068476D02*
Y1068588D01*
X198935Y1068768D01*
Y1084074D01*
X199783Y1084922D01*
X200731D01*
X201181Y1085372D01*
Y1086417D01*
G01X193700D02*
Y1085372D01*
X193250Y1084922D01*
X192302D01*
X191454Y1084074D01*
Y1068768D01*
X191274Y1068588D01*
Y1068476D01*
G01X193700Y1082677D02*
Y1083722D01*
X193250Y1084172D01*
X192613D01*
X192204Y1083763D01*
Y1068768D01*
X192384Y1068588D01*
Y1068476D01*
G01X142479Y1231251D02*
X142558Y1231172D01*
X142810D01*
X143944Y1230038D01*
X146123D01*
X146573Y1229588D01*
Y1228993D01*
X146123Y1228543D01*
X145078D01*
G01X143264Y1232036D02*
X143304Y1231996D01*
Y1231916D01*
X143303Y1231741D01*
X144255Y1230788D01*
X146434D01*
X147323Y1229899D01*
Y1228993D01*
X147773Y1228543D01*
X148818D01*
G01X142785Y1243115D02*
X142864Y1243036D01*
Y1242780D01*
X143636Y1242008D01*
X146434D01*
X147323Y1241119D01*
Y1240213D01*
X147773Y1239763D01*
X148818D01*
G01X142000Y1242330D02*
X142079Y1242251D01*
X142331Y1242252D01*
X143325Y1241258D01*
X146123D01*
X146573Y1240808D01*
Y1240213D01*
X146123Y1239763D01*
X145078D01*
G01X158724Y1259412D02*
Y1259300D01*
X158544Y1259120D01*
Y1234978D01*
X158994Y1234528D01*
X159589D01*
X160039Y1234978D01*
Y1236023D01*
G01X161334Y1259512D02*
X161354Y1259492D01*
Y1259400D01*
X161534Y1259220D01*
Y1227187D01*
X162423Y1226298D01*
X163329D01*
X163779Y1225848D01*
Y1224803D01*
G01X153874Y1259312D02*
Y1259200D01*
X154054Y1259020D01*
Y1227187D01*
X154943Y1226298D01*
X155849D01*
X156299Y1225848D01*
Y1224803D01*
G01X165094Y1259512D02*
Y1259400D01*
X165274Y1259220D01*
Y1234667D01*
X166163Y1233778D01*
X167069D01*
X167519Y1233328D01*
Y1232283D01*
G01X154984Y1259312D02*
Y1259200D01*
X154804Y1259020D01*
Y1227498D01*
X155254Y1227048D01*
X155849D01*
X156299Y1227498D01*
Y1228543D01*
G01X162444Y1259512D02*
X162464Y1259492D01*
Y1259400D01*
X162284Y1259220D01*
Y1227498D01*
X162734Y1227048D01*
X163329D01*
X163779Y1227498D01*
Y1228543D01*
G01X157614Y1259412D02*
Y1259300D01*
X157794Y1259120D01*
Y1234667D01*
X158683Y1233778D01*
X159589D01*
X160039Y1233328D01*
Y1232283D01*
G01X151244Y1259312D02*
Y1259200D01*
X151064Y1259020D01*
Y1234978D01*
X151514Y1234528D01*
X152109D01*
X152559Y1234978D01*
Y1236023D01*
G01X150134Y1259312D02*
Y1259200D01*
X150314Y1259020D01*
Y1234667D01*
X151203Y1233778D01*
X152109D01*
X152559Y1233328D01*
Y1232283D01*
G01X166204Y1259512D02*
Y1259400D01*
X166024Y1259220D01*
Y1234978D01*
X166474Y1234528D01*
X167069D01*
X167519Y1234978D01*
Y1236023D01*
G01X204921Y1078936D02*
Y1077891D01*
X204471Y1077441D01*
X203709D01*
X202676Y1076408D01*
Y1069092D01*
X202496Y1068912D01*
Y1068800D01*
G01X204921Y1075196D02*
Y1076241D01*
X204471Y1076691D01*
X204020D01*
X203426Y1076097D01*
Y1069092D01*
X203606Y1068912D01*
Y1068800D01*
G01X208661Y1086417D02*
Y1085372D01*
X208211Y1084922D01*
X207263D01*
X206415Y1084074D01*
Y1068768D01*
X206235Y1068588D01*
Y1068476D01*
G01X208661Y1082677D02*
Y1083722D01*
X208211Y1084172D01*
X207574D01*
X207165Y1083763D01*
Y1068768D01*
X207345Y1068588D01*
Y1068476D01*
G01X212401Y1078936D02*
Y1077891D01*
X211951Y1077441D01*
X211189D01*
X210156Y1076408D01*
Y1068580D01*
X209976Y1068400D01*
Y1068288D01*
G01X212401Y1075196D02*
Y1076241D01*
X211951Y1076691D01*
X211500D01*
X210906Y1076097D01*
Y1068580D01*
X211086Y1068400D01*
Y1068288D01*
G01X213715Y1068476D02*
Y1068588D01*
X213895Y1068768D01*
Y1084074D01*
X214743Y1084922D01*
X215691D01*
X216141Y1085372D01*
Y1086417D01*
G01X214825Y1068476D02*
Y1068588D01*
X214645Y1068768D01*
Y1083763D01*
X215054Y1084172D01*
X215691D01*
X216141Y1083722D01*
Y1082677D01*
G01X219881Y1078936D02*
Y1077891D01*
X219431Y1077441D01*
X218669D01*
X217636Y1076408D01*
Y1068580D01*
X217456Y1068400D01*
Y1068288D01*
G01X219881Y1075196D02*
Y1076241D01*
X219431Y1076691D01*
X218980D01*
X218386Y1076097D01*
Y1068580D01*
X218566Y1068400D01*
Y1068288D01*
G01X221196Y1068476D02*
Y1068588D01*
X221376Y1068768D01*
Y1084074D01*
X222224Y1084922D01*
X223172D01*
X223622Y1085372D01*
Y1086417D01*
G01Y1082677D02*
Y1083722D01*
X223172Y1084172D01*
X222535D01*
X222126Y1083763D01*
Y1068768D01*
X222306Y1068588D01*
Y1068476D01*
G01X227362Y1075196D02*
Y1076241D01*
X226912Y1076691D01*
X226461D01*
X225867Y1076097D01*
Y1068580D01*
X226047Y1068400D01*
Y1068288D01*
G01X227362Y1078936D02*
Y1077891D01*
X226912Y1077441D01*
X226150D01*
X225117Y1076408D01*
Y1068580D01*
X224937Y1068400D01*
Y1068288D01*
G01X231102Y1086417D02*
Y1085372D01*
X230652Y1084922D01*
X229704D01*
X228856Y1084074D01*
Y1068768D01*
X228676Y1068588D01*
Y1068476D01*
G01X231102Y1082677D02*
Y1083722D01*
X230652Y1084172D01*
X230015D01*
X229606Y1083763D01*
Y1068768D01*
X229786Y1068588D01*
Y1068476D01*
G01X229787Y1259412D02*
Y1259300D01*
X229607Y1259120D01*
Y1227498D01*
X230057Y1227048D01*
X230652D01*
X231102Y1227498D01*
Y1228543D01*
G01X228677Y1259412D02*
Y1259300D01*
X228857Y1259120D01*
Y1227187D01*
X229746Y1226298D01*
X230652D01*
X231102Y1225848D01*
Y1224803D01*
G01X236157Y1259412D02*
Y1259300D01*
X236337Y1259120D01*
Y1227187D01*
X237226Y1226298D01*
X238132D01*
X238582Y1225848D01*
Y1224803D01*
G01X237267Y1259412D02*
Y1259300D01*
X237087Y1259120D01*
Y1227498D01*
X237537Y1227048D01*
X238132D01*
X238582Y1227498D01*
Y1228543D01*
G01X241007Y1259412D02*
Y1259300D01*
X240827Y1259120D01*
Y1234978D01*
X241277Y1234528D01*
X241872D01*
X242322Y1234978D01*
Y1236023D01*
G01X239897Y1259412D02*
Y1259300D01*
X240077Y1259120D01*
Y1234667D01*
X240966Y1233778D01*
X241872D01*
X242322Y1233328D01*
Y1232283D01*
G01X244747Y1259512D02*
Y1259400D01*
X244567Y1259220D01*
Y1227498D01*
X245017Y1227048D01*
X245612D01*
X246062Y1227498D01*
Y1228543D01*
G01X232417Y1259412D02*
Y1259300D01*
X232597Y1259120D01*
Y1234667D01*
X233486Y1233778D01*
X234392D01*
X234842Y1233328D01*
Y1232283D01*
G01X243637Y1259512D02*
Y1259400D01*
X243817Y1259220D01*
Y1227187D01*
X244706Y1226298D01*
X245612D01*
X246062Y1225848D01*
Y1224803D01*
G01X233527Y1259412D02*
Y1259300D01*
X233347Y1259120D01*
Y1234978D01*
X233797Y1234528D01*
X234392D01*
X234842Y1234978D01*
Y1236023D01*
G01X262338Y1259512D02*
Y1259400D01*
X262518Y1259220D01*
Y1234667D01*
X263407Y1233778D01*
X264313D01*
X264763Y1233328D01*
Y1232283D01*
G01X258598Y1259512D02*
Y1259400D01*
X258778Y1259220D01*
Y1227187D01*
X259667Y1226298D01*
X260573D01*
X261023Y1225848D01*
Y1224803D01*
G01X252228Y1259512D02*
Y1259400D01*
X252048Y1259220D01*
Y1227498D01*
X252498Y1227048D01*
X253093D01*
X253543Y1227498D01*
Y1228543D01*
G01X247378Y1259512D02*
Y1259400D01*
X247558Y1259220D01*
Y1234667D01*
X248447Y1233778D01*
X249353D01*
X249803Y1233328D01*
Y1232283D01*
G01X254858Y1259512D02*
Y1259400D01*
X255038Y1259220D01*
Y1234667D01*
X255927Y1233778D01*
X256833D01*
X257283Y1233328D01*
Y1232283D01*
G01X255968Y1259512D02*
Y1259400D01*
X255788Y1259220D01*
Y1234978D01*
X256238Y1234528D01*
X256833D01*
X257283Y1234978D01*
Y1236023D01*
G01X259708Y1259512D02*
Y1259400D01*
X259528Y1259220D01*
Y1227498D01*
X259978Y1227048D01*
X260573D01*
X261023Y1227498D01*
Y1228543D01*
G01X251118Y1259512D02*
Y1259400D01*
X251298Y1259220D01*
Y1227187D01*
X252187Y1226298D01*
X253093D01*
X253543Y1225848D01*
Y1224803D01*
G01X248488Y1259512D02*
Y1259400D01*
X248308Y1259220D01*
Y1234978D01*
X248758Y1234528D01*
X249353D01*
X249803Y1234978D01*
Y1236023D01*
G01X266078Y1259512D02*
Y1259400D01*
X266258Y1259220D01*
Y1227187D01*
X267147Y1226298D01*
X268053D01*
X268503Y1225848D01*
Y1224803D01*
G01X273559Y1259612D02*
Y1259500D01*
X273739Y1259320D01*
Y1227187D01*
X274628Y1226298D01*
X275534D01*
X275984Y1225848D01*
Y1224803D01*
G01X270929Y1259612D02*
Y1259500D01*
X270749Y1259320D01*
Y1234978D01*
X271199Y1234528D01*
X271794D01*
X272244Y1234978D01*
Y1236023D01*
G01X277299Y1259512D02*
Y1259400D01*
X277479Y1259220D01*
Y1234667D01*
X278368Y1233778D01*
X279274D01*
X279724Y1233328D01*
Y1232283D01*
G01X278409Y1259512D02*
Y1259400D01*
X278229Y1259220D01*
Y1234978D01*
X278679Y1234528D01*
X279274D01*
X279724Y1234978D01*
Y1236023D01*
G01X274669Y1259612D02*
Y1259500D01*
X274489Y1259320D01*
Y1227498D01*
X274939Y1227048D01*
X275534D01*
X275984Y1227498D01*
Y1228543D01*
G01X269819Y1259612D02*
Y1259500D01*
X269999Y1259320D01*
Y1234667D01*
X270888Y1233778D01*
X271794D01*
X272244Y1233328D01*
Y1232283D01*
G01X267188Y1259512D02*
Y1259400D01*
X267008Y1259220D01*
Y1227498D01*
X267458Y1227048D01*
X268053D01*
X268503Y1227498D01*
Y1228543D01*
G01X263448Y1259512D02*
Y1259400D01*
X263268Y1259220D01*
Y1234978D01*
X263718Y1234528D01*
X264313D01*
X264763Y1234978D01*
Y1236023D01*
G01X284779Y1259512D02*
Y1259400D01*
X284959Y1259220D01*
Y1234667D01*
X285848Y1233778D01*
X286754D01*
X287204Y1233328D01*
Y1232283D01*
G01X281039Y1259512D02*
Y1259400D01*
X281219Y1259220D01*
Y1227187D01*
X282108Y1226298D01*
X283014D01*
X283464Y1225848D01*
Y1224803D01*
G01X282149Y1259512D02*
Y1259400D01*
X281969Y1259220D01*
Y1227498D01*
X282419Y1227048D01*
X283014D01*
X283464Y1227498D01*
Y1228543D01*
G01X285889Y1259512D02*
Y1259400D01*
X285709Y1259220D01*
Y1234978D01*
X286159Y1234528D01*
X286754D01*
X287204Y1234978D01*
Y1236023D01*
G01X650156Y1259288D02*
X650196Y1259248D01*
X650452D01*
X653500Y1256200D01*
X655323D01*
X656023Y1255500D01*
Y1227187D01*
X656912Y1226298D01*
X657818D01*
X658268Y1225848D01*
Y1224803D01*
G01X658056Y1258788D02*
X658135Y1258709D01*
X658391D01*
X659763Y1257337D01*
Y1234667D01*
X660652Y1233778D01*
X661558D01*
X662008Y1233328D01*
Y1232283D01*
G01X658841Y1259573D02*
X658920Y1259494D01*
X658919Y1259242D01*
X660513Y1257648D01*
Y1234978D01*
X660963Y1234528D01*
X661558D01*
X662008Y1234978D01*
Y1236023D01*
G01X650941Y1260073D02*
X651020Y1259994D01*
X651019Y1259742D01*
X653811Y1256950D01*
X655634D01*
X656773Y1255811D01*
Y1227498D01*
X657223Y1227048D01*
X657818D01*
X658268Y1227498D01*
Y1228543D01*
G01X663323Y1259909D02*
Y1259797D01*
X663503Y1259617D01*
Y1227187D01*
X664392Y1226298D01*
X665298D01*
X665748Y1225848D01*
Y1224803D01*
G01X664433Y1259909D02*
Y1259797D01*
X664253Y1259617D01*
Y1227498D01*
X664703Y1227048D01*
X665298D01*
X665748Y1227498D01*
Y1228543D01*
G01X667063Y1259852D02*
Y1259740D01*
X667243Y1259560D01*
Y1234667D01*
X668132Y1233778D01*
X669038D01*
X669488Y1233328D01*
Y1232283D01*
G01X668173Y1259852D02*
Y1259740D01*
X667993Y1259560D01*
Y1234978D01*
X668443Y1234528D01*
X669038D01*
X669488Y1234978D01*
Y1236023D01*
G01X639567Y1075196D02*
Y1076241D01*
X639117Y1076691D01*
X638666D01*
X638072Y1076097D01*
Y1068580D01*
X638252Y1068400D01*
Y1068288D01*
G01X639567Y1078936D02*
Y1077891D01*
X639117Y1077441D01*
X638355D01*
X637322Y1076408D01*
Y1068580D01*
X637142Y1068400D01*
Y1068288D01*
G01X632086Y1075196D02*
Y1076241D01*
X631636Y1076691D01*
X631185D01*
X630591Y1076097D01*
Y1068580D01*
X630771Y1068400D01*
Y1068288D01*
G01X632086Y1078936D02*
Y1077891D01*
X631636Y1077441D01*
X630874D01*
X629841Y1076408D01*
Y1068580D01*
X629661Y1068400D01*
Y1068288D01*
G01X670803Y1259909D02*
Y1259797D01*
X670983Y1259617D01*
Y1227187D01*
X671872Y1226298D01*
X672778D01*
X673228Y1225848D01*
Y1224803D01*
G01X675653Y1259852D02*
Y1259740D01*
X675473Y1259560D01*
Y1234978D01*
X675923Y1234528D01*
X676518D01*
X676968Y1234978D01*
Y1236023D01*
G01X671913Y1259909D02*
Y1259797D01*
X671733Y1259617D01*
Y1227498D01*
X672183Y1227048D01*
X672778D01*
X673228Y1227498D01*
Y1228543D01*
G01X674543Y1259852D02*
Y1259740D01*
X674723Y1259560D01*
Y1234667D01*
X675612Y1233778D01*
X676518D01*
X676968Y1233328D01*
Y1232283D01*
G01X678284Y1259909D02*
Y1259797D01*
X678464Y1259617D01*
Y1227187D01*
X679353Y1226298D01*
X680259D01*
X680709Y1225848D01*
Y1224803D01*
G01X640881Y1068476D02*
Y1068588D01*
X641061Y1068768D01*
Y1084074D01*
X641909Y1084922D01*
X642857D01*
X643307Y1085372D01*
Y1086417D01*
G01X641991Y1068476D02*
Y1068588D01*
X641811Y1068768D01*
Y1083763D01*
X642220Y1084172D01*
X642857D01*
X643307Y1083722D01*
Y1082677D01*
G01X633401Y1068476D02*
Y1068588D01*
X633581Y1068768D01*
Y1084074D01*
X634429Y1084922D01*
X635377D01*
X635827Y1085372D01*
Y1086417D01*
G01X634511Y1068476D02*
Y1068588D01*
X634331Y1068768D01*
Y1083763D01*
X634740Y1084172D01*
X635377D01*
X635827Y1083722D01*
Y1082677D01*
G01X679394Y1259909D02*
Y1259797D01*
X679214Y1259617D01*
Y1227498D01*
X679664Y1227048D01*
X680259D01*
X680709Y1227498D01*
Y1228543D01*
G01X682024Y1259852D02*
Y1259740D01*
X682204Y1259560D01*
Y1234667D01*
X683093Y1233778D01*
X683999D01*
X684449Y1233328D01*
Y1232283D01*
G01X683134Y1259852D02*
Y1259740D01*
X682954Y1259560D01*
Y1234978D01*
X683404Y1234528D01*
X683999D01*
X684449Y1234978D01*
Y1236023D01*
G01X686874Y1259909D02*
Y1259797D01*
X686694Y1259617D01*
Y1227498D01*
X687144Y1227048D01*
X687739D01*
X688189Y1227498D01*
Y1228543D01*
G01X685764Y1259909D02*
Y1259797D01*
X685944Y1259617D01*
Y1227187D01*
X686833Y1226298D01*
X687739D01*
X688189Y1225848D01*
Y1224803D01*
G01X690614Y1259852D02*
Y1259740D01*
X690434Y1259560D01*
Y1234978D01*
X690884Y1234528D01*
X691479D01*
X691929Y1234978D01*
Y1236023D01*
G01X689504Y1259852D02*
Y1259740D01*
X689684Y1259560D01*
Y1234667D01*
X690573Y1233778D01*
X691479D01*
X691929Y1233328D01*
Y1232283D01*
G01X696984Y1259852D02*
Y1259740D01*
X697164Y1259560D01*
Y1234667D01*
X698053Y1233778D01*
X698959D01*
X699409Y1233328D01*
Y1232283D01*
G01X698094Y1259852D02*
Y1259740D01*
X697914Y1259560D01*
Y1234978D01*
X698364Y1234528D01*
X698959D01*
X699409Y1234978D01*
Y1236023D01*
G01X694354Y1259909D02*
Y1259797D01*
X694174Y1259617D01*
Y1227498D01*
X694624Y1227048D01*
X695219D01*
X695669Y1227498D01*
Y1228543D01*
G01X693244Y1259909D02*
Y1259797D01*
X693424Y1259617D01*
Y1227187D01*
X694313Y1226298D01*
X695219D01*
X695669Y1225848D01*
Y1224803D01*
G01X700724Y1259909D02*
Y1259797D01*
X700904Y1259617D01*
Y1227187D01*
X701793Y1226298D01*
X702699D01*
X703149Y1225848D01*
Y1224803D01*
G01X705575Y1259852D02*
Y1259740D01*
X705395Y1259560D01*
Y1234978D01*
X705845Y1234528D01*
X706440D01*
X706890Y1234978D01*
Y1236023D01*
G01X701834Y1259909D02*
Y1259797D01*
X701654Y1259617D01*
Y1227498D01*
X702104Y1227048D01*
X702699D01*
X703149Y1227498D01*
Y1228543D01*
G01X704465Y1259852D02*
Y1259740D01*
X704645Y1259560D01*
Y1234667D01*
X705534Y1233778D01*
X706440D01*
X706890Y1233328D01*
Y1232283D01*
G01X710630Y1228543D02*
Y1227498D01*
X710180Y1227048D01*
X709585D01*
X709135Y1227498D01*
Y1259617D01*
X709315Y1259797D01*
Y1259909D01*
G01X708205D02*
Y1259797D01*
X708385Y1259617D01*
Y1227187D01*
X709274Y1226298D01*
X710180D01*
X710630Y1225848D01*
Y1224803D01*
G01X713055Y1259852D02*
Y1259740D01*
X712875Y1259560D01*
Y1234978D01*
X713325Y1234528D01*
X713920D01*
X714370Y1234978D01*
Y1236023D01*
G01X711945Y1259852D02*
Y1259740D01*
X712125Y1259560D01*
Y1234667D01*
X713014Y1233778D01*
X713920D01*
X714370Y1233328D01*
Y1232283D01*
G01X654527Y1075196D02*
Y1076241D01*
X654077Y1076691D01*
X653626D01*
X653032Y1076097D01*
Y1068580D01*
X653212Y1068400D01*
Y1068288D01*
G01X652102D02*
Y1068400D01*
X652282Y1068580D01*
Y1076408D01*
X653315Y1077441D01*
X654077D01*
X654527Y1077891D01*
Y1078936D01*
G01X647047Y1075196D02*
Y1076241D01*
X646597Y1076691D01*
X646146D01*
X645552Y1076097D01*
Y1068580D01*
X645732Y1068400D01*
Y1068288D01*
G01X647047Y1078936D02*
Y1077891D01*
X646597Y1077441D01*
X645835D01*
X644802Y1076408D01*
Y1068580D01*
X644622Y1068400D01*
Y1068288D01*
G01X656952Y1068476D02*
Y1068588D01*
X656772Y1068768D01*
Y1083763D01*
X657181Y1084172D01*
X657818D01*
X658268Y1083722D01*
Y1082677D01*
G01X655842Y1068476D02*
Y1068588D01*
X656022Y1068768D01*
Y1084074D01*
X656870Y1084922D01*
X657818D01*
X658268Y1085372D01*
Y1086417D01*
G01X650787Y1082677D02*
Y1083722D01*
X650337Y1084172D01*
X649700D01*
X649291Y1083763D01*
Y1068768D01*
X649471Y1068588D01*
Y1068476D01*
G01X650787Y1086417D02*
Y1085372D01*
X650337Y1084922D01*
X649389D01*
X648541Y1084074D01*
Y1068768D01*
X648361Y1068588D01*
Y1068476D01*
G01X745606Y1259909D02*
Y1259797D01*
X745786Y1259617D01*
Y1227187D01*
X746675Y1226298D01*
X747581D01*
X748031Y1225848D01*
Y1224803D01*
G01X750457Y1259852D02*
Y1259740D01*
X750277Y1259560D01*
Y1234978D01*
X750727Y1234528D01*
X751322D01*
X751772Y1234978D01*
Y1236023D01*
G01X749347Y1259852D02*
Y1259740D01*
X749527Y1259560D01*
Y1234667D01*
X750416Y1233778D01*
X751322D01*
X751772Y1233328D01*
Y1232283D01*
G01X746716Y1259909D02*
Y1259797D01*
X746536Y1259617D01*
Y1227498D01*
X746986Y1227048D01*
X747581D01*
X748031Y1227498D01*
Y1228543D01*
G01X754197Y1259909D02*
Y1259797D01*
X754017Y1259617D01*
Y1227498D01*
X754467Y1227048D01*
X755062D01*
X755512Y1227498D01*
Y1228543D01*
G01X753087Y1259909D02*
Y1259797D01*
X753267Y1259617D01*
Y1227187D01*
X754156Y1226298D01*
X755062D01*
X755512Y1225848D01*
Y1224803D01*
G01X662008Y1078936D02*
Y1077891D01*
X661558Y1077441D01*
X660796D01*
X659763Y1076408D01*
Y1069092D01*
X659583Y1068912D01*
Y1068800D01*
G01X662008Y1075196D02*
Y1076241D01*
X661558Y1076691D01*
X661107D01*
X660513Y1076097D01*
Y1069092D01*
X660693Y1068912D01*
Y1068800D01*
G01X665748Y1086417D02*
Y1085372D01*
X665298Y1084922D01*
X664350D01*
X663502Y1084074D01*
Y1068768D01*
X663322Y1068588D01*
Y1068476D01*
G01X665748Y1082677D02*
Y1083722D01*
X665298Y1084172D01*
X664661D01*
X664252Y1083763D01*
Y1068768D01*
X664432Y1068588D01*
Y1068476D01*
G01X669488Y1078936D02*
Y1077891D01*
X669038Y1077441D01*
X668276D01*
X667243Y1076408D01*
Y1068580D01*
X667063Y1068400D01*
Y1068288D01*
G01X669488Y1075196D02*
Y1076241D01*
X669038Y1076691D01*
X668587D01*
X667993Y1076097D01*
Y1068580D01*
X668173Y1068400D01*
Y1068288D01*
G01X756827Y1259852D02*
Y1259740D01*
X757007Y1259560D01*
Y1234667D01*
X757896Y1233778D01*
X758802D01*
X759252Y1233328D01*
Y1232283D01*
G01X757937Y1259852D02*
Y1259740D01*
X757757Y1259560D01*
Y1234978D01*
X758207Y1234528D01*
X758802D01*
X759252Y1234978D01*
Y1236023D01*
G01X670802Y1068476D02*
Y1068588D01*
X670982Y1068768D01*
Y1084074D01*
X671830Y1084922D01*
X672778D01*
X673228Y1085372D01*
Y1086417D01*
G01X671912Y1068476D02*
Y1068588D01*
X671732Y1068768D01*
Y1083763D01*
X672141Y1084172D01*
X672778D01*
X673228Y1083722D01*
Y1082677D01*
G01X676968Y1078936D02*
Y1077891D01*
X676518Y1077441D01*
X675756D01*
X674723Y1076408D01*
Y1068580D01*
X674543Y1068400D01*
Y1068288D01*
G01X676968Y1075196D02*
Y1076241D01*
X676518Y1076691D01*
X676067D01*
X675473Y1076097D01*
Y1068580D01*
X675653Y1068400D01*
Y1068288D01*
G01X678283Y1068476D02*
Y1068588D01*
X678463Y1068768D01*
Y1084074D01*
X679311Y1084922D01*
X680259D01*
X680709Y1085372D01*
Y1086417D01*
G01Y1082677D02*
Y1083722D01*
X680259Y1084172D01*
X679622D01*
X679213Y1083763D01*
Y1068768D01*
X679393Y1068588D01*
Y1068476D01*
G01X684449Y1078936D02*
Y1077891D01*
X683999Y1077441D01*
X683237D01*
X682204Y1076408D01*
Y1068580D01*
X682024Y1068400D01*
Y1068288D01*
G01X684449Y1075196D02*
Y1076241D01*
X683999Y1076691D01*
X683548D01*
X682954Y1076097D01*
Y1068580D01*
X683134Y1068400D01*
Y1068288D01*
G01X760567Y1259909D02*
Y1259797D01*
X760747Y1259617D01*
Y1227187D01*
X761636Y1226298D01*
X762542D01*
X762992Y1225848D01*
Y1224803D01*
G01X761677Y1259909D02*
Y1259797D01*
X761497Y1259617D01*
Y1227498D01*
X761947Y1227048D01*
X762542D01*
X762992Y1227498D01*
Y1228543D01*
G01X764307Y1259852D02*
Y1259740D01*
X764487Y1259560D01*
Y1234667D01*
X765376Y1233778D01*
X766282D01*
X766732Y1233328D01*
Y1232283D01*
G01X765417Y1259852D02*
Y1259740D01*
X765237Y1259560D01*
Y1234978D01*
X765687Y1234528D01*
X766282D01*
X766732Y1234978D01*
Y1236023D01*
G01X688189Y1086417D02*
Y1085372D01*
X687739Y1084922D01*
X686791D01*
X685943Y1084074D01*
Y1068768D01*
X685763Y1068588D01*
Y1068476D01*
G01X688189Y1082677D02*
Y1083722D01*
X687739Y1084172D01*
X687102D01*
X686693Y1083763D01*
Y1068768D01*
X686873Y1068588D01*
Y1068476D01*
G01X769157Y1259909D02*
Y1259797D01*
X768977Y1259617D01*
Y1227498D01*
X769427Y1227048D01*
X770022D01*
X770472Y1227498D01*
Y1228543D01*
G01X768047Y1259909D02*
Y1259797D01*
X768227Y1259617D01*
Y1227187D01*
X769116Y1226298D01*
X770022D01*
X770472Y1225848D01*
Y1224803D01*
G01X771787Y1259852D02*
Y1259740D01*
X771967Y1259560D01*
Y1234667D01*
X772856Y1233778D01*
X773762D01*
X774212Y1233328D01*
Y1232283D01*
G01X779268Y1255712D02*
Y1255600D01*
X779448Y1255420D01*
Y1240213D01*
X778998Y1239763D01*
X777953D01*
G01X772897Y1259852D02*
Y1259740D01*
X772717Y1259560D01*
Y1234978D01*
X773167Y1234528D01*
X773762D01*
X774212Y1234978D01*
Y1236023D01*
G01X780378Y1255712D02*
Y1255600D01*
X780198Y1255420D01*
Y1240213D01*
X780648Y1239763D01*
X781693D01*
G01X784583Y1231483D02*
X784504Y1231404D01*
X784251D01*
X782885Y1230038D01*
X780648D01*
X780198Y1229588D01*
Y1228993D01*
X780648Y1228543D01*
X781693D01*
G01X783798Y1232268D02*
X783719Y1232189D01*
Y1231933D01*
X782574Y1230788D01*
X780337D01*
X779448Y1229899D01*
Y1228993D01*
X778998Y1228543D01*
X777953D01*
G01X786512Y1218637D02*
X786400D01*
X786220Y1218817D01*
X761947D01*
X761497Y1218367D01*
Y1217772D01*
X761947Y1217322D01*
X762992D01*
G01X786512Y1219747D02*
X786400D01*
X786220Y1219567D01*
X761636D01*
X760747Y1218678D01*
Y1217772D01*
X760297Y1217322D01*
X759252D01*
G01X786512Y1216007D02*
X786400D01*
X786220Y1215827D01*
X754156D01*
X753267Y1214938D01*
Y1214032D01*
X752817Y1213582D01*
X751772D01*
G01X786512Y1214897D02*
X786400D01*
X786220Y1215077D01*
X754467D01*
X754017Y1214627D01*
Y1214032D01*
X754467Y1213582D01*
X755512D01*
G01X786512Y1211157D02*
X786400D01*
X786220Y1211337D01*
X761947D01*
X761497Y1210887D01*
Y1210292D01*
X761947Y1209842D01*
X762992D01*
G01X786512Y1208527D02*
X786400D01*
X786220Y1208347D01*
X754156D01*
X753267Y1207458D01*
Y1206552D01*
X752817Y1206102D01*
X751772D01*
G01X786512Y1212267D02*
X786400D01*
X786220Y1212087D01*
X761636D01*
X760747Y1211198D01*
Y1210292D01*
X760297Y1209842D01*
X759252D01*
G01X786612Y1203677D02*
X786500D01*
X786320Y1203857D01*
X761947D01*
X761497Y1203407D01*
Y1202812D01*
X761947Y1202362D01*
X762992D01*
G01X786412Y1199936D02*
X786300D01*
X786120Y1200116D01*
X754467D01*
X754017Y1199666D01*
Y1199071D01*
X754467Y1198621D01*
X755512D01*
G01X786612Y1204787D02*
X786500D01*
X786320Y1204607D01*
X761636D01*
X760747Y1203718D01*
Y1202812D01*
X760297Y1202362D01*
X759252D01*
G01X786412Y1201046D02*
X786300D01*
X786120Y1200866D01*
X754156D01*
X753267Y1199977D01*
Y1199071D01*
X752817Y1198621D01*
X751772D01*
G01X786512Y1207417D02*
X786400D01*
X786220Y1207597D01*
X754467D01*
X754017Y1207147D01*
Y1206552D01*
X754467Y1206102D01*
X755512D01*
G01X1096653Y1075196D02*
Y1076241D01*
X1096203Y1076691D01*
X1095752D01*
X1095158Y1076097D01*
Y1068580D01*
X1095338Y1068400D01*
Y1068288D01*
G01X1089172Y1075196D02*
Y1076241D01*
X1088722Y1076691D01*
X1088271D01*
X1087677Y1076097D01*
Y1068580D01*
X1087857Y1068400D01*
Y1068288D01*
G01X1096653Y1078936D02*
Y1077891D01*
X1096203Y1077441D01*
X1095441D01*
X1094408Y1076408D01*
Y1068580D01*
X1094228Y1068400D01*
Y1068288D01*
G01X1089172Y1078936D02*
Y1077891D01*
X1088722Y1077441D01*
X1087960D01*
X1086927Y1076408D01*
Y1068580D01*
X1086747Y1068400D01*
Y1068288D01*
G01X1099077Y1068476D02*
Y1068588D01*
X1098897Y1068768D01*
Y1083763D01*
X1099306Y1084172D01*
X1099943D01*
X1100393Y1083722D01*
Y1082677D01*
G01X1097967Y1068476D02*
Y1068588D01*
X1098147Y1068768D01*
Y1084074D01*
X1098995Y1084922D01*
X1099943D01*
X1100393Y1085372D01*
Y1086417D01*
G01X1091597Y1068476D02*
Y1068588D01*
X1091417Y1068768D01*
Y1083763D01*
X1091826Y1084172D01*
X1092463D01*
X1092913Y1083722D01*
Y1082677D01*
G01X1090487Y1068476D02*
Y1068588D01*
X1090667Y1068768D01*
Y1084074D01*
X1091515Y1084922D01*
X1092463D01*
X1092913Y1085372D01*
Y1086417D01*
G01X1054588Y1186086D02*
X1054700D01*
X1054880Y1185906D01*
X1078997D01*
X1079447Y1186356D01*
Y1186951D01*
X1078997Y1187401D01*
X1077952D01*
G01X1054588Y1184976D02*
X1054700D01*
X1054880Y1185156D01*
X1079308D01*
X1080197Y1186045D01*
Y1186951D01*
X1080647Y1187401D01*
X1081692D01*
G01X1054588Y1188716D02*
X1054700D01*
X1054880Y1188896D01*
X1086788D01*
X1087677Y1189785D01*
Y1190691D01*
X1088127Y1191141D01*
X1089172D01*
G01X1054588Y1192456D02*
X1054700D01*
X1054880Y1192636D01*
X1079308D01*
X1080197Y1193525D01*
Y1194431D01*
X1080647Y1194881D01*
X1081692D01*
G01X1054588Y1189826D02*
X1054700D01*
X1054880Y1189646D01*
X1086477D01*
X1086927Y1190096D01*
Y1190691D01*
X1086477Y1191141D01*
X1085432D01*
G01X1054588Y1193566D02*
X1054700D01*
X1054880Y1193386D01*
X1078997D01*
X1079447Y1193836D01*
Y1194431D01*
X1078997Y1194881D01*
X1077952D01*
G01X1054588Y1196196D02*
X1054700D01*
X1054880Y1196376D01*
X1086788D01*
X1087677Y1197265D01*
Y1198171D01*
X1088127Y1198621D01*
X1089172D01*
G01X1054588Y1197306D02*
X1054700D01*
X1054880Y1197126D01*
X1086477D01*
X1086927Y1197576D01*
Y1198171D01*
X1086477Y1198621D01*
X1085432D01*
G01X1054588Y1201047D02*
X1054700D01*
X1054880Y1200867D01*
X1078997D01*
X1079447Y1201317D01*
Y1201912D01*
X1078997Y1202362D01*
X1077952D01*
G01X1054488Y1203677D02*
X1054600D01*
X1054780Y1203857D01*
X1086788D01*
X1087677Y1204746D01*
Y1205652D01*
X1088127Y1206102D01*
X1089172D01*
G01X1054588Y1199937D02*
X1054700D01*
X1054880Y1200117D01*
X1079308D01*
X1080197Y1201006D01*
Y1201912D01*
X1080647Y1202362D01*
X1081692D01*
G01X1054488Y1204787D02*
X1054600D01*
X1054780Y1204607D01*
X1086477D01*
X1086927Y1205057D01*
Y1205652D01*
X1086477Y1206102D01*
X1085432D01*
G01X1054388Y1208527D02*
X1054500D01*
X1054680Y1208347D01*
X1078997D01*
X1079447Y1208797D01*
Y1209392D01*
X1078997Y1209842D01*
X1077952D01*
G01X1054388Y1207417D02*
X1054500D01*
X1054680Y1207597D01*
X1079308D01*
X1080197Y1208486D01*
Y1209392D01*
X1080647Y1209842D01*
X1081692D01*
G01X1054017Y1211157D02*
X1054129D01*
X1054309Y1211337D01*
X1086788D01*
X1087677Y1212226D01*
Y1213132D01*
X1088127Y1213582D01*
X1089172D01*
G01X1054017Y1212267D02*
X1054129D01*
X1054309Y1212087D01*
X1086477D01*
X1086927Y1212537D01*
Y1213132D01*
X1086477Y1213582D01*
X1085432D01*
G01X1054488Y1214897D02*
X1054600D01*
X1054780Y1215077D01*
X1079308D01*
X1080197Y1215966D01*
Y1216872D01*
X1080647Y1217322D01*
X1081692D01*
G01X1054488Y1216007D02*
X1054600D01*
X1054780Y1215827D01*
X1078997D01*
X1079447Y1216277D01*
Y1216872D01*
X1078997Y1217322D01*
X1077952D01*
G01X1114038Y1068476D02*
Y1068588D01*
X1113858Y1068768D01*
Y1083763D01*
X1114267Y1084172D01*
X1114904D01*
X1115354Y1083722D01*
Y1082677D01*
G01X1112928Y1068476D02*
Y1068588D01*
X1113108Y1068768D01*
Y1084074D01*
X1113956Y1084922D01*
X1114904D01*
X1115354Y1085372D01*
Y1086417D01*
G01X1111613Y1075196D02*
Y1076241D01*
X1111163Y1076691D01*
X1110712D01*
X1110118Y1076097D01*
Y1068580D01*
X1110298Y1068400D01*
Y1068288D01*
G01X1107873Y1082677D02*
Y1083722D01*
X1107423Y1084172D01*
X1106786D01*
X1106377Y1083763D01*
Y1068768D01*
X1106557Y1068588D01*
Y1068476D01*
G01X1107873Y1086417D02*
Y1085372D01*
X1107423Y1084922D01*
X1106475D01*
X1105627Y1084074D01*
Y1068768D01*
X1105447Y1068588D01*
Y1068476D01*
G01X1104133Y1075196D02*
Y1076241D01*
X1103683Y1076691D01*
X1103232D01*
X1102638Y1076097D01*
Y1068580D01*
X1102818Y1068400D01*
Y1068288D01*
G01X1109188D02*
Y1068400D01*
X1109368Y1068580D01*
Y1076408D01*
X1110401Y1077441D01*
X1111163D01*
X1111613Y1077891D01*
Y1078936D01*
G01X1104133D02*
Y1077891D01*
X1103683Y1077441D01*
X1102921D01*
X1101888Y1076408D01*
Y1068580D01*
X1101708Y1068400D01*
Y1068288D01*
G01X1055827Y1231959D02*
X1055906Y1231880D01*
X1056158Y1231881D01*
X1058001Y1230038D01*
X1060296D01*
X1060746Y1229588D01*
Y1228993D01*
X1060296Y1228543D01*
X1059251D01*
G01X1056612Y1232744D02*
X1056652Y1232704D01*
Y1232449D01*
X1058313Y1230788D01*
X1060607D01*
X1061496Y1229899D01*
Y1228993D01*
X1061946Y1228543D01*
X1062991D01*
G01X1054827Y1243259D02*
X1054906Y1243180D01*
X1055158Y1243181D01*
X1057081Y1241258D01*
X1060296D01*
X1060746Y1240808D01*
Y1240213D01*
X1060296Y1239763D01*
X1059251D01*
G01X1055612Y1244044D02*
X1055691Y1243965D01*
Y1243709D01*
X1057392Y1242008D01*
X1060607D01*
X1061496Y1241119D01*
Y1240213D01*
X1061946Y1239763D01*
X1062991D01*
G01X1069157Y1259612D02*
Y1259500D01*
X1068977Y1259320D01*
Y1227498D01*
X1069427Y1227048D01*
X1070022D01*
X1070472Y1227498D01*
Y1228543D01*
G01X1065417Y1259512D02*
Y1259400D01*
X1065237Y1259220D01*
Y1234978D01*
X1065687Y1234528D01*
X1066282D01*
X1066732Y1234978D01*
Y1236023D01*
G01X1064307Y1259512D02*
Y1259400D01*
X1064487Y1259220D01*
Y1234667D01*
X1065376Y1233778D01*
X1066282D01*
X1066732Y1233328D01*
Y1232283D01*
G01X1072897Y1259512D02*
Y1259400D01*
X1072717Y1259220D01*
Y1234978D01*
X1073167Y1234528D01*
X1073762D01*
X1074212Y1234978D01*
Y1236023D01*
G01X1071787Y1259512D02*
Y1259400D01*
X1071967Y1259220D01*
Y1234667D01*
X1072856Y1233778D01*
X1073762D01*
X1074212Y1233328D01*
Y1232283D01*
G01X1068047Y1259612D02*
Y1259500D01*
X1068227Y1259320D01*
Y1227187D01*
X1069116Y1226298D01*
X1070022D01*
X1070472Y1225848D01*
Y1224803D01*
G01X1079267Y1259724D02*
Y1259612D01*
X1079447Y1259432D01*
Y1234667D01*
X1080336Y1233778D01*
X1081242D01*
X1081692Y1233328D01*
Y1232283D01*
G01X1080377Y1259724D02*
Y1259612D01*
X1080197Y1259432D01*
Y1234978D01*
X1080647Y1234528D01*
X1081242D01*
X1081692Y1234978D01*
Y1236023D01*
G01X1075527Y1259324D02*
Y1259212D01*
X1075707Y1259032D01*
Y1227187D01*
X1076596Y1226298D01*
X1077502D01*
X1077952Y1225848D01*
Y1224803D01*
G01X1076637Y1259324D02*
Y1259212D01*
X1076457Y1259032D01*
Y1227498D01*
X1076907Y1227048D01*
X1077502D01*
X1077952Y1227498D01*
Y1228543D01*
G01X1119094Y1078936D02*
Y1077891D01*
X1118644Y1077441D01*
X1117882D01*
X1116849Y1076408D01*
Y1069092D01*
X1116669Y1068912D01*
Y1068800D01*
G01X1119094Y1075196D02*
Y1076241D01*
X1118644Y1076691D01*
X1118193D01*
X1117599Y1076097D01*
Y1069092D01*
X1117779Y1068912D01*
Y1068800D01*
G01X1122834Y1086417D02*
Y1085372D01*
X1122384Y1084922D01*
X1121436D01*
X1120588Y1084074D01*
Y1068768D01*
X1120408Y1068588D01*
Y1068476D01*
G01X1122834Y1082677D02*
Y1083722D01*
X1122384Y1084172D01*
X1121747D01*
X1121338Y1083763D01*
Y1068768D01*
X1121518Y1068588D01*
Y1068476D01*
G01X1126574Y1078936D02*
Y1077891D01*
X1126124Y1077441D01*
X1125362D01*
X1124329Y1076408D01*
Y1068580D01*
X1124149Y1068400D01*
Y1068288D01*
G01X1126574Y1075196D02*
Y1076241D01*
X1126124Y1076691D01*
X1125673D01*
X1125079Y1076097D01*
Y1068580D01*
X1125259Y1068400D01*
Y1068288D01*
G01X1127888Y1068476D02*
Y1068588D01*
X1128068Y1068768D01*
Y1084074D01*
X1128916Y1084922D01*
X1129864D01*
X1130314Y1085372D01*
Y1086417D01*
G01X1128998Y1068476D02*
Y1068588D01*
X1128818Y1068768D01*
Y1083763D01*
X1129227Y1084172D01*
X1129864D01*
X1130314Y1083722D01*
Y1082677D01*
G01X1131629Y1068288D02*
Y1068400D01*
X1131809Y1068580D01*
Y1076408D01*
X1132842Y1077441D01*
X1133604D01*
X1134054Y1077891D01*
Y1078936D01*
G01X1132739Y1068288D02*
Y1068400D01*
X1132559Y1068580D01*
Y1076097D01*
X1133153Y1076691D01*
X1133604D01*
X1134054Y1076241D01*
Y1075196D01*
G01X1135369Y1068476D02*
Y1068588D01*
X1135549Y1068768D01*
Y1084074D01*
X1136397Y1084922D01*
X1137345D01*
X1137795Y1085372D01*
Y1086417D01*
G01X1136479Y1068476D02*
Y1068588D01*
X1136299Y1068768D01*
Y1083763D01*
X1136708Y1084172D01*
X1137345D01*
X1137795Y1083722D01*
Y1082677D01*
G01X1139110Y1068288D02*
Y1068400D01*
X1139290Y1068580D01*
Y1076408D01*
X1140323Y1077441D01*
X1141085D01*
X1141535Y1077891D01*
Y1078936D01*
G01X1140220Y1068288D02*
Y1068400D01*
X1140040Y1068580D01*
Y1076097D01*
X1140634Y1076691D01*
X1141085D01*
X1141535Y1076241D01*
Y1075196D01*
G01X1142849Y1068476D02*
Y1068588D01*
X1143029Y1068768D01*
Y1084074D01*
X1143877Y1084922D01*
X1144825D01*
X1145275Y1085372D01*
Y1086417D01*
G01X1143959Y1068476D02*
Y1068588D01*
X1143779Y1068768D01*
Y1083763D01*
X1144188Y1084172D01*
X1144825D01*
X1145275Y1083722D01*
Y1082677D01*
G01X1147700Y1259312D02*
Y1259200D01*
X1147520Y1259020D01*
Y1234978D01*
X1147970Y1234528D01*
X1148565D01*
X1149015Y1234978D01*
Y1236023D01*
G01X1146590Y1259312D02*
Y1259200D01*
X1146770Y1259020D01*
Y1234667D01*
X1147659Y1233778D01*
X1148565D01*
X1149015Y1233328D01*
Y1232283D01*
G01X1151440Y1259312D02*
Y1259200D01*
X1151260Y1259020D01*
Y1227498D01*
X1151710Y1227048D01*
X1152305D01*
X1152755Y1227498D01*
Y1228543D01*
G01X1142850Y1259312D02*
Y1259200D01*
X1143030Y1259020D01*
Y1227187D01*
X1143919Y1226298D01*
X1144825D01*
X1145275Y1225848D01*
Y1224803D01*
G01X1154070Y1259312D02*
Y1259200D01*
X1154250Y1259020D01*
Y1234667D01*
X1155139Y1233778D01*
X1156045D01*
X1156495Y1233328D01*
Y1232283D01*
G01X1155180Y1259312D02*
Y1259200D01*
X1155000Y1259020D01*
Y1234978D01*
X1155450Y1234528D01*
X1156045D01*
X1156495Y1234978D01*
Y1236023D01*
G01X1143960Y1259312D02*
Y1259200D01*
X1143780Y1259020D01*
Y1227498D01*
X1144230Y1227048D01*
X1144825D01*
X1145275Y1227498D01*
Y1228543D01*
G01X1150330Y1259312D02*
Y1259200D01*
X1150510Y1259020D01*
Y1227187D01*
X1151399Y1226298D01*
X1152305D01*
X1152755Y1225848D01*
Y1224803D01*
G01X1157810Y1259312D02*
Y1259200D01*
X1157990Y1259020D01*
Y1227187D01*
X1158879Y1226298D01*
X1159785D01*
X1160235Y1225848D01*
Y1224803D01*
G01X1161551Y1259312D02*
Y1259200D01*
X1161731Y1259020D01*
Y1234667D01*
X1162620Y1233778D01*
X1163526D01*
X1163976Y1233328D01*
Y1232283D01*
G01X1165291Y1259412D02*
Y1259300D01*
X1165471Y1259120D01*
Y1227187D01*
X1166360Y1226298D01*
X1167266D01*
X1167716Y1225848D01*
Y1224803D01*
G01X1158920Y1259312D02*
Y1259200D01*
X1158740Y1259020D01*
Y1227498D01*
X1159190Y1227048D01*
X1159785D01*
X1160235Y1227498D01*
Y1228543D01*
G01X1169031Y1259412D02*
Y1259300D01*
X1169211Y1259120D01*
Y1234667D01*
X1170100Y1233778D01*
X1171006D01*
X1171456Y1233328D01*
Y1232283D01*
G01X1162661Y1259312D02*
Y1259200D01*
X1162481Y1259020D01*
Y1234978D01*
X1162931Y1234528D01*
X1163526D01*
X1163976Y1234978D01*
Y1236023D01*
G01X1170141Y1259412D02*
Y1259300D01*
X1169961Y1259120D01*
Y1234978D01*
X1170411Y1234528D01*
X1171006D01*
X1171456Y1234978D01*
Y1236023D01*
G01X1166401Y1259412D02*
Y1259300D01*
X1166221Y1259120D01*
Y1227498D01*
X1166671Y1227048D01*
X1167266D01*
X1167716Y1227498D01*
Y1228543D01*
G01X1181361Y1259612D02*
Y1259500D01*
X1181181Y1259320D01*
Y1227498D01*
X1181631Y1227048D01*
X1182226D01*
X1182676Y1227498D01*
Y1228543D01*
G01X1185102Y1259612D02*
Y1259500D01*
X1184922Y1259320D01*
Y1234978D01*
X1185372Y1234528D01*
X1185967D01*
X1186417Y1234978D01*
Y1236023D01*
G01X1177621Y1259512D02*
Y1259400D01*
X1177441Y1259220D01*
Y1234978D01*
X1177891Y1234528D01*
X1178486D01*
X1178936Y1234978D01*
Y1236023D01*
G01X1183992Y1259612D02*
Y1259500D01*
X1184172Y1259320D01*
Y1234667D01*
X1185061Y1233778D01*
X1185967D01*
X1186417Y1233328D01*
Y1232283D01*
G01X1173881Y1259512D02*
Y1259400D01*
X1173701Y1259220D01*
Y1227498D01*
X1174151Y1227048D01*
X1174746D01*
X1175196Y1227498D01*
Y1228543D01*
G01X1176511Y1259512D02*
Y1259400D01*
X1176691Y1259220D01*
Y1234667D01*
X1177580Y1233778D01*
X1178486D01*
X1178936Y1233328D01*
Y1232283D01*
G01X1180251Y1259612D02*
Y1259500D01*
X1180431Y1259320D01*
Y1227187D01*
X1181320Y1226298D01*
X1182226D01*
X1182676Y1225848D01*
Y1224803D01*
G01X1188842Y1259512D02*
Y1259400D01*
X1188662Y1259220D01*
Y1227498D01*
X1189112Y1227048D01*
X1189707D01*
X1190157Y1227498D01*
Y1228543D01*
G01X1172771Y1259512D02*
Y1259400D01*
X1172951Y1259220D01*
Y1227187D01*
X1173840Y1226298D01*
X1174746D01*
X1175196Y1225848D01*
Y1224803D01*
G01X1187732Y1259512D02*
Y1259400D01*
X1187912Y1259220D01*
Y1227187D01*
X1188801Y1226298D01*
X1189707D01*
X1190157Y1225848D01*
Y1224803D01*
G01X1195212Y1259512D02*
Y1259400D01*
X1195392Y1259220D01*
Y1227187D01*
X1196281Y1226298D01*
X1197187D01*
X1197637Y1225848D01*
Y1224803D01*
G01X1192582Y1259324D02*
Y1259212D01*
X1192402Y1259032D01*
Y1234978D01*
X1192852Y1234528D01*
X1193447D01*
X1193897Y1234978D01*
Y1236023D01*
G01X1200062Y1259412D02*
Y1259300D01*
X1199882Y1259120D01*
Y1234978D01*
X1200332Y1234528D01*
X1200927D01*
X1201377Y1234978D01*
Y1236023D01*
G01X1191472Y1259324D02*
Y1259212D01*
X1191652Y1259032D01*
Y1234667D01*
X1192541Y1233778D01*
X1193447D01*
X1193897Y1233328D01*
Y1232283D01*
G01X1197637Y1228543D02*
Y1227498D01*
X1197187Y1227048D01*
X1196592D01*
X1196142Y1227498D01*
Y1259220D01*
X1196322Y1259400D01*
Y1259512D01*
G01X1198952Y1259412D02*
Y1259300D01*
X1199132Y1259120D01*
Y1234667D01*
X1200021Y1233778D01*
X1200927D01*
X1201377Y1233328D01*
Y1232283D01*
G01X1546259Y1075196D02*
Y1076241D01*
X1545809Y1076691D01*
X1545358D01*
X1544764Y1076097D01*
Y1068580D01*
X1544944Y1068400D01*
Y1068288D01*
G01X1553740Y1078936D02*
Y1077891D01*
X1553290Y1077441D01*
X1552528D01*
X1551495Y1076408D01*
Y1068580D01*
X1551315Y1068400D01*
Y1068288D01*
G01X1553740Y1075196D02*
Y1076241D01*
X1553290Y1076691D01*
X1552839D01*
X1552245Y1076097D01*
Y1068580D01*
X1552425Y1068400D01*
Y1068288D01*
G01X1546259Y1078936D02*
Y1077891D01*
X1545809Y1077441D01*
X1545047D01*
X1544014Y1076408D01*
Y1068580D01*
X1543834Y1068400D01*
Y1068288D01*
G01X1556164Y1068476D02*
Y1068588D01*
X1555984Y1068768D01*
Y1083763D01*
X1556393Y1084172D01*
X1557030D01*
X1557480Y1083722D01*
Y1082677D01*
G01Y1086417D02*
Y1085372D01*
X1557030Y1084922D01*
X1556082D01*
X1555234Y1084074D01*
Y1068768D01*
X1555054Y1068588D01*
Y1068476D01*
G01X1547574D02*
Y1068588D01*
X1547754Y1068768D01*
Y1084074D01*
X1548602Y1084922D01*
X1549550D01*
X1550000Y1085372D01*
Y1086417D01*
G01X1548684Y1068476D02*
Y1068588D01*
X1548504Y1068768D01*
Y1083763D01*
X1548913Y1084172D01*
X1549550D01*
X1550000Y1083722D01*
Y1082677D01*
G01X1570016Y1259752D02*
Y1259640D01*
X1570196Y1259460D01*
Y1227187D01*
X1571085Y1226298D01*
X1571991D01*
X1572441Y1225848D01*
Y1224803D01*
G01X1571126Y1259752D02*
Y1259640D01*
X1570946Y1259460D01*
Y1227498D01*
X1571396Y1227048D01*
X1571991D01*
X1572441Y1227498D01*
Y1228543D01*
G01X1574866Y1259800D02*
Y1259688D01*
X1574686Y1259508D01*
Y1234978D01*
X1575136Y1234528D01*
X1575731D01*
X1576181Y1234978D01*
Y1236023D01*
G01X1577496Y1259800D02*
Y1259688D01*
X1577676Y1259508D01*
Y1227187D01*
X1578565Y1226298D01*
X1579471D01*
X1579921Y1225848D01*
Y1224803D01*
G01X1573756Y1259800D02*
Y1259688D01*
X1573936Y1259508D01*
Y1234667D01*
X1574825Y1233778D01*
X1575731D01*
X1576181Y1233328D01*
Y1232283D01*
G01X1578606Y1259800D02*
Y1259688D01*
X1578426Y1259508D01*
Y1227498D01*
X1578876Y1227048D01*
X1579471D01*
X1579921Y1227498D01*
Y1228543D01*
G01X1582346Y1259800D02*
Y1259688D01*
X1582166Y1259508D01*
Y1234978D01*
X1582616Y1234528D01*
X1583211D01*
X1583661Y1234978D01*
Y1236023D01*
G01X1581236Y1259800D02*
Y1259688D01*
X1581416Y1259508D01*
Y1234667D01*
X1582305Y1233778D01*
X1583211D01*
X1583661Y1233328D01*
Y1232283D01*
G01X1570015Y1068476D02*
Y1068588D01*
X1570195Y1068768D01*
Y1084074D01*
X1571043Y1084922D01*
X1571991D01*
X1572441Y1085372D01*
Y1086417D01*
G01X1571125Y1068476D02*
Y1068588D01*
X1570945Y1068768D01*
Y1083763D01*
X1571354Y1084172D01*
X1571991D01*
X1572441Y1083722D01*
Y1082677D01*
G01X1566275Y1068288D02*
Y1068400D01*
X1566455Y1068580D01*
Y1076408D01*
X1567488Y1077441D01*
X1568250D01*
X1568700Y1077891D01*
Y1078936D01*
G01X1564960Y1082677D02*
Y1083722D01*
X1564510Y1084172D01*
X1563873D01*
X1563464Y1083763D01*
Y1068768D01*
X1563644Y1068588D01*
Y1068476D01*
G01X1564960Y1086417D02*
Y1085372D01*
X1564510Y1084922D01*
X1563562D01*
X1562714Y1084074D01*
Y1068768D01*
X1562534Y1068588D01*
Y1068476D01*
G01X1568700Y1075196D02*
Y1076241D01*
X1568250Y1076691D01*
X1567799D01*
X1567205Y1076097D01*
Y1068580D01*
X1567385Y1068400D01*
Y1068288D01*
G01X1561220Y1075196D02*
Y1076241D01*
X1560770Y1076691D01*
X1560319D01*
X1559725Y1076097D01*
Y1068580D01*
X1559905Y1068400D01*
Y1068288D01*
G01X1561220Y1078936D02*
Y1077891D01*
X1560770Y1077441D01*
X1560008D01*
X1558975Y1076408D01*
Y1068580D01*
X1558795Y1068400D01*
Y1068288D01*
G01X1586086Y1259800D02*
Y1259688D01*
X1585906Y1259508D01*
Y1227498D01*
X1586356Y1227048D01*
X1586951D01*
X1587401Y1227498D01*
Y1228543D01*
G01X1584976Y1259800D02*
Y1259688D01*
X1585156Y1259508D01*
Y1227187D01*
X1586045Y1226298D01*
X1586951D01*
X1587401Y1225848D01*
Y1224803D01*
G01X1588716Y1259800D02*
Y1259688D01*
X1588896Y1259508D01*
Y1234667D01*
X1589785Y1233778D01*
X1590691D01*
X1591141Y1233328D01*
Y1232283D01*
G01X1589826Y1259800D02*
Y1259688D01*
X1589646Y1259508D01*
Y1234978D01*
X1590096Y1234528D01*
X1590691D01*
X1591141Y1234978D01*
Y1236023D01*
G01X1592457Y1259800D02*
Y1259688D01*
X1592637Y1259508D01*
Y1227187D01*
X1593526Y1226298D01*
X1594432D01*
X1594882Y1225848D01*
Y1224803D01*
G01X1593567Y1259800D02*
Y1259688D01*
X1593387Y1259508D01*
Y1227498D01*
X1593837Y1227048D01*
X1594432D01*
X1594882Y1227498D01*
Y1228543D01*
G01X1597307Y1259800D02*
Y1259688D01*
X1597127Y1259508D01*
Y1234978D01*
X1597577Y1234528D01*
X1598172D01*
X1598622Y1234978D01*
Y1236023D01*
G01X1599937Y1259800D02*
Y1259688D01*
X1600117Y1259508D01*
Y1227187D01*
X1601006Y1226298D01*
X1601912D01*
X1602362Y1225848D01*
Y1224803D01*
G01X1596197Y1259800D02*
Y1259688D01*
X1596377Y1259508D01*
Y1234667D01*
X1597266Y1233778D01*
X1598172D01*
X1598622Y1233328D01*
Y1232283D01*
G01X1601047Y1259800D02*
Y1259688D01*
X1600867Y1259508D01*
Y1227498D01*
X1601317Y1227048D01*
X1601912D01*
X1602362Y1227498D01*
Y1228543D01*
G01X1604787Y1259800D02*
Y1259688D01*
X1604607Y1259508D01*
Y1234978D01*
X1605057Y1234528D01*
X1605652D01*
X1606102Y1234978D01*
Y1236023D01*
G01X1603677Y1259800D02*
Y1259688D01*
X1603857Y1259508D01*
Y1234667D01*
X1604746Y1233778D01*
X1605652D01*
X1606102Y1233328D01*
Y1232283D01*
G01X1608527Y1259800D02*
Y1259688D01*
X1608347Y1259508D01*
Y1227498D01*
X1608797Y1227048D01*
X1609392D01*
X1609842Y1227498D01*
Y1228543D01*
G01X1607417Y1259800D02*
Y1259688D01*
X1607597Y1259508D01*
Y1227187D01*
X1608486Y1226298D01*
X1609392D01*
X1609842Y1225848D01*
Y1224803D01*
G01X1612267Y1259800D02*
Y1259688D01*
X1612087Y1259508D01*
Y1234978D01*
X1612537Y1234528D01*
X1613132D01*
X1613582Y1234978D01*
Y1236023D01*
G01X1611157Y1259800D02*
Y1259688D01*
X1611337Y1259508D01*
Y1234667D01*
X1612226Y1233778D01*
X1613132D01*
X1613582Y1233328D01*
Y1232283D01*
G01X1614897Y1259800D02*
Y1259688D01*
X1615077Y1259508D01*
Y1227187D01*
X1615966Y1226298D01*
X1616872D01*
X1617322Y1225848D01*
Y1224803D01*
G01X1616007Y1259800D02*
Y1259688D01*
X1615827Y1259508D01*
Y1227498D01*
X1616277Y1227048D01*
X1616872D01*
X1617322Y1227498D01*
Y1228543D01*
G01X1576181Y1078936D02*
Y1077891D01*
X1575731Y1077441D01*
X1574969D01*
X1573936Y1076408D01*
Y1069092D01*
X1573756Y1068912D01*
Y1068800D01*
G01X1576181Y1075196D02*
Y1076241D01*
X1575731Y1076691D01*
X1575280D01*
X1574686Y1076097D01*
Y1069092D01*
X1574866Y1068912D01*
Y1068800D01*
G01X1579921Y1086417D02*
Y1085372D01*
X1579471Y1084922D01*
X1578523D01*
X1577675Y1084074D01*
Y1068768D01*
X1577495Y1068588D01*
Y1068476D01*
G01X1579921Y1082677D02*
Y1083722D01*
X1579471Y1084172D01*
X1578834D01*
X1578425Y1083763D01*
Y1068768D01*
X1578605Y1068588D01*
Y1068476D01*
G01X1622378Y1259800D02*
Y1259688D01*
X1622558Y1259508D01*
Y1227187D01*
X1623447Y1226298D01*
X1624353D01*
X1624803Y1225848D01*
Y1224803D01*
G01X1619748Y1259800D02*
Y1259688D01*
X1619568Y1259508D01*
Y1234978D01*
X1620018Y1234528D01*
X1620613D01*
X1621063Y1234978D01*
Y1236023D01*
G01X1618638Y1259800D02*
Y1259688D01*
X1618818Y1259508D01*
Y1234667D01*
X1619707Y1233778D01*
X1620613D01*
X1621063Y1233328D01*
Y1232283D01*
G01X1623488Y1259800D02*
Y1259688D01*
X1623308Y1259508D01*
Y1227498D01*
X1623758Y1227048D01*
X1624353D01*
X1624803Y1227498D01*
Y1228543D01*
G01X1583661Y1078936D02*
Y1077891D01*
X1583211Y1077441D01*
X1582449D01*
X1581416Y1076408D01*
Y1068580D01*
X1581236Y1068400D01*
Y1068288D01*
G01X1583661Y1075196D02*
Y1076241D01*
X1583211Y1076691D01*
X1582760D01*
X1582166Y1076097D01*
Y1068580D01*
X1582346Y1068400D01*
Y1068288D01*
G01X1584975Y1068476D02*
Y1068588D01*
X1585155Y1068768D01*
Y1084074D01*
X1586003Y1084922D01*
X1586951D01*
X1587401Y1085372D01*
Y1086417D01*
G01X1586085Y1068476D02*
Y1068588D01*
X1585905Y1068768D01*
Y1083763D01*
X1586314Y1084172D01*
X1586951D01*
X1587401Y1083722D01*
Y1082677D01*
G01X1591141Y1078936D02*
Y1077891D01*
X1590691Y1077441D01*
X1589929D01*
X1588896Y1076408D01*
Y1068580D01*
X1588716Y1068400D01*
Y1068288D01*
G01X1591141Y1075196D02*
Y1076241D01*
X1590691Y1076691D01*
X1590240D01*
X1589646Y1076097D01*
Y1068580D01*
X1589826Y1068400D01*
Y1068288D01*
G01X1594882Y1082677D02*
Y1083722D01*
X1594432Y1084172D01*
X1593795D01*
X1593386Y1083763D01*
Y1068768D01*
X1593566Y1068588D01*
Y1068476D01*
G01X1592456D02*
Y1068588D01*
X1592636Y1068768D01*
Y1084074D01*
X1593484Y1084922D01*
X1594432D01*
X1594882Y1085372D01*
Y1086417D01*
G01X1627228Y1260112D02*
Y1260000D01*
X1627048Y1259820D01*
Y1234978D01*
X1627498Y1234528D01*
X1628093D01*
X1628543Y1234978D01*
Y1236023D01*
G01X1626118Y1260112D02*
Y1260000D01*
X1626298Y1259820D01*
Y1234667D01*
X1627187Y1233778D01*
X1628093D01*
X1628543Y1233328D01*
Y1232283D01*
G01X1598622Y1078936D02*
Y1077891D01*
X1598172Y1077441D01*
X1597410D01*
X1596377Y1076408D01*
Y1068580D01*
X1596197Y1068400D01*
Y1068288D01*
G01X1598622Y1075196D02*
Y1076241D01*
X1598172Y1076691D01*
X1597721D01*
X1597127Y1076097D01*
Y1068580D01*
X1597307Y1068400D01*
Y1068288D01*
G01X1602362Y1082677D02*
Y1083722D01*
X1601912Y1084172D01*
X1601275D01*
X1600866Y1083763D01*
Y1068768D01*
X1601046Y1068588D01*
Y1068476D01*
G01X1599936D02*
Y1068588D01*
X1600116Y1068768D01*
Y1084074D01*
X1600964Y1084922D01*
X1601912D01*
X1602362Y1085372D01*
Y1086417D01*
G01X1660889Y1259824D02*
Y1259712D01*
X1660709Y1259532D01*
Y1227498D01*
X1661159Y1227048D01*
X1661754D01*
X1662204Y1227498D01*
Y1228543D01*
G01X1659779Y1259824D02*
Y1259712D01*
X1659959Y1259532D01*
Y1227187D01*
X1660848Y1226298D01*
X1661754D01*
X1662204Y1225848D01*
Y1224803D01*
G01X1663520Y1259600D02*
Y1259488D01*
X1663700Y1259308D01*
Y1234667D01*
X1664589Y1233778D01*
X1665495D01*
X1665945Y1233328D01*
Y1232283D01*
G01X1664630Y1259600D02*
Y1259488D01*
X1664450Y1259308D01*
Y1234978D01*
X1664900Y1234528D01*
X1665495D01*
X1665945Y1234978D01*
Y1236023D01*
G01X1668370Y1259600D02*
Y1259488D01*
X1668190Y1259308D01*
Y1227498D01*
X1668640Y1227048D01*
X1669235D01*
X1669685Y1227498D01*
Y1228543D01*
G01X1667260Y1259600D02*
Y1259488D01*
X1667440Y1259308D01*
Y1227187D01*
X1668329Y1226298D01*
X1669235D01*
X1669685Y1225848D01*
Y1224803D01*
G01X1671000Y1259600D02*
Y1259488D01*
X1671180Y1259308D01*
Y1234667D01*
X1672069Y1233778D01*
X1672975D01*
X1673425Y1233328D01*
Y1232283D01*
G01X1672110Y1259600D02*
Y1259488D01*
X1671930Y1259308D01*
Y1234978D01*
X1672380Y1234528D01*
X1672975D01*
X1673425Y1234978D01*
Y1236023D01*
G01X1675850Y1259600D02*
Y1259488D01*
X1675670Y1259308D01*
Y1227498D01*
X1676120Y1227048D01*
X1676715D01*
X1677165Y1227498D01*
Y1228543D01*
G01X1674740Y1259600D02*
Y1259488D01*
X1674920Y1259308D01*
Y1227187D01*
X1675809Y1226298D01*
X1676715D01*
X1677165Y1225848D01*
Y1224803D01*
G01X1679590Y1259600D02*
Y1259488D01*
X1679410Y1259308D01*
Y1234978D01*
X1679860Y1234528D01*
X1680455D01*
X1680905Y1234978D01*
Y1236023D01*
G01X1678480Y1259600D02*
Y1259488D01*
X1678660Y1259308D01*
Y1234667D01*
X1679549Y1233778D01*
X1680455D01*
X1680905Y1233328D01*
Y1232283D01*
G01X1700624Y1204787D02*
X1700512D01*
X1700332Y1204607D01*
X1675809D01*
X1674920Y1203718D01*
Y1202812D01*
X1674470Y1202362D01*
X1673425D01*
G01X1700624Y1203677D02*
X1700512D01*
X1700332Y1203857D01*
X1676120D01*
X1675670Y1203407D01*
Y1202812D01*
X1676120Y1202362D01*
X1677165D01*
G01X1700812Y1201046D02*
X1700700D01*
X1700520Y1200866D01*
X1668329D01*
X1667440Y1199977D01*
Y1199071D01*
X1666990Y1198621D01*
X1665945D01*
G01X1700812Y1199936D02*
X1700700D01*
X1700520Y1200116D01*
X1668640D01*
X1668190Y1199666D01*
Y1199071D01*
X1668640Y1198621D01*
X1669685D01*
G01X1700712Y1211157D02*
X1700600D01*
X1700420Y1211337D01*
X1676120D01*
X1675670Y1210887D01*
Y1210292D01*
X1676120Y1209842D01*
X1677165D01*
G01X1700424Y1208527D02*
X1700312D01*
X1700132Y1208347D01*
X1668329D01*
X1667440Y1207458D01*
Y1206552D01*
X1666990Y1206102D01*
X1665945D01*
G01X1700612Y1218637D02*
X1700500D01*
X1700320Y1218817D01*
X1676120D01*
X1675670Y1218367D01*
Y1217772D01*
X1676120Y1217322D01*
X1677165D01*
G01X1700712Y1214897D02*
X1700600D01*
X1700420Y1215077D01*
X1668640D01*
X1668190Y1214627D01*
Y1214032D01*
X1668640Y1213582D01*
X1669685D01*
G01X1700712Y1212267D02*
X1700600D01*
X1700420Y1212087D01*
X1675809D01*
X1674920Y1211198D01*
Y1210292D01*
X1674470Y1209842D01*
X1673425D01*
G01X1700424Y1207417D02*
X1700312D01*
X1700132Y1207597D01*
X1668640D01*
X1668190Y1207147D01*
Y1206552D01*
X1668640Y1206102D01*
X1669685D01*
G01X1700712Y1216007D02*
X1700600D01*
X1700420Y1215827D01*
X1668329D01*
X1667440Y1214938D01*
Y1214032D01*
X1666990Y1213582D01*
X1665945D01*
G01X1700612Y1219747D02*
X1700500D01*
X1700320Y1219567D01*
X1675809D01*
X1674920Y1218678D01*
Y1217772D01*
X1674470Y1217322D01*
X1673425D01*
G01X1682220Y1259600D02*
Y1259488D01*
X1682400Y1259308D01*
Y1227187D01*
X1683289Y1226298D01*
X1684195D01*
X1684645Y1225848D01*
Y1224803D01*
G01X1683330Y1259600D02*
Y1259488D01*
X1683150Y1259308D01*
Y1227498D01*
X1683600Y1227048D01*
X1684195D01*
X1684645Y1227498D01*
Y1228543D01*
G01X1685960Y1259600D02*
Y1259488D01*
X1686140Y1259308D01*
Y1234667D01*
X1687029Y1233778D01*
X1687935D01*
X1688385Y1233328D01*
Y1232283D01*
G01X1687070Y1259600D02*
Y1259488D01*
X1686890Y1259308D01*
Y1234978D01*
X1687340Y1234528D01*
X1687935D01*
X1688385Y1234978D01*
Y1236023D01*
G01X1694551Y1256012D02*
Y1255900D01*
X1694371Y1255720D01*
Y1240213D01*
X1694821Y1239763D01*
X1695866D01*
G01X1693441Y1256012D02*
Y1255900D01*
X1693621Y1255720D01*
Y1240213D01*
X1693171Y1239763D01*
X1692126D01*
G01X1697799Y1231599D02*
X1697720Y1231520D01*
Y1231288D01*
X1697220Y1230788D01*
X1694406D01*
X1693621Y1230003D01*
Y1228993D01*
X1693171Y1228543D01*
X1692126D01*
G01X1698584Y1230814D02*
X1698505Y1230735D01*
X1698228D01*
X1697531Y1230038D01*
X1694717D01*
X1694371Y1229692D01*
Y1228993D01*
X1694821Y1228543D01*
X1695866D01*
G54D16*
X109882Y1484213D03*
Y1499567D03*
Y1586575D03*
Y1601930D03*
Y1617284D03*
X127205Y1484213D03*
X118543Y1488544D03*
X127205Y1499567D03*
Y1514922D03*
X118543Y1503898D03*
X127205Y1586575D03*
X118543Y1590906D03*
X127205Y1601930D03*
X118543Y1606260D03*
X127205Y1617284D03*
X118543Y1621615D03*
X144528Y1484213D03*
X135866Y1488544D03*
X144528Y1499567D03*
Y1514922D03*
X135866Y1503898D03*
Y1519252D03*
X144528Y1586575D03*
X135866Y1590906D03*
X144528Y1601930D03*
X135866Y1606260D03*
X144528Y1617284D03*
X135866Y1621615D03*
X161850Y1484213D03*
X153189Y1488544D03*
X161850Y1499567D03*
Y1514922D03*
X153189Y1503898D03*
Y1519252D03*
X161850Y1586575D03*
X153189Y1590906D03*
X161850Y1601930D03*
X153189Y1606260D03*
X161850Y1617284D03*
X153189Y1621615D03*
X179173Y1468859D03*
Y1484213D03*
X170512Y1488544D03*
X179173Y1499567D03*
Y1514922D03*
X170512Y1503898D03*
Y1519252D03*
X179173Y1555867D03*
Y1571221D03*
Y1586575D03*
X170512Y1590906D03*
X179173Y1601930D03*
X170512Y1606260D03*
X179173Y1617284D03*
X170512Y1621615D03*
X187835Y1457835D03*
Y1473189D03*
Y1488544D03*
Y1503898D03*
Y1519252D03*
Y1560197D03*
Y1575552D03*
Y1590906D03*
Y1606260D03*
Y1621615D03*
X283110Y1499567D03*
X291771Y1503898D03*
X283110Y1601930D03*
X291771Y1606260D03*
X283110Y1617284D03*
X291771Y1621615D03*
X300433Y1499567D03*
X309094Y1503898D03*
X300433Y1514922D03*
X309094Y1519252D03*
X300433Y1601930D03*
X309094Y1606260D03*
X300433Y1617284D03*
X309094Y1621615D03*
X317756Y1499567D03*
X326417Y1503898D03*
X317756Y1514922D03*
X326417Y1519252D03*
X317756Y1601930D03*
X326417Y1606260D03*
X317756Y1617284D03*
X326417Y1621615D03*
X335078Y1499567D03*
X343740Y1503898D03*
X335078Y1514922D03*
X343740Y1519252D03*
X335078Y1601930D03*
X343740Y1606260D03*
X335078Y1617284D03*
X343740Y1621615D03*
X361063Y1457835D03*
X352401Y1468859D03*
X361063Y1473189D03*
X352401Y1484213D03*
X361063Y1488544D03*
X352401Y1499567D03*
X361063Y1503898D03*
X352401Y1514922D03*
X361063Y1519252D03*
X352401Y1555867D03*
X361063Y1560197D03*
X352401Y1571221D03*
X361063Y1575552D03*
X352401Y1586575D03*
X361063Y1590906D03*
X352401Y1601930D03*
X361063Y1606260D03*
X352401Y1617284D03*
X361063Y1621615D03*
X456339Y1514922D03*
Y1601930D03*
Y1617284D03*
X473662Y1514922D03*
X465000Y1519252D03*
X473662Y1601930D03*
X465000Y1606260D03*
X473662Y1617284D03*
X465000Y1621615D03*
X490985Y1514922D03*
X482323Y1519252D03*
X490985Y1601930D03*
X482323Y1606260D03*
X490985Y1617284D03*
X482323Y1621615D03*
X508307Y1514922D03*
X499646Y1519252D03*
X508307Y1601930D03*
X499646Y1606260D03*
X508307Y1617284D03*
X499646Y1621615D03*
X516969Y1519252D03*
Y1606260D03*
Y1621615D03*
X534292Y1560197D03*
X525630Y1571221D03*
X534292Y1575552D03*
X525630Y1586575D03*
X534292Y1590906D03*
X525630Y1601930D03*
X534292Y1606260D03*
X525630Y1617284D03*
X534292Y1621615D03*
X629567Y1571221D03*
X638228Y1575552D03*
X629567Y1586575D03*
X638228Y1590906D03*
X629567Y1601930D03*
X638228Y1606260D03*
X629567Y1617284D03*
X638228Y1621615D03*
X646890Y1571221D03*
Y1586575D03*
Y1601930D03*
Y1617284D03*
X664213Y1571221D03*
X655551Y1575552D03*
X664213Y1586575D03*
X655551Y1590906D03*
X664213Y1601930D03*
X655551Y1606260D03*
X664213Y1617284D03*
X655551Y1621615D03*
X681535Y1571221D03*
X672874Y1575552D03*
X681535Y1586575D03*
X672874Y1590906D03*
X681535Y1601930D03*
X672874Y1606260D03*
X681535Y1617284D03*
X672874Y1621615D03*
X698858Y1571221D03*
X690197Y1575552D03*
X698858Y1586575D03*
X690197Y1590906D03*
X698858Y1601930D03*
X690197Y1606260D03*
X698858Y1617284D03*
X690197Y1621615D03*
X707520Y1457835D03*
Y1473189D03*
Y1488544D03*
Y1503898D03*
Y1519252D03*
Y1560197D03*
Y1575552D03*
Y1590906D03*
Y1606260D03*
Y1621615D03*
X1131850Y1586575D03*
X1140511Y1590906D03*
X1131850Y1601930D03*
X1140511Y1606260D03*
X1131850Y1617284D03*
X1140511Y1621615D03*
X1149173Y1586575D03*
X1157834Y1590906D03*
X1149173Y1601930D03*
X1157834Y1606260D03*
X1149173Y1617284D03*
X1157834Y1621615D03*
X1166496Y1586575D03*
Y1601930D03*
Y1617284D03*
X1183818Y1586575D03*
X1175157Y1590906D03*
X1183818Y1601930D03*
X1175157Y1606260D03*
X1183818Y1617284D03*
X1175157Y1621615D03*
X1201141Y1586575D03*
X1192480Y1590906D03*
X1201141Y1601930D03*
X1192480Y1606260D03*
X1201141Y1617284D03*
X1192480Y1621615D03*
X1209803Y1457835D03*
Y1473189D03*
Y1488544D03*
Y1503898D03*
Y1519252D03*
Y1560197D03*
Y1575552D03*
Y1590906D03*
Y1606260D03*
Y1621615D03*
X1313740Y1606260D03*
X1305079Y1617284D03*
X1313740Y1621615D03*
X1331063Y1606260D03*
X1322402Y1617284D03*
X1331063Y1621615D03*
X1348386Y1606260D03*
X1339725Y1617284D03*
X1348386Y1621615D03*
X1365709Y1606260D03*
X1357047Y1617284D03*
X1365709Y1621615D03*
X1374370Y1601930D03*
X1383032Y1606260D03*
X1374370Y1617284D03*
X1383032Y1621615D03*
X1478307Y1514922D03*
Y1555867D03*
Y1601930D03*
Y1617284D03*
X1495630Y1514922D03*
X1486968Y1519252D03*
X1495630Y1601930D03*
X1486968Y1606260D03*
X1495630Y1617284D03*
X1486968Y1621615D03*
X1512953Y1514922D03*
X1504291Y1519252D03*
X1512953Y1601930D03*
X1504291Y1606260D03*
X1512953Y1617284D03*
X1504291Y1621615D03*
X1530275Y1514922D03*
X1521614Y1519252D03*
X1530275Y1601930D03*
X1521614Y1606260D03*
X1530275Y1617284D03*
X1521614Y1621615D03*
X1547598Y1571221D03*
Y1586575D03*
Y1601930D03*
X1538937Y1606260D03*
X1547598Y1617284D03*
X1538937Y1621615D03*
X1556260Y1560197D03*
Y1575552D03*
Y1590906D03*
Y1606260D03*
Y1621615D03*
X1651535Y1484213D03*
X1660196Y1488544D03*
X1651535Y1499567D03*
X1660196Y1503898D03*
X1651535Y1571221D03*
X1660196Y1575552D03*
X1651535Y1586575D03*
X1660196Y1590906D03*
X1651535Y1601930D03*
X1660196Y1606260D03*
X1651535Y1617284D03*
X1660196Y1621615D03*
X1668858Y1484213D03*
X1677519Y1488544D03*
X1668858Y1499567D03*
X1677519Y1503898D03*
X1668858Y1514922D03*
X1677519Y1519252D03*
X1668858Y1571221D03*
X1677519Y1575552D03*
X1668858Y1586575D03*
X1677519Y1590906D03*
X1668858Y1601930D03*
X1677519Y1606260D03*
X1668858Y1617284D03*
X1677519Y1621615D03*
X1686181Y1484213D03*
Y1499567D03*
Y1514922D03*
Y1571221D03*
Y1586575D03*
Y1601930D03*
Y1617284D03*
X1703503Y1484213D03*
X1694842Y1488544D03*
X1703503Y1499567D03*
Y1514922D03*
X1694842Y1503898D03*
Y1519252D03*
X1703503Y1571221D03*
X1694842Y1575552D03*
X1703503Y1586575D03*
X1694842Y1590906D03*
X1703503Y1601930D03*
X1694842Y1606260D03*
X1703503Y1617284D03*
X1694842Y1621615D03*
X1720826Y1484213D03*
X1712165Y1488544D03*
X1720826Y1499567D03*
Y1514922D03*
X1712165Y1503898D03*
Y1519252D03*
X1720826Y1555867D03*
Y1571221D03*
X1712165Y1575552D03*
X1720826Y1586575D03*
X1712165Y1590906D03*
X1720826Y1601930D03*
X1712165Y1606260D03*
X1720826Y1617284D03*
X1712165Y1621615D03*
X1729488Y1457835D03*
Y1473189D03*
Y1488544D03*
Y1503898D03*
Y1519252D03*
Y1560197D03*
Y1575552D03*
Y1590906D03*
Y1606260D03*
Y1621615D03*
G54D25*
X1030635Y764546D03*
G54D35*
G01X881761Y1785438D02*
Y1781510D01*
X881339Y1781088D01*
X866829D01*
X865568Y1779827D01*
Y1772020D01*
X865068Y1771520D01*
X859558D01*
X859058Y1772020D01*
Y1782841D01*
X857797Y1784102D01*
X851209D01*
X849948Y1782841D01*
Y1772020D01*
X849448Y1771520D01*
X843938D01*
X843438Y1772020D01*
Y1782841D01*
X842177Y1784102D01*
X835589D01*
X834328Y1782841D01*
Y1772020D01*
X833828Y1771520D01*
X828318D01*
X827818Y1772020D01*
Y1782841D01*
X826557Y1784102D01*
X819969D01*
X818708Y1782841D01*
Y1772020D01*
X818208Y1771520D01*
X812698D01*
X812198Y1772020D01*
Y1782841D01*
X810937Y1784102D01*
X804349D01*
X803088Y1782841D01*
Y1772020D01*
X802588Y1771520D01*
X797078D01*
X796578Y1772020D01*
Y1782841D01*
X795317Y1784102D01*
X788729D01*
X787468Y1782841D01*
Y1772020D01*
X786968Y1771520D01*
X781458D01*
X780958Y1772020D01*
Y1782841D01*
X779697Y1784102D01*
X773109D01*
X771848Y1782841D01*
Y1772020D01*
X771348Y1771520D01*
X765838D01*
X765338Y1772020D01*
Y1782841D01*
X764077Y1784102D01*
X757489D01*
X756228Y1782841D01*
Y1772020D01*
X755728Y1771520D01*
X750218D01*
X749718Y1772020D01*
Y1782841D01*
X748457Y1784102D01*
X741869D01*
X740608Y1782841D01*
Y1772020D01*
X740108Y1771520D01*
X734598D01*
X734098Y1772020D01*
Y1782841D01*
X732837Y1784102D01*
X726249D01*
X724988Y1782841D01*
Y1772020D01*
X724488Y1771520D01*
X718978D01*
X718478Y1772020D01*
Y1782841D01*
X717217Y1784102D01*
X710629D01*
X709368Y1782841D01*
Y1772020D01*
X708868Y1771520D01*
X703358D01*
X702858Y1772020D01*
Y1782841D01*
X701597Y1784102D01*
X695009D01*
X693748Y1782841D01*
Y1772020D01*
X693248Y1771520D01*
X687738D01*
X687238Y1772020D01*
Y1782841D01*
X685977Y1784102D01*
X679389D01*
X678128Y1782841D01*
Y1772020D01*
X677628Y1771520D01*
X672118D01*
X671618Y1772020D01*
Y1782841D01*
X670357Y1784102D01*
X663769D01*
X662508Y1782841D01*
Y1772020D01*
X662008Y1771520D01*
X656498D01*
X655998Y1772020D01*
Y1782703D01*
X654737Y1783964D01*
X648149D01*
X646888Y1782703D01*
Y1772020D01*
X646388Y1771520D01*
X640878D01*
X640378Y1772020D01*
Y1779827D01*
X639117Y1781088D01*
X630211D01*
X629711Y1781588D01*
Y1785438D01*
G01X881761Y1775438D02*
Y1779274D01*
X881247Y1779788D01*
X867368D01*
X866868Y1779288D01*
Y1771481D01*
X865607Y1770220D01*
X859019D01*
X857758Y1771481D01*
Y1782302D01*
X857258Y1782802D01*
X851748D01*
X851248Y1782302D01*
Y1771481D01*
X849987Y1770220D01*
X843399D01*
X842138Y1771481D01*
Y1782302D01*
X841638Y1782802D01*
X836128D01*
X835628Y1782302D01*
Y1771481D01*
X834367Y1770220D01*
X827779D01*
X826518Y1771481D01*
Y1782302D01*
X826018Y1782802D01*
X820508D01*
X820008Y1782302D01*
Y1771481D01*
X818747Y1770220D01*
X812159D01*
X810898Y1771481D01*
Y1782302D01*
X810398Y1782802D01*
X804888D01*
X804388Y1782302D01*
Y1771481D01*
X803127Y1770220D01*
X796539D01*
X795278Y1771481D01*
Y1782302D01*
X794778Y1782802D01*
X789268D01*
X788768Y1782302D01*
Y1771481D01*
X787507Y1770220D01*
X780919D01*
X779658Y1771481D01*
Y1782302D01*
X779158Y1782802D01*
X773648D01*
X773148Y1782302D01*
Y1771481D01*
X771887Y1770220D01*
X765299D01*
X764038Y1771481D01*
Y1782302D01*
X763538Y1782802D01*
X758028D01*
X757528Y1782302D01*
Y1771481D01*
X756267Y1770220D01*
X749679D01*
X748418Y1771481D01*
Y1782302D01*
X747918Y1782802D01*
X742408D01*
X741908Y1782302D01*
Y1771481D01*
X740647Y1770220D01*
X734059D01*
X732798Y1771481D01*
Y1782302D01*
X732298Y1782802D01*
X726788D01*
X726288Y1782302D01*
Y1771481D01*
X725027Y1770220D01*
X718439D01*
X717178Y1771481D01*
Y1782302D01*
X716678Y1782802D01*
X711168D01*
X710668Y1782302D01*
Y1771481D01*
X709407Y1770220D01*
X702819D01*
X701558Y1771481D01*
Y1782302D01*
X701058Y1782802D01*
X695548D01*
X695048Y1782302D01*
Y1771481D01*
X693787Y1770220D01*
X687199D01*
X685938Y1771481D01*
Y1782302D01*
X685438Y1782802D01*
X679928D01*
X679428Y1782302D01*
Y1771481D01*
X678167Y1770220D01*
X671579D01*
X670318Y1771481D01*
Y1782302D01*
X669818Y1782802D01*
X664308D01*
X663808Y1782302D01*
Y1771481D01*
X662547Y1770220D01*
X655959D01*
X654698Y1771481D01*
Y1782164D01*
X654198Y1782664D01*
X648688D01*
X648188Y1782164D01*
Y1771481D01*
X646927Y1770220D01*
X640339D01*
X639078Y1771481D01*
Y1779288D01*
X638578Y1779788D01*
X630211D01*
X629711Y1779288D01*
Y1775438D01*
G54D26*
X1734069Y1739208D03*
Y1749208D03*
G54D17*
X145078Y1228543D03*
X148818D03*
Y1239763D03*
X145078D03*
X163779Y1187401D03*
Y1194881D03*
Y1202362D03*
Y1209842D03*
Y1217322D03*
X160039Y1236023D03*
X163779Y1224803D03*
X156299D03*
Y1228543D03*
X163779D03*
X160039Y1232283D03*
X152559Y1236023D03*
Y1232283D03*
X174999Y1075196D03*
X182480D03*
X174999Y1078936D03*
X182480D03*
X178740Y1082677D03*
Y1086417D03*
X167519Y1187401D03*
X174999Y1198621D03*
Y1191141D03*
X167519Y1194881D03*
X171259Y1198621D03*
Y1191141D03*
X167519Y1202362D03*
Y1209842D03*
X171259Y1213582D03*
Y1206102D03*
X174999D03*
X167519Y1217322D03*
X174999Y1213582D03*
X178740Y1232283D03*
Y1236023D03*
X174999Y1228543D03*
Y1224803D03*
X182480Y1228543D03*
Y1224803D03*
X167519Y1232283D03*
Y1236023D03*
X182480Y1239763D03*
Y1243503D03*
Y1247243D03*
X171259Y1250984D03*
X178740D03*
Y1239763D03*
X174999Y1243503D03*
Y1247243D03*
X178740Y1254724D03*
X171259D03*
X174999Y1239763D03*
X171259D03*
X175000Y1258465D03*
X182480D03*
X189960Y1075196D03*
X197440D03*
X186220Y1082677D03*
Y1086417D03*
X189960Y1078936D03*
X193700Y1086417D03*
Y1082677D03*
X197440Y1078936D03*
X191830Y1144389D03*
Y1151869D03*
X195570Y1148129D03*
Y1155610D03*
X188090D03*
X191830Y1159350D03*
Y1170570D03*
X195570Y1166830D03*
X188090D03*
X191830Y1185531D03*
Y1178051D03*
X195570Y1181791D03*
Y1174310D03*
X188090D03*
X197440Y1224803D03*
X193700Y1232283D03*
X189960Y1228543D03*
X186220Y1232283D03*
X189960Y1224803D03*
X193700Y1236023D03*
X186220D03*
X197440Y1228543D03*
Y1239763D03*
Y1247243D03*
Y1243503D03*
X193700Y1254724D03*
X186220D03*
X193700Y1239763D03*
X186220D03*
X189960D03*
X186220Y1250984D03*
X189960Y1247243D03*
X193700Y1250984D03*
X189960Y1243503D03*
Y1258465D03*
X197441D03*
X204921Y1075196D03*
X212401D03*
Y1078936D03*
X208661Y1082677D03*
X201181D03*
Y1086417D03*
X208661D03*
X204921Y1078936D03*
X210531Y1155610D03*
X203051D03*
X214271Y1170570D03*
X210531Y1166830D03*
X214271Y1159350D03*
X206791Y1170570D03*
X203051Y1166830D03*
X199311Y1170570D03*
X206791Y1159350D03*
X199311D03*
X203051Y1174310D03*
X210531D03*
X212401Y1228543D03*
Y1224803D03*
X208661Y1232283D03*
X204921Y1228543D03*
X201181Y1232283D03*
X204921Y1224803D03*
X201181Y1236023D03*
X208661D03*
Y1250984D03*
X201181Y1239763D03*
X212401D03*
Y1247243D03*
Y1243503D03*
X201181Y1254724D03*
X208661Y1239763D03*
X204921D03*
Y1243503D03*
X201181Y1250984D03*
X204921Y1247243D03*
X208661Y1254724D03*
X212401Y1258465D03*
X204921D03*
X204152Y1408495D03*
X213969Y1445013D03*
Y1453293D03*
Y1456013D03*
Y1464293D03*
X227362Y1075196D03*
X219881D03*
Y1078936D03*
X216141Y1086417D03*
X231102Y1082677D03*
Y1086417D03*
X223622Y1082677D03*
X227362Y1078936D03*
X216141Y1082677D03*
X223622Y1086417D03*
X218011Y1155610D03*
X225492D03*
Y1166830D03*
X221751Y1170570D03*
X218011Y1166830D03*
X221751Y1159350D03*
X229232Y1170570D03*
Y1159350D03*
X225492Y1174310D03*
X218011D03*
X231102Y1228543D03*
Y1224803D03*
X219881Y1228543D03*
Y1224803D03*
X216141Y1232283D03*
Y1236023D03*
X219881Y1239763D03*
Y1247243D03*
Y1243503D03*
X216141Y1250984D03*
Y1254724D03*
Y1239763D03*
X219882Y1258465D03*
X227249Y1445013D03*
Y1464293D03*
Y1456013D03*
Y1453293D03*
X236712Y1155610D03*
X244192D03*
X236712Y1166830D03*
X240452Y1170570D03*
Y1159350D03*
X244192Y1166830D03*
X236712Y1174310D03*
X244192D03*
X238582Y1224803D03*
Y1228543D03*
X242322Y1236023D03*
Y1232283D03*
X246062Y1228543D03*
X234842Y1232283D03*
X246062Y1224803D03*
X234842Y1236023D03*
X251673Y1155610D03*
X259153D03*
X251673Y1166830D03*
X255413Y1170570D03*
X247933D03*
X255413Y1159350D03*
X247933D03*
X259153Y1166830D03*
X251673Y1174310D03*
X259153D03*
X261023Y1224803D03*
X253543Y1228543D03*
X249803Y1232283D03*
X257283D03*
Y1236023D03*
X261023Y1228543D03*
X253543Y1224803D03*
X249803Y1236023D03*
X266633Y1155610D03*
Y1174310D03*
X264763Y1232283D03*
X268503Y1224803D03*
X275984D03*
X272244Y1236023D03*
X279724Y1232283D03*
Y1236023D03*
X275984Y1228543D03*
X272244Y1232283D03*
X268503Y1228543D03*
X264763Y1236023D03*
X287204Y1232283D03*
X283464Y1224803D03*
Y1228543D03*
X287204Y1236023D03*
X600295Y1084547D03*
Y1092027D03*
X604035Y1077066D03*
Y1080806D03*
Y1084547D03*
Y1092027D03*
Y1103247D03*
X600295D03*
Y1095767D03*
X604035D03*
X600295Y1110728D03*
Y1118208D03*
X604035Y1110728D03*
Y1118208D03*
X600295Y1125688D03*
X604035D03*
X607776Y1106988D03*
X615256Y1114468D03*
X611516D03*
X607776D03*
X615256Y1118208D03*
Y1121948D03*
X611516D03*
X607776D03*
X615256Y1125688D03*
Y1129429D03*
X611516D03*
X607776D03*
X618996Y1125688D03*
Y1129429D03*
X632086Y1075196D03*
Y1078936D03*
X635827Y1086417D03*
Y1082677D03*
X630216Y1129428D03*
X626476D03*
X622736Y1129429D03*
X639567Y1075196D03*
X647047D03*
X643307Y1086417D03*
Y1082677D03*
X647047Y1078936D03*
X639567D03*
X650787Y1082677D03*
Y1086417D03*
X648917Y1136909D03*
X652657Y1148129D03*
Y1155610D03*
X648917Y1144389D03*
Y1151869D03*
Y1159350D03*
Y1170570D03*
X652657Y1166830D03*
X648917Y1185531D03*
Y1178051D03*
X652657Y1181791D03*
Y1174310D03*
X662008Y1075196D03*
X654527D03*
X669488D03*
X662008Y1078936D03*
X665748Y1082677D03*
X658268D03*
X654527Y1078936D03*
X665748Y1086417D03*
X658268D03*
X669488Y1078936D03*
X667618Y1129429D03*
X660138D03*
X656398D03*
X663878D03*
X660138Y1155610D03*
X667618D03*
X663878Y1170570D03*
X660138Y1166830D03*
X656398Y1170570D03*
X663878Y1159350D03*
X656398D03*
X667618Y1166830D03*
Y1174310D03*
X660138D03*
X667618Y1200491D03*
X656398D03*
X663878D03*
X660138D03*
X669488Y1232283D03*
X662008D03*
X665748Y1224803D03*
X662008Y1236023D03*
X658268Y1224803D03*
X665748Y1228543D03*
X658268D03*
X669488Y1236023D03*
X676968Y1075196D03*
X684449D03*
X676968Y1078936D03*
X680709Y1086417D03*
X684449Y1078936D03*
X673228Y1086417D03*
Y1082677D03*
X680709D03*
X675098Y1129429D03*
X671358D03*
X678838D03*
X682579D03*
Y1155610D03*
X675098D03*
X682579Y1166830D03*
X678838Y1170570D03*
X671358D03*
X675098Y1166830D03*
X671358Y1159350D03*
X678838D03*
X682579Y1174310D03*
X675098D03*
Y1200491D03*
X671358D03*
X678838D03*
X682579D03*
X676968Y1236023D03*
X684449Y1232283D03*
X673228Y1228543D03*
X680709Y1224803D03*
X684449Y1236023D03*
X676968Y1232283D03*
X673228Y1224803D03*
X680709Y1228543D03*
X688189Y1086417D03*
Y1082677D03*
X701279Y1129429D03*
X697539D03*
X693799D03*
X686319D03*
X701279Y1155610D03*
X693799D03*
Y1166830D03*
X697539Y1170570D03*
Y1159350D03*
X701279Y1166830D03*
X686319Y1170570D03*
Y1159350D03*
X701279Y1174310D03*
X693799D03*
X701279Y1200491D03*
X697539D03*
X693799D03*
X686319D03*
X688189Y1228543D03*
X691929Y1236023D03*
X699409Y1232283D03*
X688189Y1224803D03*
X699409Y1236023D03*
X691929Y1232283D03*
X695669Y1228543D03*
Y1224803D03*
X705020Y1129429D03*
X708760D03*
X712500D03*
X716240D03*
X708760Y1155610D03*
X716240D03*
Y1166830D03*
X705020Y1159350D03*
X712500D03*
X705020Y1170570D03*
X712500D03*
X708760Y1166830D03*
X716240Y1174310D03*
X708760D03*
X712500Y1200491D03*
X705020D03*
X708760D03*
X716240D03*
X706890Y1236023D03*
X714370D03*
X710630Y1228543D03*
X703149D03*
X714370Y1232283D03*
X703149Y1224803D03*
X710630D03*
X706890Y1232283D03*
X719980Y1129429D03*
X723720D03*
Y1155610D03*
Y1174310D03*
X719980Y1200491D03*
X723720D03*
X742421Y1155610D03*
Y1159350D03*
Y1166830D03*
Y1170570D03*
Y1174310D03*
X748031Y1224803D03*
Y1228543D03*
X762992Y1202362D03*
X755512Y1198621D03*
X759252Y1202362D03*
X751772Y1198621D03*
X762992Y1217322D03*
X751772Y1213582D03*
X762992Y1209842D03*
X755512Y1213582D03*
X751772Y1206102D03*
X759252Y1217322D03*
Y1209842D03*
X755512Y1206102D03*
Y1228543D03*
X751772Y1236023D03*
X762992Y1228543D03*
X751772Y1232283D03*
X766732D03*
Y1236023D03*
X759252Y1232283D03*
X762992Y1224803D03*
X759252Y1236023D03*
X755512Y1224803D03*
X770472Y1228543D03*
X781693D03*
X770472Y1224803D03*
X777953Y1228543D03*
X774212Y1232283D03*
Y1236023D03*
X777953Y1239763D03*
X781693D03*
X1059251Y1228543D03*
Y1239763D03*
X1070472Y1228543D03*
X1066732Y1236023D03*
Y1232283D03*
X1074212Y1236023D03*
Y1232283D03*
X1070472Y1224803D03*
X1062991Y1228543D03*
Y1239763D03*
X1089172Y1075196D03*
Y1078936D03*
X1077952Y1187401D03*
X1081692D03*
X1077952Y1194881D03*
Y1202362D03*
X1089172Y1191141D03*
Y1198621D03*
X1081692Y1202362D03*
X1085432Y1198621D03*
X1081692Y1194881D03*
X1085432Y1191141D03*
X1089172Y1206102D03*
X1077952Y1209842D03*
X1081692D03*
Y1217322D03*
X1089172Y1213582D03*
X1077952Y1217322D03*
X1085432Y1206102D03*
Y1213582D03*
X1081692Y1232283D03*
Y1236023D03*
X1077952Y1224803D03*
Y1228543D03*
X1096653Y1075196D03*
X1104133D03*
X1100393Y1082677D03*
X1104133Y1078936D03*
X1107873Y1082677D03*
Y1086417D03*
X1092913Y1082677D03*
X1100393Y1086417D03*
X1092913D03*
X1096653Y1078936D03*
X1106003Y1151869D03*
Y1144389D03*
X1102263Y1155610D03*
X1106003Y1170570D03*
Y1159350D03*
X1102263Y1166830D03*
X1106003Y1178051D03*
Y1185531D03*
X1102263Y1174310D03*
X1111613Y1075196D03*
X1119094D03*
X1122834Y1086417D03*
X1119094Y1078936D03*
X1115354Y1082677D03*
X1111613Y1078936D03*
X1115354Y1086417D03*
X1122834Y1082677D03*
X1124704Y1155610D03*
X1109743D03*
Y1148129D03*
X1117224Y1155610D03*
X1113484Y1159350D03*
X1120964D03*
X1109743Y1166830D03*
X1113484Y1170570D03*
X1117224Y1166830D03*
X1120964Y1170570D03*
X1124704Y1166830D03*
X1109743Y1174310D03*
Y1181791D03*
X1117224Y1174310D03*
X1124704D03*
X1126574Y1075196D03*
X1134054D03*
Y1078936D03*
X1126574D03*
X1130314Y1086417D03*
Y1082677D03*
X1137795Y1086417D03*
Y1082677D03*
X1139665Y1155610D03*
X1132184D03*
X1139665Y1166830D03*
X1135924Y1170570D03*
X1128444D03*
X1132184Y1166830D03*
X1128444Y1159350D03*
X1135924D03*
X1139665Y1174310D03*
X1132184D03*
X1141535Y1075196D03*
X1145275Y1086417D03*
Y1082677D03*
X1141535Y1078936D03*
X1150885Y1155610D03*
X1143405Y1170570D03*
X1154625Y1159350D03*
X1143405D03*
X1150885Y1166830D03*
X1154625Y1170570D03*
X1150885Y1174310D03*
X1149015Y1236023D03*
Y1232283D03*
X1152755Y1228543D03*
X1145275Y1224803D03*
X1156495Y1232283D03*
Y1236023D03*
X1145275Y1228543D03*
X1152755Y1224803D03*
X1173326Y1155610D03*
X1165846D03*
X1158365D03*
X1173326Y1166830D03*
X1165846D03*
X1169586Y1170570D03*
X1158365Y1166830D03*
X1162106Y1170570D03*
X1169586Y1159350D03*
X1162106D03*
X1165846Y1174310D03*
X1158365D03*
X1173326D03*
X1160235Y1224803D03*
X1163976Y1232283D03*
X1167716Y1224803D03*
X1160235Y1228543D03*
X1171456Y1232283D03*
X1163976Y1236023D03*
X1171456D03*
X1167716Y1228543D03*
X1180806Y1155610D03*
Y1174310D03*
X1182676Y1228543D03*
X1186417Y1236023D03*
X1178936D03*
X1186417Y1232283D03*
X1175196Y1228543D03*
X1178936Y1232283D03*
X1182676Y1224803D03*
X1175196D03*
X1197637D03*
X1193897Y1236023D03*
X1190157Y1228543D03*
X1201377Y1236023D03*
X1190157Y1224803D03*
X1193897Y1232283D03*
X1197637Y1228543D03*
X1201377Y1232283D03*
X1514468Y1084547D03*
Y1092027D03*
Y1095767D03*
Y1103247D03*
Y1110728D03*
Y1118208D03*
Y1125688D03*
X1525689Y1073326D03*
X1521948Y1077066D03*
X1525689D03*
X1518208D03*
Y1080806D03*
X1529429Y1080807D03*
X1521949D03*
X1529429Y1084547D03*
X1521949D03*
X1518208D03*
X1529429Y1088287D03*
X1525689D03*
X1521949D03*
X1525689Y1092027D03*
X1518208D03*
X1521949Y1103247D03*
X1518208D03*
X1529429Y1106988D03*
X1525689D03*
X1521949D03*
X1525689Y1095767D03*
X1518208D03*
X1529429Y1099507D03*
X1521949D03*
X1529429Y1103247D03*
Y1110728D03*
X1518208D03*
X1529429Y1114468D03*
X1525689D03*
X1521949D03*
X1529429Y1118208D03*
X1518208D03*
X1529429Y1121948D03*
X1525689D03*
X1521949D03*
X1529429Y1125688D03*
X1518208D03*
X1529429Y1129429D03*
X1525689D03*
X1521949D03*
X1527559Y1254724D03*
X1520078D03*
X1523819Y1258465D03*
X1533169Y1073326D03*
X1546259Y1075196D03*
X1540649Y1088287D03*
X1533169Y1077066D03*
X1536909Y1080807D03*
Y1084547D03*
Y1088287D03*
X1533169D03*
Y1092027D03*
X1540649D03*
X1546259Y1090157D03*
Y1078936D03*
X1544389Y1099507D03*
X1533169Y1095767D03*
X1536909Y1099507D03*
Y1103247D03*
X1540649Y1106988D03*
X1536909D03*
X1533169D03*
X1544389D03*
X1540649Y1095767D03*
Y1099507D03*
X1546259Y1101377D03*
Y1105117D03*
X1544389Y1118208D03*
X1540649D03*
Y1121948D03*
X1544389Y1110728D03*
X1540649D03*
X1536909Y1114468D03*
X1533169D03*
Y1125688D03*
X1544389Y1129428D03*
X1540649D03*
X1536909Y1129429D03*
X1533169D03*
X1535039Y1254724D03*
X1542519D03*
X1546260Y1258465D03*
X1538779D03*
X1531299D03*
X1553740Y1075196D03*
X1561220D03*
X1553740Y1090157D03*
X1557480Y1082677D03*
X1553740Y1078936D03*
X1561220D03*
X1550000Y1086417D03*
Y1082677D03*
X1557480Y1086417D03*
X1553740Y1105117D03*
X1557480Y1097637D03*
Y1093897D03*
X1553740Y1101377D03*
X1550000Y1093897D03*
Y1097637D03*
X1551870Y1114468D03*
X1548130D03*
X1559350Y1118208D03*
X1555610D03*
X1551870D03*
X1548130D03*
X1559350Y1121948D03*
X1555610D03*
X1551870D03*
X1548130D03*
Y1110728D03*
X1557480Y1108858D03*
X1553740D03*
X1550000D03*
X1551870Y1110728D03*
X1559350Y1125688D03*
X1555610D03*
X1551870D03*
X1548130D03*
X1559350Y1129429D03*
X1555610D03*
X1551870D03*
X1548130D03*
X1563090Y1144389D03*
Y1151869D03*
Y1159350D03*
Y1170570D03*
Y1185531D03*
Y1178051D03*
X1550000Y1254724D03*
X1557480D03*
X1561220Y1258465D03*
X1553740D03*
X1576181Y1075196D03*
X1568700D03*
Y1078936D03*
X1572441Y1086417D03*
X1564960Y1082677D03*
Y1086417D03*
X1572441Y1082677D03*
X1576181Y1078936D03*
X1574311Y1155610D03*
X1566830Y1148129D03*
Y1155610D03*
X1578051Y1170570D03*
X1574311Y1166830D03*
X1570571Y1170570D03*
X1566830Y1166830D03*
X1578051Y1159350D03*
X1570571D03*
X1574311Y1174310D03*
X1566830Y1181791D03*
Y1174310D03*
X1572441Y1228543D03*
X1576181Y1236023D03*
X1572441Y1224803D03*
X1576181Y1232283D03*
X1564960Y1254724D03*
X1583661Y1075196D03*
X1591141D03*
X1594882Y1082677D03*
X1579921D03*
X1583661Y1078936D03*
X1594882Y1086417D03*
X1587401Y1082677D03*
X1579921Y1086417D03*
X1587401D03*
X1591141Y1078936D03*
X1581791Y1155610D03*
X1589271D03*
X1593011Y1170570D03*
X1585531D03*
X1589271Y1166830D03*
X1581791D03*
X1585531Y1159350D03*
X1593011D03*
X1589271Y1174310D03*
X1581791D03*
X1594882Y1224803D03*
X1591141Y1232283D03*
X1583661Y1236023D03*
X1579921Y1228543D03*
X1583661Y1232283D03*
X1594882Y1228543D03*
X1579921Y1224803D03*
X1587401Y1228543D03*
Y1224803D03*
X1591141Y1236023D03*
X1598622Y1075196D03*
X1602362Y1082677D03*
Y1086417D03*
X1598622Y1078936D03*
X1596752Y1155610D03*
X1607972D03*
Y1166830D03*
X1611712Y1170570D03*
X1600492D03*
X1596752Y1166830D03*
X1611712Y1159350D03*
X1600492D03*
X1607972Y1174310D03*
X1596752D03*
X1598622Y1236023D03*
X1606102D03*
X1609842Y1228543D03*
X1606102Y1232283D03*
X1602362Y1224803D03*
X1609842D03*
X1602362Y1228543D03*
X1598622Y1232283D03*
X1622933Y1155610D03*
X1615452D03*
Y1166830D03*
X1619193Y1170570D03*
X1626673Y1159350D03*
X1619193D03*
X1622933Y1166830D03*
X1626673Y1170570D03*
X1622933Y1174310D03*
X1615452D03*
X1617322Y1228543D03*
X1624803Y1224803D03*
X1617322D03*
X1621063Y1236023D03*
X1613582D03*
X1621063Y1232283D03*
X1624803Y1228543D03*
X1613582Y1232283D03*
X1637893Y1155610D03*
X1630413D03*
Y1166830D03*
X1637893Y1174310D03*
X1630413D03*
X1628543Y1236023D03*
Y1232283D03*
X1649114Y1155610D03*
Y1159350D03*
Y1170570D03*
Y1166830D03*
Y1174310D03*
X1675295Y1166830D03*
Y1159350D03*
X1673425Y1202362D03*
X1665945Y1198621D03*
X1669685D03*
X1665945Y1206102D03*
X1669685Y1213582D03*
X1673425Y1209842D03*
X1669685Y1206102D03*
X1665945Y1213582D03*
X1673425Y1217322D03*
Y1236023D03*
X1662204Y1228543D03*
X1669685D03*
X1673425Y1232283D03*
X1665945D03*
Y1236023D03*
X1662204Y1224803D03*
X1669685D03*
X1679035Y1166830D03*
X1677165Y1202362D03*
Y1209842D03*
Y1217322D03*
Y1228543D03*
X1680905Y1236023D03*
Y1232283D03*
X1692126Y1228543D03*
X1684645Y1224803D03*
Y1228543D03*
X1677165Y1224803D03*
X1688385Y1232283D03*
Y1236023D03*
X1692126Y1239763D03*
X1695866Y1228543D03*
Y1239763D03*
G54D36*
G01X35688Y111255D02*
X36842Y112409D01*
X36865Y112400D01*
X38598D01*
X42185Y115987D01*
X44800Y119900D01*
X50956Y126056D01*
X60360Y148378D01*
X60263Y154210D01*
X51814Y194565D01*
X51328Y225685D01*
X52389Y236456D01*
Y243508D01*
X51645Y335329D01*
X92428Y469880D01*
X105377Y568321D01*
X175123Y937151D01*
X181456Y1006330D01*
X181153Y1037243D01*
X184904Y1061030D01*
Y1068476D01*
G01X35688Y114655D02*
X36654Y113689D01*
X37086Y113510D01*
X38138D01*
X41323Y116695D01*
X43938Y120608D01*
X50017Y126687D01*
X50989Y128996D01*
X50776Y129520D01*
X51534Y131318D01*
X52058Y131531D01*
X52815Y133328D01*
X52601Y133851D01*
X53359Y135649D01*
X53883Y135863D01*
X59246Y148593D01*
X59154Y154086D01*
X50705Y194441D01*
X50217Y225731D01*
X51279Y236511D01*
Y243503D01*
X50533Y335489D01*
X91339Y470115D01*
X104280Y568497D01*
X174022Y937305D01*
X180345Y1006375D01*
X180042Y1037325D01*
X183794Y1061117D01*
Y1068476D01*
G01X180055Y1068288D02*
Y1064194D01*
X176266Y1037485D01*
X176569Y1006529D01*
X170280Y937829D01*
X100552Y569094D01*
X87638Y470914D01*
X67235Y403601D01*
X67234Y403598D01*
X67187Y403443D01*
Y403441D01*
X46754Y336033D01*
X47506Y242080D01*
Y236798D01*
X46452Y225881D01*
X46913Y196397D01*
X41802Y158572D01*
X41657Y149371D01*
X43725Y137723D01*
X43817Y126334D01*
X42064Y124581D01*
X41499D01*
X40119Y123201D01*
Y122636D01*
X38080Y120597D01*
X36130D01*
X35730Y120997D01*
X33780D01*
X33380Y120597D01*
X29533D01*
X28388Y121742D01*
G01X35688Y125428D02*
X36833Y126573D01*
X39095D01*
X41120Y128597D01*
X40974Y137985D01*
X38913Y149041D01*
X39056Y158062D01*
X44181Y195993D01*
X43724Y225203D01*
X44827Y237378D01*
Y243299D01*
X44071Y336419D01*
X64493Y403792D01*
X64494Y403795D01*
X64541Y403950D01*
Y403952D01*
X85010Y471481D01*
X97905Y569518D01*
X167623Y938201D01*
X173888Y1006638D01*
X173585Y1037473D01*
X177424Y1064505D01*
Y1068476D01*
G01X173684Y1068288D02*
Y1064854D01*
X172905Y1058363D01*
X171451Y1051286D01*
X169824Y1037711D01*
Y1032787D01*
X170083Y1006345D01*
X163891Y938717D01*
X94074Y569505D01*
X81263Y472104D01*
X60774Y404508D01*
X60773Y404506D01*
X40283Y336907D01*
X41029Y246490D01*
Y237178D01*
X39960Y225367D01*
X40415Y196278D01*
X35290Y158350D01*
X34993Y139194D01*
Y137740D01*
X30913Y133660D01*
X29533D01*
X28388Y132515D01*
G01X181165Y1068288D02*
Y1064115D01*
X177377Y1037412D01*
X177680Y1006484D01*
X171381Y937675D01*
X101649Y568918D01*
X88727Y470679D01*
X68297Y403278D01*
Y403276D01*
X68250Y403121D01*
X68249Y403118D01*
X47866Y335873D01*
X48616Y242085D01*
Y236744D01*
X47563Y225836D01*
X48025Y196331D01*
X42911Y158489D01*
X42769Y149460D01*
X44835Y137825D01*
X44931Y125878D01*
X38540Y119487D01*
X29533D01*
X28388Y118342D01*
G01X35688Y128828D02*
X36833Y127683D01*
X38635D01*
X40002Y129050D01*
X39950Y132427D01*
X39543Y132820D01*
X39513Y134771D01*
X39906Y135177D01*
X39865Y137874D01*
X39460Y140049D01*
X38992Y140369D01*
X38635Y142287D01*
X38955Y142754D01*
X37801Y148947D01*
X37947Y158145D01*
X43069Y196059D01*
X42613Y225245D01*
X43717Y237429D01*
Y243294D01*
X42959Y336579D01*
X63431Y404115D01*
Y404117D01*
X63478Y404272D01*
X63479Y404275D01*
X83921Y471716D01*
X96808Y569694D01*
X166522Y938355D01*
X168084Y955435D01*
X168085D01*
X172777Y1006683D01*
X172474Y1037546D01*
X176314Y1064584D01*
Y1068476D01*
G01X172574Y1068288D02*
Y1064922D01*
X172573Y1064921D01*
X171808Y1058541D01*
X170354Y1051464D01*
X168714Y1037778D01*
Y1032781D01*
X168972Y1006390D01*
X162790Y938871D01*
X145336Y846572D01*
X145335D01*
X127883Y754275D01*
X127882D01*
X92977Y569681D01*
X80174Y472339D01*
X59711Y404830D01*
X59710Y404827D01*
X39171Y337067D01*
X39919Y246485D01*
Y237229D01*
X38849Y225408D01*
X39303Y196344D01*
X34181Y158433D01*
X34128Y154975D01*
X33721Y154581D01*
X33691Y152631D01*
X34084Y152225D01*
X34054Y150276D01*
X33647Y149882D01*
X33617Y147931D01*
X34011Y147525D01*
X33883Y139203D01*
Y138200D01*
X30453Y134770D01*
X29533D01*
X28388Y135915D01*
G01X76112Y1372385D02*
X77257Y1371240D01*
Y1369193D01*
X71137Y1363073D01*
Y1350874D01*
X66516Y1288231D01*
Y1257781D01*
X69131Y1244633D01*
X72769Y1235850D01*
X85810Y1216332D01*
X98881Y1196769D01*
X103563Y1192927D01*
X122759Y1184976D01*
X143088D01*
G01X79512Y1372385D02*
X78367Y1371240D01*
Y1368733D01*
X72247Y1362613D01*
Y1350833D01*
X68661Y1302194D01*
X69067Y1301723D01*
X68927Y1299827D01*
X68455Y1299420D01*
X68316Y1297526D01*
X68722Y1297055D01*
X68582Y1295159D01*
X68110Y1294752D01*
X67971Y1292858D01*
X68377Y1292387D01*
X68237Y1290491D01*
X67765Y1290084D01*
X67626Y1288190D01*
Y1257891D01*
X70199Y1244957D01*
X73753Y1236376D01*
X99713Y1197523D01*
X104140Y1193890D01*
X122980Y1186086D01*
X143088D01*
G01X91752Y1396583D02*
X90607Y1395438D01*
Y1393473D01*
X96727Y1387353D01*
Y1345914D01*
X91326Y1328107D01*
X91526Y1327733D01*
X90960Y1325866D01*
X90585Y1325666D01*
X83451Y1302145D01*
X83651Y1301771D01*
X83085Y1299904D01*
X82710Y1299704D01*
X82144Y1297838D01*
X82344Y1297464D01*
X81778Y1295597D01*
X81403Y1295397D01*
X80837Y1293531D01*
X81037Y1293157D01*
X80471Y1291290D01*
X80096Y1291090D01*
X75146Y1274772D01*
Y1258770D01*
X77147Y1248709D01*
X80837Y1239802D01*
X101674Y1208616D01*
X102090Y1208534D01*
X103174Y1206911D01*
X103092Y1206495D01*
X105694Y1202600D01*
X108322Y1200443D01*
X124925Y1193566D01*
X140088D01*
G01X88352Y1348187D02*
X89497Y1347042D01*
Y1342074D01*
X70276Y1278726D01*
Y1258163D01*
X72641Y1246267D01*
X76221Y1237623D01*
X88948Y1218576D01*
X101704Y1199486D01*
X105851Y1196083D01*
X123637Y1188716D01*
X140288D01*
G01X88352Y1396583D02*
X89497Y1395438D01*
Y1393013D01*
X95617Y1386893D01*
Y1346079D01*
X74036Y1274937D01*
Y1258660D01*
X76079Y1248385D01*
X79853Y1239276D01*
X92343Y1220583D01*
X104862Y1201846D01*
X107745Y1199480D01*
X124704Y1192456D01*
X140088D01*
G01X91752Y1348187D02*
X90607Y1347042D01*
Y1341909D01*
X75797Y1293096D01*
X76091Y1292547D01*
X75539Y1290728D01*
X74989Y1290435D01*
X74438Y1288617D01*
X74732Y1288068D01*
X74180Y1286249D01*
X73630Y1285956D01*
X73079Y1284138D01*
X73372Y1283590D01*
X72820Y1281770D01*
X72270Y1281477D01*
X71828Y1280019D01*
X71829D01*
X71386Y1278561D01*
Y1258273D01*
X73709Y1246591D01*
X77205Y1238149D01*
X102536Y1200240D01*
X106428Y1197046D01*
X123858Y1189826D01*
X140288D01*
G01X100592Y1372385D02*
X101737Y1371240D01*
Y1368273D01*
X107857Y1362153D01*
Y1345171D01*
X77796Y1272597D01*
Y1259516D01*
X79717Y1249854D01*
X83395Y1240976D01*
X102609Y1212221D01*
X113257Y1201573D01*
X126238Y1196196D01*
X140388D01*
G01X116232Y1348187D02*
X115087Y1347042D01*
Y1344637D01*
X111101Y1328726D01*
X90138Y1289510D01*
X82666Y1271469D01*
Y1260007D01*
X84309Y1251744D01*
X87896Y1243085D01*
X96772Y1229801D01*
X97301Y1229695D01*
X98423Y1228017D01*
X98318Y1227488D01*
X99373Y1225909D01*
X99984Y1225787D01*
X101040Y1224207D01*
X100919Y1223596D01*
X101974Y1222017D01*
X102585Y1221895D01*
X103641Y1220315D01*
X103520Y1219704D01*
X104349Y1218463D01*
Y1218462D01*
X105177Y1217222D01*
X116848Y1205552D01*
X127725Y1201047D01*
X140388D01*
G01X103992Y1372385D02*
X102847Y1371240D01*
Y1368733D01*
X108967Y1362613D01*
Y1344950D01*
X78906Y1272376D01*
Y1259626D01*
X80785Y1250178D01*
X84379Y1241502D01*
X103471Y1212929D01*
X104527Y1211873D01*
X105149D01*
X106494Y1210528D01*
Y1209906D01*
X107837Y1208563D01*
X108459D01*
X109804Y1207218D01*
Y1206596D01*
X111147Y1205253D01*
X111769D01*
X113114Y1203908D01*
Y1203286D01*
X113886Y1202514D01*
X126459Y1197306D01*
X140388D01*
G01X112832Y1348187D02*
X113977Y1347042D01*
Y1344775D01*
X113976Y1344774D01*
X110057Y1329129D01*
X89133Y1289985D01*
X81556Y1271690D01*
Y1259897D01*
X83241Y1251420D01*
X86912Y1242559D01*
X104315Y1216514D01*
X116219Y1204611D01*
X127504Y1199937D01*
X140388D01*
G01X118543Y1585788D02*
Y1584284D01*
X119043Y1583784D01*
X121927D01*
X123167Y1582544D01*
Y1553967D01*
X115214Y1546014D01*
X98417Y1539056D01*
X88758Y1529397D01*
X82803Y1516163D01*
X79500Y1461327D01*
X81907Y1412346D01*
X84487Y1386144D01*
Y1370193D01*
X90607Y1364073D01*
Y1361244D01*
X91752Y1360099D01*
G01X118543Y1580670D02*
Y1582174D01*
X119043Y1582674D01*
X121467D01*
X122057Y1582084D01*
Y1554427D01*
X114585Y1546955D01*
X97788Y1539997D01*
X87829Y1530038D01*
X81707Y1516433D01*
X78388Y1461333D01*
X80799Y1412264D01*
X83377Y1386089D01*
Y1369733D01*
X89497Y1363613D01*
Y1361244D01*
X88352Y1360099D01*
G01X109882Y1576339D02*
Y1577843D01*
X110382Y1578343D01*
X111786D01*
X113395Y1576734D01*
Y1551665D01*
X111771Y1550041D01*
X95966Y1543494D01*
X84681Y1532209D01*
X77900Y1517140D01*
X74240Y1456422D01*
X77257Y1395029D01*
Y1385442D01*
X76112Y1384297D01*
G01X109882Y1581457D02*
Y1579953D01*
X110382Y1579453D01*
X112246D01*
X114505Y1577194D01*
Y1551205D01*
X112400Y1549100D01*
X96595Y1542553D01*
X85610Y1531568D01*
X78996Y1516870D01*
X75352Y1456416D01*
X78367Y1395057D01*
Y1385442D01*
X79512Y1384297D01*
G01X88352Y1408495D02*
X89497Y1409640D01*
Y1413609D01*
X84902Y1436709D01*
X82286Y1463261D01*
X85436Y1515554D01*
X90976Y1527867D01*
X99589Y1536480D01*
X123013Y1546183D01*
X125613Y1548783D01*
Y1549207D01*
X126993Y1550587D01*
X127417D01*
X130718Y1553888D01*
Y1576734D01*
X129109Y1578343D01*
X127705D01*
X127205Y1577843D01*
Y1576339D01*
G01Y1581457D02*
Y1579953D01*
X127705Y1579453D01*
X129569D01*
X131828Y1577194D01*
Y1553428D01*
X123642Y1545242D01*
X100218Y1535539D01*
X91905Y1527226D01*
X86532Y1515284D01*
X83400Y1463282D01*
X86002Y1436872D01*
X90607Y1413719D01*
Y1409640D01*
X91752Y1408495D01*
G01X116232Y1396583D02*
X115087Y1395438D01*
Y1393473D01*
X121207Y1387353D01*
Y1346916D01*
X117632Y1332645D01*
X112841Y1323682D01*
X112984Y1323208D01*
X112064Y1321487D01*
X111590Y1321344D01*
X110671Y1319625D01*
X110815Y1319151D01*
X109895Y1317430D01*
X109421Y1317287D01*
X108502Y1315568D01*
X108646Y1315094D01*
X107726Y1313373D01*
X107252Y1313230D01*
X93067Y1286693D01*
X86426Y1270660D01*
Y1260382D01*
X87807Y1253439D01*
X91458Y1244626D01*
X104658Y1228542D01*
X112131Y1221069D01*
X112555D01*
X113935Y1219690D01*
Y1219265D01*
X115313Y1217887D01*
X115808D01*
X117187Y1216508D01*
Y1216013D01*
X124728Y1208472D01*
X133624Y1204787D01*
X140088D01*
G01X112832Y1396583D02*
X113977Y1395438D01*
Y1393013D01*
X120097Y1386893D01*
Y1347053D01*
X116588Y1333048D01*
X92062Y1287168D01*
X85316Y1270881D01*
Y1260272D01*
X86739Y1253115D01*
X88607Y1248606D01*
Y1248607D01*
X90495Y1244049D01*
X103834Y1227795D01*
X124099Y1207531D01*
X133403Y1203677D01*
X140088D01*
G01X125072Y1372385D02*
X126217Y1371240D01*
Y1368273D01*
X132337Y1362153D01*
Y1345774D01*
X132336Y1345773D01*
X132337D01*
X127017Y1332933D01*
X95879Y1286332D01*
X89076Y1269908D01*
Y1260647D01*
X90287Y1254557D01*
X93234Y1247443D01*
X95404Y1244196D01*
X129916Y1209684D01*
X135388Y1207417D01*
X140388D01*
G01X140712Y1348187D02*
X139567Y1347042D01*
Y1345650D01*
X139140Y1344025D01*
X137791Y1340717D01*
X132112Y1330691D01*
X123604Y1317957D01*
X123701Y1317472D01*
X122616Y1315849D01*
X122131Y1315753D01*
X121048Y1314132D01*
X121145Y1313647D01*
X120061Y1312024D01*
X119575Y1311928D01*
X118492Y1310307D01*
X118589Y1309822D01*
X117505Y1308199D01*
X117019Y1308103D01*
X109984Y1297572D01*
X110066Y1297156D01*
X108982Y1295534D01*
X108566Y1295451D01*
X107483Y1293830D01*
X107565Y1293414D01*
X106481Y1291792D01*
X106065Y1291709D01*
X104982Y1290088D01*
X105064Y1289672D01*
X103980Y1288050D01*
X103564Y1287967D01*
X102481Y1286346D01*
X102564Y1285930D01*
X101480Y1284307D01*
X101064Y1284225D01*
X99252Y1281513D01*
X93946Y1268703D01*
Y1261132D01*
X94421Y1258747D01*
X94895Y1256363D01*
X96980Y1251330D01*
X99266Y1247906D01*
X105898Y1241273D01*
X106393D01*
X107773Y1239893D01*
Y1239398D01*
X109151Y1238020D01*
X109646D01*
X111026Y1236640D01*
Y1236145D01*
X133654Y1213517D01*
X136671Y1212267D01*
X140388D01*
G01X128472Y1372385D02*
X127327Y1371240D01*
Y1368733D01*
X133447Y1362613D01*
Y1345552D01*
X128001Y1332407D01*
X118580Y1318307D01*
X118676Y1317822D01*
X117592Y1316199D01*
X117107Y1316103D01*
X116024Y1314482D01*
X116121Y1313997D01*
X115036Y1312374D01*
X114551Y1312278D01*
X113468Y1310657D01*
X113565Y1310172D01*
X112480Y1308549D01*
X111995Y1308453D01*
X96863Y1285806D01*
X90186Y1269687D01*
Y1260757D01*
X91355Y1254881D01*
X94218Y1247969D01*
X96266Y1244904D01*
X97609Y1243561D01*
X98231D01*
X99576Y1242216D01*
Y1241594D01*
X100919Y1240251D01*
X101541D01*
X102886Y1238906D01*
Y1238284D01*
X104264Y1236906D01*
X104901D01*
X106281Y1235526D01*
Y1234889D01*
X107659Y1233511D01*
X108296D01*
X109676Y1232131D01*
Y1231494D01*
X130545Y1210625D01*
X135609Y1208527D01*
X140388D01*
G01X140712Y1396583D02*
X139567Y1395438D01*
Y1393473D01*
X145687Y1387353D01*
Y1346692D01*
X140259Y1333588D01*
X107501Y1284563D01*
X107622Y1283952D01*
X106565Y1282372D01*
X105955Y1282250D01*
X104900Y1280671D01*
X105021Y1280061D01*
X103965Y1278480D01*
X103354Y1278359D01*
X100462Y1274030D01*
X97706Y1267375D01*
Y1261509D01*
X98505Y1257494D01*
X99823Y1254312D01*
X101819Y1251325D01*
X107189Y1245955D01*
X107745D01*
X109155Y1244545D01*
Y1243989D01*
X110498Y1242646D01*
X110954D01*
X112465Y1241135D01*
Y1240679D01*
X136827Y1216317D01*
X137575Y1216007D01*
X140488D01*
G01X137312Y1396583D02*
X138457Y1395438D01*
Y1393013D01*
X144577Y1386893D01*
Y1346914D01*
X144576Y1346913D01*
X144577D01*
X142627Y1342204D01*
X142051Y1341966D01*
X141324Y1340210D01*
X141562Y1339635D01*
X139275Y1334114D01*
X138220Y1332535D01*
X137610Y1332413D01*
X136553Y1330833D01*
X136674Y1330222D01*
X99478Y1274556D01*
X96596Y1267596D01*
Y1261399D01*
X97437Y1257170D01*
X98839Y1253786D01*
X100957Y1250617D01*
X136198Y1215376D01*
X137354Y1214897D01*
X140488D01*
G01X137312Y1348187D02*
X138457Y1347042D01*
Y1345794D01*
X138084Y1344378D01*
X136790Y1341202D01*
X131166Y1331274D01*
X98268Y1282039D01*
X92836Y1268924D01*
Y1261022D01*
X93827Y1256039D01*
X94912Y1253420D01*
Y1253421D01*
X95996Y1250804D01*
X98403Y1247198D01*
X133025Y1212576D01*
X136450Y1211157D01*
X140388D01*
G01X135866Y1580670D02*
Y1582174D01*
X136366Y1582674D01*
X138790D01*
X139380Y1582084D01*
Y1553850D01*
X130517Y1544987D01*
X101320Y1532893D01*
X94123Y1525696D01*
X89309Y1514997D01*
X87270Y1481131D01*
Y1459355D01*
X88873Y1443072D01*
X95617Y1409167D01*
Y1393663D01*
X101737Y1387543D01*
Y1385442D01*
X100592Y1384297D01*
G01X135866Y1585788D02*
Y1584284D01*
X136366Y1583784D01*
X139250D01*
X140490Y1582544D01*
Y1553390D01*
X131146Y1544046D01*
X101949Y1531952D01*
X95052Y1525055D01*
X90405Y1514727D01*
X88380Y1481097D01*
Y1459410D01*
X89973Y1443235D01*
X96727Y1409277D01*
Y1394123D01*
X102847Y1388003D01*
Y1385442D01*
X103992Y1384297D01*
G01X144528Y1576339D02*
Y1577843D01*
X145028Y1578343D01*
X146432D01*
X148041Y1576734D01*
Y1552711D01*
X139868Y1544538D01*
X103022Y1529277D01*
X97271Y1523526D01*
X93182Y1514437D01*
X91030Y1478694D01*
Y1460935D01*
X94407Y1443956D01*
X106883Y1413836D01*
X107857Y1408942D01*
Y1369733D01*
X113977Y1363613D01*
Y1361244D01*
X112832Y1360099D01*
G01X144528Y1581457D02*
Y1579953D01*
X145028Y1579453D01*
X146892D01*
X149151Y1577194D01*
Y1552251D01*
X140497Y1543597D01*
X103651Y1528336D01*
X98200Y1522885D01*
X94278Y1514167D01*
X92140Y1478660D01*
Y1461045D01*
X95475Y1444280D01*
X107951Y1414160D01*
X108967Y1409052D01*
Y1370193D01*
X115087Y1364073D01*
Y1361244D01*
X116232Y1360099D01*
G01X112832Y1408495D02*
X113977Y1409640D01*
Y1412127D01*
X102522Y1436346D01*
X97849Y1447041D01*
X97846Y1447052D01*
X97847D01*
X94790Y1462426D01*
Y1477526D01*
X95699Y1492629D01*
X95698D01*
X95727Y1493110D01*
X95728Y1493112D01*
X96966Y1513679D01*
X100420Y1521357D01*
X104994Y1525931D01*
X147564Y1543564D01*
X150763Y1546763D01*
Y1547258D01*
X152142Y1548637D01*
X152637D01*
X156702Y1552702D01*
Y1581729D01*
X155757Y1582674D01*
X153689D01*
X153189Y1582174D01*
Y1580670D01*
G01Y1585788D02*
Y1584284D01*
X153689Y1583784D01*
X156217D01*
X157812Y1582189D01*
Y1552242D01*
X148193Y1542623D01*
X105623Y1524990D01*
X101349Y1520716D01*
X98062Y1513409D01*
X96836Y1493045D01*
Y1493041D01*
X95900Y1477492D01*
Y1462536D01*
X98915Y1447376D01*
X103533Y1436806D01*
X115087Y1412377D01*
Y1409640D01*
X116232Y1408495D01*
G01X161850Y1576339D02*
Y1577843D01*
X162350Y1578343D01*
X163754D01*
X165363Y1576734D01*
Y1553863D01*
X163887Y1552387D01*
X163392D01*
X162013Y1551008D01*
Y1550513D01*
X160635Y1549135D01*
X160140D01*
X158760Y1547755D01*
Y1547260D01*
X157382Y1545882D01*
X156887D01*
X155507Y1544502D01*
Y1544007D01*
X152598Y1541098D01*
X150797Y1540352D01*
X150340Y1540542D01*
X148537Y1539795D01*
X148348Y1539337D01*
X146547Y1538591D01*
X146090Y1538781D01*
X144287Y1538034D01*
X144097Y1537577D01*
X144096D01*
X120063Y1527624D01*
X119072D01*
X107008Y1522627D01*
X103569Y1519188D01*
X100847Y1513138D01*
X98550Y1474955D01*
Y1463588D01*
X101668Y1449701D01*
X119232Y1412567D01*
X120097Y1408718D01*
Y1393663D01*
X126217Y1387543D01*
Y1385442D01*
X125072Y1384297D01*
G01X161850Y1581457D02*
Y1579953D01*
X162350Y1579453D01*
X164214D01*
X166473Y1577194D01*
Y1553403D01*
X153227Y1540157D01*
X120284Y1526514D01*
X119293D01*
X107637Y1521686D01*
X104498Y1518547D01*
X101943Y1512868D01*
X99660Y1474921D01*
Y1463712D01*
X102725Y1450065D01*
X120289Y1412931D01*
X121207Y1408842D01*
Y1394123D01*
X127327Y1388003D01*
Y1385442D01*
X128472Y1384297D01*
G01X109882Y1479095D02*
Y1477591D01*
X110382Y1477091D01*
X112246D01*
X114505Y1474832D01*
Y1450423D01*
X139567Y1412916D01*
Y1409640D01*
X140712Y1408495D01*
G01X137312D02*
X138457Y1409640D01*
Y1412579D01*
X113395Y1450086D01*
Y1474372D01*
X111786Y1475981D01*
X110382D01*
X109882Y1475481D01*
Y1473977D01*
G01X170512Y1580670D02*
Y1582174D01*
X171012Y1582674D01*
X173436D01*
X174025Y1582085D01*
Y1553795D01*
X170702Y1550472D01*
X170207D01*
X168828Y1549093D01*
Y1548598D01*
X167450Y1547220D01*
X166955D01*
X165575Y1545840D01*
Y1545345D01*
X164197Y1543967D01*
X163702D01*
X162322Y1542587D01*
Y1542092D01*
X159750Y1539520D01*
X157949Y1538774D01*
X157492Y1538963D01*
X155689Y1538216D01*
X155500Y1537759D01*
X153699Y1537013D01*
X153242Y1537202D01*
X151439Y1536455D01*
X151250Y1535998D01*
X151249D01*
X121741Y1523772D01*
X119734D01*
X109042Y1519343D01*
X106717Y1517018D01*
X104600Y1512311D01*
X102310Y1474238D01*
Y1466039D01*
X104835Y1453344D01*
X130767Y1414536D01*
X132337Y1409359D01*
Y1369733D01*
X138457Y1363613D01*
Y1361244D01*
X137312Y1360099D01*
G01X170512Y1585788D02*
Y1584284D01*
X171012Y1583784D01*
X173896D01*
X175135Y1582545D01*
Y1553335D01*
X160379Y1538579D01*
X121962Y1522662D01*
X119955D01*
X109671Y1518402D01*
X107646Y1516377D01*
X105696Y1512041D01*
X103420Y1474204D01*
Y1466149D01*
X105881Y1453777D01*
X131782Y1415016D01*
X133447Y1409524D01*
Y1370193D01*
X139567Y1364073D01*
Y1361244D01*
X140712Y1360099D01*
G01X188645Y1068288D02*
Y1054614D01*
X186840Y1036284D01*
Y1034736D01*
X187933Y978234D01*
X154865Y557756D01*
X154998Y545320D01*
X157774Y519629D01*
X158300Y470837D01*
X156577Y413930D01*
X143970Y256891D01*
X142430Y218424D01*
X142799Y194853D01*
X137624Y156555D01*
X137355Y139194D01*
Y137740D01*
X133275Y133660D01*
X131895D01*
X130750Y132515D01*
G01Y121742D02*
X131895Y120597D01*
X135725D01*
X136125Y120997D01*
X138075D01*
X138475Y120597D01*
X140442D01*
X142855Y123010D01*
Y123576D01*
X144235Y124956D01*
X144801D01*
X146179Y126334D01*
X146087Y137723D01*
X144019Y149371D01*
X144125Y156068D01*
X144124D01*
X144126Y156134D01*
X149305Y194466D01*
X148914Y219520D01*
X150332Y254948D01*
X162929Y411885D01*
X164713Y470774D01*
X163508Y582598D01*
X194832Y984171D01*
X194025Y1025990D01*
X193441Y1037889D01*
X195015Y1053871D01*
Y1068288D01*
G01X196125D02*
Y1053816D01*
X194554Y1037862D01*
X195135Y1026028D01*
X195943Y984138D01*
X164619Y582561D01*
X165824Y470763D01*
X164038Y411824D01*
X151441Y254881D01*
X150025Y219506D01*
X150417Y194400D01*
X145235Y156051D01*
X145131Y149460D01*
X147197Y137825D01*
X147293Y125878D01*
X140902Y119487D01*
X131895D01*
X130750Y118342D01*
G01X187535Y1068288D02*
Y1054669D01*
X185730Y1036339D01*
Y1034725D01*
X186822Y978267D01*
X153754Y557794D01*
X153888Y545254D01*
X156664Y519563D01*
X157189Y470848D01*
X155468Y413991D01*
X142861Y256958D01*
X141319Y218438D01*
X141687Y194919D01*
X136515Y156638D01*
X136452Y152570D01*
X136045Y152176D01*
X136015Y150226D01*
X136409Y149820D01*
X136379Y147871D01*
X135972Y147477D01*
X135942Y145526D01*
X136336Y145120D01*
X136245Y139203D01*
Y138200D01*
X132815Y134770D01*
X131895D01*
X130750Y135915D01*
G01X118543Y1478308D02*
Y1479812D01*
X119043Y1480312D01*
X121467D01*
X122057Y1479722D01*
Y1455337D01*
X124377Y1446533D01*
X126763Y1442321D01*
X126593Y1441708D01*
X127555Y1440010D01*
X128169Y1439840D01*
X129130Y1438144D01*
X128960Y1437530D01*
X129922Y1435833D01*
X130535Y1435663D01*
X144577Y1410876D01*
Y1393663D01*
X150697Y1387543D01*
Y1385442D01*
X149552Y1384297D01*
G01X118543Y1483426D02*
Y1481922D01*
X119043Y1481422D01*
X121927D01*
X123167Y1480182D01*
Y1455481D01*
X125414Y1446955D01*
X145687Y1411169D01*
Y1394123D01*
X151807Y1388003D01*
Y1385442D01*
X152952Y1384297D01*
G01X127205Y1473977D02*
Y1475481D01*
X127705Y1475981D01*
X129109D01*
X130718Y1474372D01*
Y1456406D01*
X133395Y1447579D01*
X155144Y1415031D01*
X156817Y1409516D01*
Y1369733D01*
X162937Y1363613D01*
Y1361244D01*
X161792Y1360099D01*
G01X127205Y1479095D02*
Y1477591D01*
X127705Y1477091D01*
X129569D01*
X131828Y1474832D01*
Y1456571D01*
X134410Y1448059D01*
X156159Y1415511D01*
X157927Y1409681D01*
Y1370193D01*
X164047Y1364073D01*
Y1361244D01*
X165192Y1360099D01*
G01X138050Y111255D02*
X139195Y112400D01*
X140960D01*
X152373Y123813D01*
X162722Y148378D01*
X162664Y151877D01*
X154212Y192243D01*
X153821Y217291D01*
X155387Y256423D01*
X167764Y410630D01*
X169586Y470726D01*
X168382Y582435D01*
X199727Y984284D01*
X198600Y1042759D01*
X199865Y1055603D01*
Y1068476D01*
G01X138050Y114655D02*
X139067Y113638D01*
X139376Y113510D01*
X140500D01*
X143322Y116332D01*
Y116898D01*
X144702Y118278D01*
X145268D01*
X146646Y119656D01*
Y120222D01*
X148026Y121602D01*
X148592D01*
X151434Y124444D01*
X161608Y148593D01*
X161555Y151753D01*
X153103Y192119D01*
X152710Y217305D01*
X154278Y256490D01*
X166655Y410691D01*
X168475Y470737D01*
X167271Y582472D01*
X198616Y984317D01*
X197488Y1042803D01*
X198755Y1055658D01*
Y1068476D01*
G01X191274D02*
Y1054259D01*
X189525Y1036508D01*
X190404Y1018601D01*
X191068Y984273D01*
X159745Y582724D01*
X160951Y470811D01*
X159208Y413260D01*
X146633Y256601D01*
X145089Y217997D01*
X145452Y194695D01*
X140281Y156423D01*
X140163Y148947D01*
X141365Y142495D01*
X141045Y142028D01*
X141403Y140110D01*
X141870Y139790D01*
X142227Y137874D01*
X142275Y134774D01*
X141881Y134368D01*
X141911Y132417D01*
X142318Y132023D01*
X142364Y129050D01*
X140997Y127683D01*
X139195D01*
X138050Y128828D01*
G01X192384Y1068476D02*
Y1054204D01*
X190638Y1036481D01*
X191514Y1018639D01*
X192179Y984240D01*
X160856Y582687D01*
X162062Y470800D01*
X160317Y413199D01*
X147742Y256534D01*
X146200Y217983D01*
X146564Y194629D01*
X141390Y156340D01*
X141275Y149041D01*
X143336Y137985D01*
X143482Y128597D01*
X141457Y126573D01*
X139195D01*
X138050Y125428D01*
G01X149552Y1372385D02*
X150697Y1371240D01*
Y1368273D01*
X156817Y1362153D01*
Y1344401D01*
X153006Y1318711D01*
X138988Y1272503D01*
X138482Y1272234D01*
X137911Y1270346D01*
X138180Y1269842D01*
X137629Y1268024D01*
X137238Y1267816D01*
X136613Y1265752D01*
X136821Y1265363D01*
X136270Y1263545D01*
X134100Y1252631D01*
Y1244453D01*
X136182Y1238634D01*
X141158Y1232572D01*
X142479Y1231251D01*
G01X152952Y1372385D02*
X151807Y1371240D01*
Y1368733D01*
X157927Y1362613D01*
Y1344319D01*
X154092Y1318467D01*
X140051Y1272182D01*
X140050Y1272179D01*
X137482Y1263715D01*
X137349Y1263275D01*
X135210Y1252521D01*
Y1244646D01*
X137163Y1239190D01*
X141984Y1233316D01*
X143264Y1232036D01*
G01X165192Y1348187D02*
X164047Y1347042D01*
Y1341686D01*
X162391Y1330524D01*
X145171Y1273760D01*
X145170Y1273757D01*
X140023Y1256791D01*
X139759Y1255921D01*
X139100Y1251478D01*
Y1248435D01*
X140256Y1245644D01*
X142785Y1243115D01*
G01X161792Y1348187D02*
X162937Y1347042D01*
Y1341768D01*
X162659Y1339889D01*
X162158Y1339518D01*
X161879Y1337638D01*
X162250Y1337138D01*
X161305Y1330768D01*
X145466Y1278560D01*
X145468D01*
X144918Y1278267D01*
X144367Y1276447D01*
X144660Y1275899D01*
X144659D01*
X144108Y1274081D01*
X144109D01*
X143559Y1273788D01*
X143008Y1271968D01*
X143301Y1271420D01*
X142750Y1269602D01*
X142200Y1269309D01*
X141649Y1267489D01*
X141942Y1266941D01*
X141391Y1265123D01*
X140841Y1264830D01*
X140290Y1263010D01*
X140583Y1262462D01*
X140032Y1260644D01*
X139482Y1260351D01*
X138931Y1258531D01*
X139224Y1257983D01*
X138673Y1256165D01*
X137990Y1251560D01*
Y1248214D01*
X139315Y1245015D01*
X142000Y1242330D01*
G01X135866Y1483426D02*
Y1481922D01*
X136366Y1481422D01*
X139250D01*
X140490Y1480182D01*
Y1453865D01*
X147987Y1438014D01*
X162558Y1416207D01*
X164047Y1411297D01*
Y1409640D01*
X165192Y1408495D01*
G01X161792D02*
X162937Y1409640D01*
Y1411132D01*
X161543Y1415727D01*
X152633Y1429062D01*
X152147Y1429159D01*
X151063Y1430781D01*
X151160Y1431266D01*
X147018Y1437465D01*
X139380Y1453615D01*
Y1479722D01*
X138790Y1480312D01*
X136366D01*
X135866Y1479812D01*
Y1478308D01*
G01X144528Y1479095D02*
Y1477591D01*
X145028Y1477091D01*
X146892D01*
X149151Y1474832D01*
Y1456349D01*
X151313Y1449224D01*
X170167Y1409359D01*
Y1394123D01*
X176287Y1388003D01*
Y1385442D01*
X177432Y1384297D01*
G01X174032D02*
X175177Y1385442D01*
Y1387543D01*
X169057Y1393663D01*
Y1409109D01*
X157811Y1432888D01*
X157345Y1433055D01*
X156510Y1434819D01*
X156677Y1435285D01*
X155844Y1437047D01*
X155378Y1437214D01*
X154543Y1438978D01*
X154710Y1439444D01*
X153877Y1441206D01*
X153411Y1441373D01*
X152576Y1443137D01*
X152743Y1443603D01*
X150274Y1448823D01*
X148041Y1456184D01*
Y1474372D01*
X146432Y1475981D01*
X145028D01*
X144528Y1475481D01*
Y1473977D01*
G01X189672Y1348187D02*
X188527Y1347042D01*
Y1341100D01*
X179233Y1314083D01*
X159069Y1271452D01*
Y1271453D01*
X158724Y1270725D01*
Y1259412D01*
G01X186272Y1396583D02*
X187417Y1395438D01*
Y1393013D01*
X193537Y1386893D01*
Y1346494D01*
X191237Y1336252D01*
X184861Y1317721D01*
X165974Y1277787D01*
X165389Y1277578D01*
X164575Y1275859D01*
X164785Y1275273D01*
X163973Y1273556D01*
X163387Y1273347D01*
X162574Y1271628D01*
X162784Y1271042D01*
X161334Y1267976D01*
Y1259512D01*
G01X174032Y1372385D02*
X175177Y1371240D01*
Y1368273D01*
X181297Y1362153D01*
Y1355890D01*
X181000Y1355593D01*
Y1353407D01*
X181297Y1353110D01*
Y1347221D01*
X179538Y1338235D01*
X154576Y1276916D01*
X153874Y1273793D01*
Y1259312D01*
G01X198512Y1372385D02*
X199657Y1371240D01*
Y1368273D01*
X205777Y1362153D01*
Y1347616D01*
X203546Y1340263D01*
X184216Y1299392D01*
X165094Y1266574D01*
Y1259512D01*
G01X177432Y1372385D02*
X176287Y1371240D01*
Y1368733D01*
X182407Y1362613D01*
Y1347112D01*
X180607Y1337916D01*
X155639Y1276583D01*
X154984Y1273669D01*
Y1259312D01*
G01X189672Y1396583D02*
X188527Y1395438D01*
Y1393473D01*
X194647Y1387353D01*
Y1346370D01*
X192307Y1335949D01*
X185891Y1317302D01*
X164382Y1271824D01*
X163985Y1270984D01*
Y1270983D01*
X162444Y1267726D01*
Y1259512D01*
G01X186272Y1348187D02*
X187417Y1347042D01*
Y1341286D01*
X178203Y1314502D01*
X159058Y1274026D01*
X158472Y1273816D01*
X157658Y1272098D01*
X157868Y1271512D01*
X157614Y1270975D01*
Y1259412D01*
G01X165192Y1396583D02*
X164047Y1395438D01*
Y1393473D01*
X170167Y1387353D01*
Y1341721D01*
X151244Y1279341D01*
Y1259312D01*
G01X161792Y1396583D02*
X162937Y1395438D01*
Y1393013D01*
X169057Y1386893D01*
Y1341886D01*
X150134Y1279506D01*
Y1259312D01*
G01X153189Y1483426D02*
Y1481922D01*
X153689Y1481422D01*
X156217D01*
X157812Y1479827D01*
Y1455054D01*
X158423Y1452738D01*
X181538Y1411934D01*
X182407Y1409069D01*
Y1370193D01*
X188527Y1364073D01*
Y1361244D01*
X189672Y1360099D01*
G01X153189Y1478308D02*
Y1479812D01*
X153689Y1480312D01*
X155757D01*
X156702Y1479367D01*
Y1454910D01*
X157386Y1452316D01*
X180511Y1411493D01*
X181297Y1408904D01*
Y1369733D01*
X187417Y1363613D01*
Y1361244D01*
X186272Y1360099D01*
G01X161850Y1473977D02*
Y1475481D01*
X162350Y1475981D01*
X163754D01*
X165363Y1474372D01*
Y1456708D01*
X168124Y1446232D01*
X169060Y1444579D01*
X168948Y1444174D01*
X170026Y1442272D01*
X170431Y1442160D01*
X171367Y1440507D01*
X171229Y1440008D01*
X172239Y1438225D01*
X172738Y1438088D01*
X187417Y1412176D01*
Y1409640D01*
X186272Y1408495D01*
G01X161850Y1479095D02*
Y1477591D01*
X162350Y1477091D01*
X164214D01*
X166473Y1474832D01*
Y1456852D01*
X169161Y1446654D01*
X188527Y1412469D01*
Y1409640D01*
X189672Y1408495D01*
G01X201912Y1372385D02*
X200767Y1371240D01*
Y1368733D01*
X206887Y1362613D01*
Y1347451D01*
X204585Y1339862D01*
X185199Y1298874D01*
X166204Y1266274D01*
Y1259512D01*
G01X198512Y1384297D02*
X199657Y1385442D01*
Y1387543D01*
X193537Y1393663D01*
Y1410157D01*
X177491Y1440175D01*
X175162Y1449475D01*
X174628Y1449795D01*
X174166Y1451639D01*
X174486Y1452172D01*
X174025Y1454015D01*
Y1479723D01*
X173436Y1480312D01*
X171012D01*
X170512Y1479812D01*
Y1478308D01*
G01Y1483426D02*
Y1481922D01*
X171012Y1481422D01*
X173896D01*
X175135Y1480183D01*
Y1454152D01*
X178535Y1440578D01*
X194647Y1410436D01*
Y1394123D01*
X200767Y1388003D01*
Y1385442D01*
X201912Y1384297D01*
G01X202496Y1068800D02*
Y1048297D01*
X243696Y268233D01*
X243594Y240138D01*
X244274Y196584D01*
X238877Y156638D01*
X238836Y153981D01*
X238429Y153588D01*
X238399Y151637D01*
X238793Y151231D01*
X238763Y149282D01*
X238356Y148888D01*
X238326Y146937D01*
X238720Y146531D01*
X238607Y139203D01*
Y138200D01*
X235177Y134770D01*
X234257D01*
X233112Y135915D01*
G01X203606Y1068800D02*
Y1048327D01*
X244807Y268260D01*
X244705Y240145D01*
X245386Y196518D01*
X239986Y156555D01*
X239717Y139194D01*
Y137740D01*
X235637Y133660D01*
X234257D01*
X233112Y132515D01*
G01X206235Y1068476D02*
Y1046322D01*
X206564Y1042568D01*
X247510Y267352D01*
X247404Y240195D01*
X248084Y196691D01*
X242643Y156423D01*
X242525Y148947D01*
X243624Y143048D01*
X243304Y142581D01*
X243662Y140663D01*
X244129Y140343D01*
X244589Y137874D01*
X244634Y134970D01*
X244240Y134564D01*
X244270Y132613D01*
X244677Y132219D01*
X244726Y129050D01*
X243359Y127683D01*
X241557D01*
X240412Y128828D01*
G01X207345Y1068476D02*
Y1046371D01*
X207672Y1042646D01*
X248621Y267379D01*
X248515Y240202D01*
X249196Y196625D01*
X243752Y156340D01*
X243637Y149041D01*
X245698Y137985D01*
X245844Y128597D01*
X243819Y126573D01*
X241557D01*
X240412Y125428D01*
G01X209976Y1068288D02*
Y1048739D01*
X210492Y1042859D01*
X251333Y269646D01*
X252058Y197355D01*
X246665Y157448D01*
X246467Y154809D01*
X246381Y149371D01*
X248449Y137723D01*
X248541Y126334D01*
X247163Y124956D01*
X246597D01*
X245217Y123576D01*
Y123010D01*
X242804Y120597D01*
X240854D01*
X240454Y120997D01*
X238504D01*
X238104Y120597D01*
X234257D01*
X233112Y121742D01*
G01X211086Y1068288D02*
Y1048788D01*
X211600Y1042937D01*
X252443Y269681D01*
X253169Y197286D01*
X247770Y157332D01*
X247577Y154759D01*
X247493Y149460D01*
X249559Y137825D01*
X249655Y125878D01*
X243264Y119487D01*
X234257D01*
X233112Y118342D01*
G01X240412Y114655D02*
X241377Y113690D01*
X241811Y113510D01*
X242862D01*
X245603Y116251D01*
Y116817D01*
X246983Y118197D01*
X247549D01*
X248927Y119575D01*
Y120141D01*
X250307Y121521D01*
X250873D01*
X253796Y124444D01*
X263970Y148593D01*
X263878Y154087D01*
X255911Y192142D01*
X255125Y269156D01*
X214245Y1043119D01*
X213715Y1049163D01*
Y1068476D01*
G01X240412Y111255D02*
X241566Y112409D01*
X241589Y112400D01*
X243322D01*
X254735Y123813D01*
X265084Y148378D01*
X264987Y154211D01*
X257020Y192263D01*
X256235Y269191D01*
X215353Y1043197D01*
X214825Y1049212D01*
Y1068476D01*
G01X217456Y1068288D02*
Y1064958D01*
X218743Y1050086D01*
X295780Y607744D01*
X301202Y565603D01*
X302445Y458560D01*
X345698Y240542D01*
X346410Y194912D01*
X341143Y155924D01*
X341070Y150925D01*
X340613Y150481D01*
X340584Y148530D01*
X341027Y148074D01*
X340999Y146125D01*
X340542Y145681D01*
X340513Y143731D01*
X340957Y143274D01*
X340868Y137139D01*
X338500Y134770D01*
X337114D01*
X336269Y135120D01*
X335474Y135915D01*
G01X218566Y1068288D02*
Y1065006D01*
X219845Y1050229D01*
X296878Y607910D01*
X302312Y565681D01*
X303554Y458675D01*
X346807Y240660D01*
X347522Y194846D01*
X342252Y155841D01*
X341972Y136672D01*
X338960Y133660D01*
X336619D01*
X335474Y132515D01*
G01X342774Y128828D02*
X343662Y127940D01*
X344282Y127683D01*
X345213D01*
X347080Y129551D01*
X347041Y132078D01*
X346583Y132521D01*
X346553Y134472D01*
X346996Y134929D01*
X346955Y137625D01*
X346141Y141996D01*
X345731Y142276D01*
X345374Y144194D01*
X345654Y144603D01*
X344884Y148737D01*
X345004Y156357D01*
X345003D01*
X345005Y156423D01*
X350176Y194695D01*
X349454Y240936D01*
X306201Y458951D01*
X304961Y565868D01*
X299499Y608307D01*
X222491Y1050485D01*
X221196Y1065516D01*
Y1068476D01*
G01X222306D02*
Y1065564D01*
X223593Y1050628D01*
X300597Y608473D01*
X306071Y565946D01*
X307310Y459066D01*
X350563Y241054D01*
X351288Y194629D01*
X346114Y156340D01*
X345996Y148831D01*
X348064Y137736D01*
X348198Y129098D01*
X345673Y126573D01*
X343919D01*
X342774Y125428D01*
G01X226047Y1068288D02*
Y1066653D01*
X227375Y1051342D01*
X304403Y609049D01*
X309832Y566892D01*
X311074Y459417D01*
X354413Y240982D01*
X355141Y194400D01*
X349959Y156051D01*
X349866Y150205D01*
X352697Y134261D01*
X352731Y129933D01*
X351604Y126928D01*
X346814Y119487D01*
X336619D01*
X335474Y118342D01*
G01X224937Y1068288D02*
Y1066604D01*
X226273Y1051199D01*
X303305Y608883D01*
X308722Y566814D01*
X309965Y459302D01*
X353304Y240864D01*
X354029Y194466D01*
X348850Y156135D01*
X348754Y150116D01*
X351587Y134159D01*
X351619Y130130D01*
X350606Y127429D01*
X349551Y125790D01*
X348929Y125655D01*
X347872Y124014D01*
X348007Y123393D01*
X346208Y120597D01*
X343625D01*
X343175Y121047D01*
X341225D01*
X340775Y120597D01*
X336907D01*
X336415Y120801D01*
X335474Y121742D01*
G01X228676Y1068476D02*
Y1063621D01*
X229383Y1060561D01*
X230300Y1049993D01*
X307024Y609446D01*
X312481Y567079D01*
X313722Y459693D01*
X357060Y241260D01*
X357791Y194441D01*
X365594Y157169D01*
X366414Y149856D01*
X366035Y147888D01*
X355564Y123034D01*
X352830Y120300D01*
X352193D01*
X350813Y118920D01*
Y118283D01*
X349435Y116905D01*
X348798D01*
X347418Y115525D01*
Y114888D01*
X346040Y113510D01*
X344659D01*
X343396Y114033D01*
X342774Y114655D01*
G01X229786Y1068476D02*
Y1063748D01*
X230483Y1060735D01*
X231402Y1050136D01*
X231403D01*
X308122Y609612D01*
X313591Y567157D01*
X314831Y459808D01*
X358169Y241378D01*
X358900Y194565D01*
X366692Y157345D01*
X367537Y149812D01*
X367103Y147564D01*
X356503Y122403D01*
X346500Y112400D01*
X343919D01*
X342774Y111255D01*
G01X245023Y1372385D02*
X243878Y1371240D01*
Y1368733D01*
X238626Y1363481D01*
X236752Y1359521D01*
X229787Y1288800D01*
Y1259412D01*
G01X241623Y1372385D02*
X242768Y1371240D01*
Y1369193D01*
X237705Y1364130D01*
X235666Y1359822D01*
X228677Y1288855D01*
Y1259412D01*
G01X253863Y1396583D02*
X255008Y1395438D01*
Y1393013D01*
X261128Y1386893D01*
Y1339045D01*
X236157Y1278761D01*
Y1259412D01*
G01X257263Y1396583D02*
X256118Y1395438D01*
Y1393473D01*
X262238Y1387353D01*
Y1338824D01*
X237267Y1278540D01*
Y1259412D01*
G01X269503Y1372385D02*
X268358Y1371240D01*
Y1368733D01*
X274478Y1362613D01*
Y1343705D01*
X272862Y1339805D01*
X256212Y1308657D01*
X241007Y1276510D01*
Y1259412D01*
G01X266103Y1372385D02*
X267248Y1371240D01*
Y1368273D01*
X273368Y1362153D01*
Y1343926D01*
X271857Y1340280D01*
X255220Y1309156D01*
X239897Y1276760D01*
Y1259412D01*
G01X281743Y1348187D02*
X280598Y1347042D01*
Y1338653D01*
X266753Y1312752D01*
X258001Y1299653D01*
X246828Y1278751D01*
X244747Y1273727D01*
Y1259512D01*
G01X253863Y1348187D02*
X255008Y1347042D01*
Y1336352D01*
X232417Y1281819D01*
Y1259412D01*
G01X278343Y1348187D02*
X279488Y1347042D01*
Y1338932D01*
X265799Y1313324D01*
X257047Y1300225D01*
X245823Y1279226D01*
X243637Y1273948D01*
Y1259512D01*
G01X257263Y1348187D02*
X256118Y1347042D01*
Y1336131D01*
X233527Y1281598D01*
Y1259412D01*
G01X241623Y1384297D02*
X242768Y1385442D01*
Y1401572D01*
X247193Y1483434D01*
X251039Y1518914D01*
X256683Y1532540D01*
X267852Y1543709D01*
X268050D01*
X268191Y1543850D01*
X270442Y1544782D01*
X270631Y1545239D01*
X272434Y1545987D01*
X272891Y1545797D01*
X274692Y1546543D01*
X274693D01*
X274883Y1547000D01*
X276686Y1547747D01*
X277143Y1547557D01*
X278944Y1548303D01*
X279133Y1548761D01*
X280936Y1549508D01*
X281393Y1549318D01*
X283194Y1550064D01*
X286623Y1553493D01*
Y1592008D01*
X284934Y1593697D01*
X283610D01*
X283110Y1593197D01*
Y1591693D01*
G01Y1596811D02*
Y1595307D01*
X283610Y1594807D01*
X285394D01*
X287733Y1592468D01*
Y1553033D01*
X283823Y1549123D01*
X268819Y1542908D01*
X268481Y1542768D01*
X257624Y1531911D01*
X252126Y1518636D01*
X248300Y1483344D01*
X243878Y1401542D01*
Y1385442D01*
X245023Y1384297D01*
G01X315063Y1372385D02*
X316208Y1371240D01*
Y1368273D01*
X322328Y1362153D01*
Y1345435D01*
X320877Y1341381D01*
X273581Y1283752D01*
X269859Y1280029D01*
X264269Y1271664D01*
X262338Y1267002D01*
Y1259512D01*
G01X302823Y1396583D02*
X303968Y1395438D01*
Y1393013D01*
X310088Y1386893D01*
Y1342753D01*
X304296Y1328775D01*
X266403Y1282602D01*
X260546Y1272832D01*
X258598Y1268125D01*
Y1259512D01*
G01X293983Y1372385D02*
X292838Y1371240D01*
Y1368733D01*
X298958Y1362613D01*
Y1342611D01*
X291475Y1331411D01*
X291571Y1330925D01*
X290487Y1329303D01*
X290001Y1329207D01*
X274263Y1305652D01*
X262151Y1289322D01*
X253646Y1274310D01*
X252228Y1270885D01*
Y1259512D01*
G01X278343Y1396583D02*
X279488Y1395438D01*
Y1393013D01*
X285608Y1386893D01*
Y1340487D01*
X280295Y1327661D01*
X259244Y1296158D01*
X248969Y1276933D01*
X247378Y1273091D01*
Y1259512D01*
G01X302823Y1348187D02*
X303968Y1347042D01*
Y1343746D01*
X303967Y1343745D01*
X301120Y1335124D01*
X268694Y1291405D01*
X263225Y1284739D01*
X256497Y1273515D01*
X254858Y1269556D01*
Y1259512D01*
G01X306223Y1348187D02*
X305078Y1347042D01*
Y1343566D01*
X302118Y1334606D01*
X269570Y1290721D01*
X264135Y1284098D01*
X257492Y1273014D01*
X255968Y1269335D01*
Y1259512D01*
G01X306223Y1396583D02*
X305078Y1395438D01*
Y1393473D01*
X311198Y1387353D01*
Y1342532D01*
X305259Y1328198D01*
X267313Y1281961D01*
X261541Y1272331D01*
X259708Y1267904D01*
Y1259512D01*
G01X290583Y1372385D02*
X291728Y1371240D01*
Y1368273D01*
X297848Y1362153D01*
Y1342948D01*
X273354Y1306292D01*
X261218Y1289929D01*
X252646Y1274798D01*
X251118Y1271106D01*
Y1259512D01*
G01X281743Y1396583D02*
X280598Y1395438D01*
Y1393473D01*
X286718Y1387353D01*
Y1340266D01*
X281279Y1327135D01*
X260198Y1295586D01*
X249974Y1276458D01*
X248488Y1272870D01*
Y1259512D01*
G01X253863Y1360099D02*
X255008Y1361244D01*
Y1363613D01*
X248888Y1369733D01*
Y1408606D01*
X254787Y1517773D01*
X260129Y1530668D01*
X269979Y1540518D01*
X290238Y1548909D01*
X292032Y1550703D01*
Y1551198D01*
X293412Y1552578D01*
X293907D01*
X295285Y1553956D01*
Y1596645D01*
X293902Y1598028D01*
X292271D01*
X291771Y1597528D01*
Y1596024D01*
G01Y1601142D02*
Y1599638D01*
X292271Y1599138D01*
X294362D01*
X296395Y1597105D01*
Y1553496D01*
X290867Y1547968D01*
X270608Y1539577D01*
X261070Y1530039D01*
X255886Y1517523D01*
X249998Y1408576D01*
Y1370193D01*
X256118Y1364073D01*
Y1361244D01*
X257263Y1360099D01*
G01X266103Y1384297D02*
X267248Y1385442D01*
Y1387543D01*
X261128Y1393663D01*
Y1410785D01*
X261676Y1413541D01*
X262700Y1492134D01*
Y1516075D01*
X266798Y1525969D01*
X274655Y1533826D01*
X306236Y1546906D01*
X308278Y1548948D01*
Y1549443D01*
X309657Y1550822D01*
X310152D01*
X312608Y1553278D01*
Y1596645D01*
X311225Y1598028D01*
X309594D01*
X309094Y1597528D01*
Y1596024D01*
G01Y1601142D02*
Y1599638D01*
X309594Y1599138D01*
X311685D01*
X313718Y1597105D01*
Y1552818D01*
X306865Y1545965D01*
X275284Y1532885D01*
X267739Y1525340D01*
X263810Y1515854D01*
Y1492126D01*
X262785Y1413424D01*
X262238Y1410675D01*
Y1394123D01*
X268358Y1388003D01*
Y1385442D01*
X269503Y1384297D01*
G01X300433Y1596811D02*
Y1595307D01*
X300933Y1594807D01*
X302717D01*
X305056Y1592468D01*
Y1552986D01*
X298763Y1546693D01*
X272643Y1535874D01*
X264177Y1527408D01*
X259850Y1516961D01*
Y1483385D01*
X256118Y1421798D01*
Y1409640D01*
X257263Y1408495D01*
G01X253863D02*
X255008Y1409640D01*
Y1421832D01*
X258740Y1483419D01*
Y1517182D01*
X263236Y1528037D01*
X272014Y1536815D01*
X289634Y1544112D01*
X289823Y1544570D01*
X291626Y1545317D01*
X292083Y1545127D01*
X293884Y1545873D01*
X294073Y1546330D01*
X295876Y1547078D01*
X296333Y1546888D01*
X298134Y1547634D01*
X300513Y1550013D01*
Y1550508D01*
X301892Y1551887D01*
X302387D01*
X303946Y1553446D01*
Y1592008D01*
X302257Y1593697D01*
X300933D01*
X300433Y1593197D01*
Y1591693D01*
G01X327303Y1348187D02*
X328448Y1347042D01*
Y1342522D01*
X328447Y1342521D01*
X326976Y1338969D01*
X293005Y1297576D01*
X272686Y1277256D01*
X267997Y1270240D01*
X266078Y1265606D01*
Y1259512D01*
G01X339543Y1372385D02*
X340688Y1371240D01*
Y1368273D01*
X346808Y1362153D01*
Y1345103D01*
X343467Y1337037D01*
X278449Y1272019D01*
X274963Y1266802D01*
X273559Y1263412D01*
Y1259612D01*
G01X330703Y1396583D02*
X329558Y1395438D01*
Y1393473D01*
X335678Y1387353D01*
Y1341348D01*
X330956Y1334281D01*
X304755Y1302355D01*
X276586Y1274186D01*
X272380Y1267891D01*
X270929Y1264389D01*
Y1259612D01*
G01X351783Y1348187D02*
X352928Y1347042D01*
Y1342761D01*
X351469Y1339239D01*
X280697Y1268467D01*
X278280Y1264851D01*
X277299Y1262482D01*
Y1259512D01*
G01X355183Y1348187D02*
X354038Y1347042D01*
Y1342540D01*
X352410Y1338610D01*
X281559Y1267759D01*
X279264Y1264325D01*
X278409Y1262261D01*
Y1259512D01*
G01X342943Y1372385D02*
X341798Y1371240D01*
Y1368733D01*
X347918Y1362613D01*
Y1344882D01*
X344408Y1336408D01*
X279311Y1271311D01*
X275947Y1266276D01*
X274669Y1263191D01*
Y1259612D01*
G01X327303Y1396583D02*
X328448Y1395438D01*
Y1393013D01*
X334568Y1386893D01*
Y1341685D01*
X330063Y1334943D01*
X303931Y1303102D01*
X275724Y1274894D01*
X271396Y1268417D01*
X269819Y1264610D01*
Y1259612D01*
G01X330703Y1348187D02*
X329558Y1347042D01*
Y1342300D01*
X327939Y1338392D01*
X293829Y1296829D01*
X273548Y1276548D01*
X268981Y1269714D01*
X267188Y1265385D01*
Y1259512D01*
G01X318463Y1372385D02*
X317318Y1371240D01*
Y1368733D01*
X323438Y1362613D01*
Y1345242D01*
X321858Y1340825D01*
X274405Y1283005D01*
X270721Y1279321D01*
X265253Y1271138D01*
X263448Y1266781D01*
Y1259512D01*
G01X317756Y1596811D02*
Y1595307D01*
X318256Y1594807D01*
X320040D01*
X322379Y1592468D01*
Y1552409D01*
X314731Y1544761D01*
X277228Y1529227D01*
X270742Y1522741D01*
X267773Y1515573D01*
Y1492097D01*
X267144Y1443738D01*
X274478Y1410191D01*
Y1370193D01*
X280598Y1364073D01*
Y1361244D01*
X281743Y1360099D01*
G01X317756Y1591693D02*
Y1593197D01*
X318256Y1593697D01*
X319580D01*
X321269Y1592008D01*
Y1552869D01*
X317987Y1549587D01*
X317492D01*
X316113Y1548208D01*
Y1547713D01*
X314102Y1545702D01*
X312301Y1544956D01*
X311844Y1545146D01*
X310041Y1544398D01*
X309852Y1543941D01*
Y1543942D01*
X308051Y1543196D01*
Y1543195D01*
X307594Y1543385D01*
X305791Y1542638D01*
X305602Y1542180D01*
X305601Y1542181D01*
X276599Y1530168D01*
X269801Y1523370D01*
X266663Y1515794D01*
Y1492105D01*
X266032Y1443625D01*
X273368Y1410071D01*
Y1369733D01*
X279488Y1363613D01*
Y1361244D01*
X278343Y1360099D01*
G01X326417Y1596024D02*
Y1597528D01*
X326917Y1598028D01*
X328548D01*
X329930Y1596646D01*
Y1551000D01*
X324936Y1546006D01*
X323135Y1545260D01*
X322678Y1545450D01*
X320875Y1544702D01*
X320686Y1544245D01*
Y1544246D01*
X278842Y1526913D01*
X273091Y1521162D01*
X270433Y1514744D01*
Y1492079D01*
X269819Y1445025D01*
X279488Y1412195D01*
Y1409640D01*
X278343Y1408495D01*
G01X335078Y1591693D02*
Y1593197D01*
X335578Y1593697D01*
X336902D01*
X338591Y1592008D01*
Y1551361D01*
X336352Y1549122D01*
X335857D01*
X334478Y1547743D01*
Y1547248D01*
X331305Y1544075D01*
X329293Y1543242D01*
X328836Y1543431D01*
X327033Y1542684D01*
X326844Y1542227D01*
X326843D01*
X325043Y1541481D01*
X324586Y1541671D01*
X322783Y1540923D01*
X322594Y1540466D01*
Y1540467D01*
X320793Y1539721D01*
Y1539720D01*
X320336Y1539910D01*
X318533Y1539162D01*
X318344Y1538705D01*
X318343Y1538706D01*
X280434Y1523003D01*
X276336Y1518905D01*
X274202Y1513753D01*
Y1492053D01*
X273669Y1451116D01*
Y1448486D01*
X285608Y1409127D01*
Y1393663D01*
X291728Y1387543D01*
Y1385442D01*
X290583Y1384297D01*
G01X326417Y1601142D02*
Y1599638D01*
X326917Y1599138D01*
X329008D01*
X331040Y1597106D01*
Y1550540D01*
X325565Y1545065D01*
X279471Y1525972D01*
X274032Y1520533D01*
X271543Y1514523D01*
Y1492071D01*
X270932Y1445178D01*
X280598Y1412356D01*
Y1409640D01*
X281743Y1408495D01*
G01X335078Y1596811D02*
Y1595307D01*
X335578Y1594807D01*
X337362D01*
X339701Y1592468D01*
Y1550901D01*
X331934Y1543134D01*
X281063Y1522062D01*
X277277Y1518276D01*
X275312Y1513532D01*
Y1492045D01*
X274779Y1451108D01*
Y1448651D01*
X286718Y1409292D01*
Y1394123D01*
X292838Y1388003D01*
Y1385442D01*
X293983Y1384297D01*
G01X343740Y1596024D02*
Y1597528D01*
X344240Y1598028D01*
X345871D01*
X347253Y1596646D01*
Y1553323D01*
X335401Y1541471D01*
X282474Y1519547D01*
X279427Y1516500D01*
X277962Y1512963D01*
Y1492027D01*
X277433Y1451381D01*
X283486Y1439922D01*
X283340Y1439449D01*
X284252Y1437724D01*
X284725Y1437578D01*
X296292Y1415681D01*
X297848Y1409406D01*
Y1369733D01*
X303968Y1363613D01*
Y1361244D01*
X302823Y1360099D01*
G01X343740Y1601142D02*
Y1599638D01*
X344240Y1599138D01*
X346331D01*
X348363Y1597106D01*
Y1552863D01*
X336030Y1540530D01*
X283103Y1518606D01*
X280368Y1515871D01*
X279072Y1512742D01*
Y1492019D01*
X278547Y1451649D01*
X297337Y1416080D01*
X298958Y1409542D01*
Y1370193D01*
X305078Y1364073D01*
Y1361244D01*
X306223Y1360099D01*
G01X364023Y1372385D02*
X365168Y1371240D01*
Y1368273D01*
X371288Y1362153D01*
Y1347242D01*
X371287D01*
X365613Y1334443D01*
X285447Y1261782D01*
X284779Y1260276D01*
Y1259512D01*
G01X351783Y1396583D02*
X352928Y1395438D01*
Y1393013D01*
X359048Y1386893D01*
Y1344734D01*
X356562Y1338732D01*
X283445Y1265615D01*
X281643Y1262920D01*
X281039Y1261461D01*
Y1259512D01*
G01X355183Y1396583D02*
X354038Y1395438D01*
Y1393473D01*
X360158Y1387353D01*
Y1344513D01*
X357503Y1338103D01*
X284307Y1264907D01*
X282627Y1262394D01*
X282149Y1261240D01*
Y1259512D01*
G01X367423Y1372385D02*
X366278Y1371240D01*
Y1368733D01*
X372398Y1362613D01*
Y1347007D01*
X366533Y1333778D01*
X286367Y1261117D01*
X285889Y1260040D01*
Y1259512D01*
G01X283110Y1489331D02*
Y1490835D01*
X283610Y1491335D01*
X284934D01*
X286623Y1489646D01*
Y1449328D01*
X288396Y1445581D01*
X288229Y1445115D01*
X289065Y1443351D01*
X289531Y1443185D01*
X289530D01*
X290364Y1441422D01*
X290365Y1441423D01*
X290198Y1440957D01*
X291033Y1439193D01*
X291499Y1439027D01*
X291498Y1439026D01*
X292332Y1437264D01*
X292333Y1437265D01*
X292166Y1436799D01*
X293001Y1435035D01*
X293467Y1434869D01*
X293466Y1434868D01*
X303968Y1412677D01*
Y1409640D01*
X302823Y1408495D01*
G01X283110Y1494449D02*
Y1492945D01*
X283610Y1492445D01*
X285394D01*
X287733Y1490106D01*
Y1449578D01*
X305078Y1412927D01*
Y1409640D01*
X306223Y1408495D01*
G01X315063Y1384297D02*
X316208Y1385442D01*
Y1387543D01*
X310088Y1393663D01*
Y1411484D01*
X308583Y1419045D01*
X298885Y1442461D01*
X298493Y1442624D01*
X297746Y1444426D01*
X297908Y1444818D01*
X295285Y1451152D01*
Y1494283D01*
X293902Y1495666D01*
X292271D01*
X291771Y1495166D01*
Y1493662D01*
G01Y1498780D02*
Y1497276D01*
X292271Y1496776D01*
X294362D01*
X296395Y1494743D01*
Y1451373D01*
X309651Y1419369D01*
X311198Y1411594D01*
Y1394123D01*
X317318Y1388003D01*
Y1385442D01*
X318463Y1384297D01*
G01X300433Y1494449D02*
Y1492945D01*
X300933Y1492445D01*
X302717D01*
X305056Y1490106D01*
Y1454533D01*
X323438Y1410155D01*
Y1370193D01*
X329558Y1364073D01*
Y1361244D01*
X330703Y1360099D01*
G01X300433Y1489331D02*
Y1490835D01*
X300933Y1491335D01*
X302257D01*
X303946Y1489646D01*
Y1454312D01*
X306433Y1448307D01*
X306244Y1447850D01*
X306991Y1446047D01*
X307448Y1445858D01*
X307447D01*
X308193Y1444057D01*
X308194D01*
X308004Y1443600D01*
X308752Y1441797D01*
X309209Y1441608D01*
X309208D01*
X309954Y1439807D01*
X309955D01*
X309765Y1439350D01*
X310512Y1437547D01*
X310970Y1437358D01*
X310968D01*
X322328Y1409934D01*
Y1369733D01*
X328448Y1363613D01*
Y1361244D01*
X327303Y1360099D01*
G01X330703Y1408495D02*
X329558Y1409640D01*
Y1412895D01*
X313718Y1451137D01*
Y1494743D01*
X311685Y1496776D01*
X309594D01*
X309094Y1497276D01*
Y1498780D01*
G01X327303Y1408495D02*
X328448Y1409640D01*
Y1412674D01*
X315528Y1443867D01*
X315071Y1444056D01*
X314324Y1445859D01*
X314513Y1446316D01*
X312608Y1450916D01*
Y1494283D01*
X311225Y1495666D01*
X309594D01*
X309094Y1495166D01*
Y1493662D01*
G01X317756Y1489331D02*
Y1490835D01*
X318256Y1491335D01*
X319580D01*
X321269Y1489646D01*
Y1453486D01*
X322879Y1448179D01*
X322645Y1447742D01*
X323211Y1445875D01*
X323649Y1445642D01*
X324215Y1443776D01*
X323981Y1443340D01*
X324547Y1441473D01*
X324985Y1441240D01*
X325551Y1439374D01*
X325317Y1438938D01*
X325883Y1437071D01*
X326321Y1436838D01*
X326319D01*
X334568Y1409646D01*
Y1393663D01*
X340688Y1387543D01*
Y1385442D01*
X339543Y1384297D01*
G01X317756Y1494449D02*
Y1492945D01*
X318256Y1492445D01*
X320040D01*
X322379Y1490106D01*
Y1453651D01*
X335678Y1409811D01*
Y1394123D01*
X341798Y1388003D01*
Y1385442D01*
X342943Y1384297D01*
G01X326417Y1498780D02*
Y1497276D01*
X326917Y1496776D01*
X329008D01*
X331040Y1494744D01*
Y1451507D01*
X347918Y1410759D01*
Y1370193D01*
X354038Y1364073D01*
Y1361244D01*
X355183Y1360099D01*
G01X326417Y1493662D02*
Y1495166D01*
X326917Y1495666D01*
X328548D01*
X329930Y1494284D01*
Y1451286D01*
X332204Y1445795D01*
X332015Y1445338D01*
X332762Y1443535D01*
X333219Y1443346D01*
X333218D01*
X346808Y1410538D01*
Y1369733D01*
X352928Y1363613D01*
Y1361244D01*
X351783Y1360099D01*
G01X335078Y1489331D02*
Y1490835D01*
X335578Y1491335D01*
X336902D01*
X338591Y1489646D01*
Y1448271D01*
X339995Y1444880D01*
X339779Y1444357D01*
X340526Y1442555D01*
X341049Y1442338D01*
X341795Y1440537D01*
X341578Y1440014D01*
X342325Y1438212D01*
X342848Y1437995D01*
X342847D01*
X343593Y1436194D01*
X343594D01*
X343431Y1435802D01*
X344179Y1433999D01*
X344571Y1433837D01*
X344570Y1433836D01*
X352928Y1413659D01*
Y1409640D01*
X351783Y1408495D01*
G01X335078Y1494449D02*
Y1492945D01*
X335578Y1492445D01*
X337362D01*
X339701Y1490106D01*
Y1448492D01*
X353954Y1414083D01*
X354038Y1413999D01*
Y1409640D01*
X355183Y1408495D01*
G01X343740Y1498780D02*
Y1497276D01*
X344240Y1496776D01*
X346331D01*
X348363Y1494744D01*
Y1453146D01*
X360158Y1414264D01*
Y1394123D01*
X366278Y1388003D01*
Y1385442D01*
X367423Y1384297D01*
G01X343740Y1493662D02*
Y1495166D01*
X344240Y1495666D01*
X345871D01*
X347253Y1494284D01*
Y1452981D01*
X349553Y1445397D01*
X349353Y1445023D01*
X349919Y1443156D01*
X350294Y1442956D01*
X359048Y1414099D01*
Y1393663D01*
X365168Y1387543D01*
Y1385442D01*
X364023Y1384297D01*
G01X343286Y1728583D02*
Y1732378D01*
X343936Y1733028D01*
X352541D01*
X354491Y1734978D01*
Y1736952D01*
X355791Y1738252D01*
X357851D01*
X359151Y1736952D01*
Y1729754D01*
X361101Y1727804D01*
X364081D01*
X366031Y1729754D01*
Y1736952D01*
X367331Y1738252D01*
X369391D01*
X370691Y1736952D01*
Y1729754D01*
X372641Y1727804D01*
X375621D01*
X377571Y1729754D01*
Y1736952D01*
X378871Y1738252D01*
X380931D01*
X382231Y1736952D01*
Y1729754D01*
X384181Y1727804D01*
X387161D01*
X389111Y1729754D01*
Y1736952D01*
X390411Y1738252D01*
X392471D01*
X393771Y1736952D01*
Y1729754D01*
X395721Y1727804D01*
X398701D01*
X400651Y1729754D01*
Y1736952D01*
X401951Y1738252D01*
X404011D01*
X405311Y1736952D01*
Y1729754D01*
X407261Y1727804D01*
X410241D01*
X412191Y1729754D01*
Y1736952D01*
X413491Y1738252D01*
X415551D01*
X416851Y1736952D01*
Y1729754D01*
X418801Y1727804D01*
X421781D01*
X423731Y1729754D01*
Y1736952D01*
X425031Y1738252D01*
X427091D01*
X428391Y1736952D01*
Y1729754D01*
X430341Y1727804D01*
X433321D01*
X435271Y1729754D01*
Y1736952D01*
X436571Y1738252D01*
X438631D01*
X439931Y1736952D01*
Y1729754D01*
X441881Y1727804D01*
X444861D01*
X446811Y1729754D01*
Y1736952D01*
X448111Y1738252D01*
X450171D01*
X451471Y1736952D01*
Y1729754D01*
X453421Y1727804D01*
X456401D01*
X458351Y1729754D01*
Y1736952D01*
X459651Y1738252D01*
X461711D01*
X463011Y1736952D01*
Y1729754D01*
X464961Y1727804D01*
X467941D01*
X469891Y1729754D01*
Y1736952D01*
X471191Y1738252D01*
X473251D01*
X474551Y1736952D01*
Y1729754D01*
X476501Y1727804D01*
X479481D01*
X481431Y1729754D01*
Y1736952D01*
X482731Y1738252D01*
X484791D01*
X486091Y1736952D01*
Y1729754D01*
X488041Y1727804D01*
X491021D01*
X492971Y1729754D01*
Y1736952D01*
X494271Y1738252D01*
X496331D01*
X497631Y1736952D01*
Y1729754D01*
X499581Y1727804D01*
X502561D01*
X504511Y1729754D01*
Y1736952D01*
X505811Y1738252D01*
X507871D01*
X509171Y1736952D01*
Y1729754D01*
X511121Y1727804D01*
X514101D01*
X516051Y1729754D01*
Y1736952D01*
X517351Y1738252D01*
X519411D01*
X520711Y1736952D01*
Y1729754D01*
X522661Y1727804D01*
X525641D01*
X527591Y1729754D01*
Y1736952D01*
X528891Y1738252D01*
X530951D01*
X532251Y1736952D01*
Y1729754D01*
X534201Y1727804D01*
X537181D01*
X539131Y1729754D01*
Y1736952D01*
X540431Y1738252D01*
X542491D01*
X543791Y1736952D01*
Y1729754D01*
X545741Y1727804D01*
X548721D01*
X550671Y1729754D01*
Y1736952D01*
X551971Y1738252D01*
X554031D01*
X555331Y1736952D01*
Y1729754D01*
X557281Y1727804D01*
X560261D01*
X562211Y1729754D01*
Y1736952D01*
X563511Y1738252D01*
X565571D01*
X566871Y1736952D01*
Y1729754D01*
X568821Y1727804D01*
X571801D01*
X573751Y1729754D01*
Y1736952D01*
X575051Y1738252D01*
X577111D01*
X578411Y1736952D01*
Y1729754D01*
X580361Y1727804D01*
X583341D01*
X585291Y1729754D01*
Y1731728D01*
X586591Y1733028D01*
X594736D01*
X595386Y1732378D01*
Y1728583D01*
G01X343286Y1738583D02*
Y1734788D01*
X343936Y1734138D01*
X352081D01*
X353381Y1735438D01*
Y1737412D01*
X355331Y1739362D01*
X358311D01*
X360261Y1737412D01*
Y1730214D01*
X361561Y1728914D01*
X363621D01*
X364921Y1730214D01*
Y1737412D01*
X366871Y1739362D01*
X369851D01*
X371801Y1737412D01*
Y1730214D01*
X373101Y1728914D01*
X375161D01*
X376461Y1730214D01*
Y1737412D01*
X378411Y1739362D01*
X381391D01*
X383341Y1737412D01*
Y1730214D01*
X384641Y1728914D01*
X386701D01*
X388001Y1730214D01*
Y1737412D01*
X389951Y1739362D01*
X392931D01*
X394881Y1737412D01*
Y1730214D01*
X396181Y1728914D01*
X398241D01*
X399541Y1730214D01*
Y1737412D01*
X401491Y1739362D01*
X404471D01*
X406421Y1737412D01*
Y1730214D01*
X407721Y1728914D01*
X409781D01*
X411081Y1730214D01*
Y1737412D01*
X413031Y1739362D01*
X416011D01*
X417961Y1737412D01*
Y1730214D01*
X419261Y1728914D01*
X421321D01*
X422621Y1730214D01*
Y1737412D01*
X424571Y1739362D01*
X427551D01*
X429501Y1737412D01*
Y1730214D01*
X430801Y1728914D01*
X432861D01*
X434161Y1730214D01*
Y1737412D01*
X436111Y1739362D01*
X439091D01*
X441041Y1737412D01*
Y1730214D01*
X442341Y1728914D01*
X444401D01*
X445701Y1730214D01*
Y1737412D01*
X447651Y1739362D01*
X450631D01*
X452581Y1737412D01*
Y1730214D01*
X453881Y1728914D01*
X455941D01*
X457241Y1730214D01*
Y1737412D01*
X459191Y1739362D01*
X462171D01*
X464121Y1737412D01*
Y1730214D01*
X465421Y1728914D01*
X467481D01*
X468781Y1730214D01*
Y1737412D01*
X470731Y1739362D01*
X473711D01*
X475661Y1737412D01*
Y1730214D01*
X476961Y1728914D01*
X479021D01*
X480321Y1730214D01*
Y1737412D01*
X482271Y1739362D01*
X485251D01*
X487201Y1737412D01*
Y1730214D01*
X488501Y1728914D01*
X490561D01*
X491861Y1730214D01*
Y1737412D01*
X493811Y1739362D01*
X496791D01*
X498741Y1737412D01*
Y1730214D01*
X500041Y1728914D01*
X502101D01*
X503401Y1730214D01*
Y1737412D01*
X505351Y1739362D01*
X508331D01*
X510281Y1737412D01*
Y1730214D01*
X511581Y1728914D01*
X513641D01*
X514941Y1730214D01*
Y1737412D01*
X516891Y1739362D01*
X519871D01*
X521821Y1737412D01*
Y1730214D01*
X523121Y1728914D01*
X525181D01*
X526481Y1730214D01*
Y1737412D01*
X528431Y1739362D01*
X531411D01*
X533361Y1737412D01*
Y1730214D01*
X534661Y1728914D01*
X536721D01*
X538021Y1730214D01*
Y1737412D01*
X539971Y1739362D01*
X542951D01*
X544901Y1737412D01*
Y1730214D01*
X546201Y1728914D01*
X548261D01*
X549561Y1730214D01*
Y1737412D01*
X551511Y1739362D01*
X554491D01*
X556441Y1737412D01*
Y1730214D01*
X557741Y1728914D01*
X559801D01*
X561101Y1730214D01*
Y1737412D01*
X563051Y1739362D01*
X566031D01*
X567981Y1737412D01*
Y1730214D01*
X569281Y1728914D01*
X571341D01*
X572641Y1730214D01*
Y1737412D01*
X574591Y1739362D01*
X577571D01*
X579521Y1737412D01*
Y1730214D01*
X580821Y1728914D01*
X582881D01*
X584181Y1730214D01*
Y1732188D01*
X586131Y1734138D01*
X594736D01*
X595386Y1734788D01*
Y1738583D01*
G01X440402Y1372385D02*
X441547Y1371240D01*
Y1368583D01*
X447667Y1362463D01*
Y1343640D01*
X453868Y1337439D01*
X512215Y1302466D01*
X648238Y1261205D01*
X650156Y1259288D01*
G01X440402Y1384297D02*
X441547Y1385442D01*
Y1409265D01*
X442624Y1415190D01*
X450478Y1436961D01*
X452959Y1441490D01*
X452820Y1441965D01*
X453758Y1443676D01*
X454233Y1443815D01*
X455169Y1445525D01*
X455030Y1446000D01*
X455968Y1447711D01*
X456443Y1447850D01*
X458948Y1452423D01*
X459400Y1455045D01*
Y1505042D01*
X457753Y1506689D01*
X456839D01*
X456339Y1506189D01*
Y1504685D01*
G01X452642Y1348187D02*
X453787Y1347042D01*
Y1342838D01*
X456193Y1340432D01*
X470402Y1331915D01*
Y1331916D01*
X512792Y1306507D01*
X652815Y1264028D01*
X658056Y1258788D01*
G01X456042Y1348187D02*
X454897Y1347042D01*
Y1343298D01*
X456881Y1341314D01*
X513246Y1307530D01*
X653404Y1265010D01*
X658841Y1259573D01*
G01X443802Y1372385D02*
X442657Y1371240D01*
Y1369043D01*
X448777Y1362923D01*
Y1344100D01*
X454556Y1338321D01*
X512669Y1303489D01*
X648827Y1262187D01*
X650941Y1260073D01*
G01X456042Y1360099D02*
X454910Y1361231D01*
Y1363960D01*
X448777Y1370093D01*
Y1412330D01*
X449543Y1415200D01*
X459776Y1435269D01*
X469171Y1451501D01*
Y1509832D01*
X466874Y1512129D01*
X465501D01*
X465000Y1512630D01*
Y1514134D01*
G01Y1509016D02*
Y1510519D01*
X465500Y1511019D01*
X466414D01*
X468061Y1509372D01*
Y1451800D01*
X463957Y1444709D01*
X463547Y1444600D01*
X462569Y1442911D01*
X462679Y1442501D01*
X458800Y1435800D01*
X458786Y1435773D01*
X458787D01*
X448500Y1415600D01*
X447667Y1412476D01*
Y1369633D01*
X453800Y1363500D01*
Y1361257D01*
X452642Y1360099D01*
G01Y1396583D02*
X453787Y1395438D01*
Y1392543D01*
X459907Y1386423D01*
Y1343923D01*
X462558Y1341272D01*
X515231Y1309699D01*
X585049Y1288518D01*
X654603Y1267417D01*
X659119Y1264710D01*
X663087Y1260742D01*
X663323Y1260173D01*
Y1259909D01*
G01X456042Y1396583D02*
X454897Y1395438D01*
Y1393003D01*
X461017Y1386883D01*
Y1344383D01*
X463246Y1342154D01*
X515685Y1310722D01*
X655057Y1268440D01*
X659807Y1265592D01*
X664028Y1261371D01*
X664433Y1260394D01*
Y1259909D01*
G01X456339Y1509804D02*
Y1508300D01*
X456840Y1507799D01*
X458213D01*
X460510Y1505502D01*
Y1454950D01*
X460011Y1452052D01*
X451493Y1436503D01*
X443700Y1414900D01*
X442657Y1409164D01*
Y1385442D01*
X443802Y1384297D01*
G01X473662Y1504685D02*
Y1506189D01*
X474162Y1506689D01*
X475076D01*
X476723Y1505042D01*
Y1454100D01*
X475300Y1448700D01*
X472503Y1444227D01*
X472090Y1444132D01*
X471055Y1442478D01*
X471150Y1442064D01*
X470117Y1440411D01*
X469703Y1440316D01*
X468668Y1438662D01*
X468763Y1438248D01*
X467730Y1436595D01*
X467316Y1436500D01*
X466281Y1434846D01*
X466377Y1434432D01*
X454601Y1415602D01*
X453787Y1410376D01*
Y1409640D01*
X452642Y1408495D01*
G01X456042D02*
X454897Y1409640D01*
Y1410290D01*
X455663Y1415206D01*
X476331Y1448254D01*
X477833Y1453956D01*
Y1505502D01*
X475536Y1507799D01*
X474163D01*
X473662Y1508300D01*
Y1509804D01*
G01X505002Y1408495D02*
X503857Y1409640D01*
Y1412283D01*
X504841Y1415523D01*
X530516Y1453946D01*
Y1516741D01*
X530088Y1517407D01*
X529708Y1517998D01*
X519424Y1524785D01*
X501180Y1532383D01*
Y1532382D01*
X482937Y1539979D01*
X463103Y1553824D01*
X460510Y1560120D01*
Y1592509D01*
X458213Y1594806D01*
X456840D01*
X456339Y1595307D01*
Y1596811D01*
G01X501602Y1408495D02*
X502747Y1409640D01*
Y1412448D01*
X503826Y1416003D01*
X517507Y1436477D01*
X517410Y1436962D01*
X518495Y1438585D01*
X518980Y1438681D01*
X520063Y1440302D01*
X519966Y1440787D01*
X521051Y1442410D01*
X521536Y1442506D01*
X522619Y1444127D01*
X522523Y1444612D01*
X523607Y1446235D01*
X524093Y1446331D01*
X529406Y1454283D01*
Y1516414D01*
X528900Y1517200D01*
X518900Y1523800D01*
X482400Y1539000D01*
X462200Y1553100D01*
X459400Y1559900D01*
Y1592049D01*
X457753Y1593696D01*
X456839D01*
X456339Y1593196D01*
Y1591693D01*
G01X464882Y1372385D02*
X466027Y1371240D01*
Y1368583D01*
X472147Y1362463D01*
Y1341654D01*
X476503Y1337298D01*
X516769Y1313164D01*
X551606Y1302596D01*
X656116Y1270895D01*
X661452Y1267697D01*
X665800Y1263349D01*
X667063Y1260300D01*
Y1259852D01*
G01X468282Y1372385D02*
X467137Y1371240D01*
Y1369043D01*
X473257Y1362923D01*
Y1342114D01*
X477191Y1338180D01*
X517223Y1314187D01*
X586766Y1293092D01*
X586765D01*
X656570Y1271918D01*
X662140Y1268579D01*
X666741Y1263978D01*
X668173Y1260521D01*
Y1259852D01*
G01X490985Y1509804D02*
Y1508300D01*
X491486Y1507799D01*
X492859D01*
X495156Y1505502D01*
Y1452453D01*
X475305Y1422743D01*
X473257Y1415991D01*
Y1370203D01*
X479377Y1364083D01*
Y1361244D01*
X480522Y1360099D01*
G01X477122D02*
X478267Y1361244D01*
Y1363623D01*
X472147Y1369743D01*
Y1416156D01*
X474290Y1423223D01*
X483658Y1437244D01*
X483575Y1437660D01*
X484659Y1439282D01*
X485075Y1439365D01*
X486158Y1440986D01*
X486076Y1441402D01*
X487160Y1443024D01*
X487576Y1443107D01*
X488659Y1444728D01*
X488576Y1445144D01*
X489660Y1446766D01*
X490077Y1446849D01*
X494046Y1452790D01*
Y1505042D01*
X492399Y1506689D01*
X491485D01*
X490985Y1506189D01*
Y1504685D01*
G01X482323Y1509016D02*
Y1510519D01*
X482823Y1511019D01*
X483737D01*
X485384Y1509372D01*
Y1451062D01*
X482140Y1446207D01*
X481724Y1446124D01*
X480639Y1444502D01*
X480722Y1444085D01*
X479639Y1442464D01*
X479223Y1442381D01*
X478139Y1440759D01*
X478221Y1440343D01*
X459907Y1412934D01*
Y1393603D01*
X466027Y1387483D01*
Y1385442D01*
X464882Y1384297D01*
G01X482323Y1514134D02*
Y1512630D01*
X482824Y1512129D01*
X484197D01*
X486494Y1509832D01*
Y1450725D01*
X461017Y1412597D01*
Y1394063D01*
X467137Y1387943D01*
Y1385442D01*
X468282Y1384297D01*
G01X465000Y1601142D02*
Y1599638D01*
X465501Y1599137D01*
X466874D01*
X469171Y1596840D01*
Y1560271D01*
X469623Y1558056D01*
X471555Y1552511D01*
X473352Y1551257D01*
X473355Y1551255D01*
X484757Y1543295D01*
X521496Y1528027D01*
X536129Y1522777D01*
X537594Y1521554D01*
X538155Y1520355D01*
Y1508561D01*
X539428Y1456811D01*
X537389Y1451111D01*
X510927Y1412540D01*
X509977Y1409884D01*
Y1394063D01*
X516097Y1387943D01*
Y1385442D01*
X517242Y1384297D01*
G01X465000Y1596024D02*
Y1597527D01*
X465500Y1598027D01*
X466414D01*
X468061Y1596380D01*
Y1560158D01*
X468550Y1557761D01*
X470625Y1551806D01*
X472717Y1550346D01*
X472729Y1550338D01*
X484220Y1542316D01*
X521095Y1526991D01*
X535568Y1521798D01*
X536693Y1520860D01*
X537045Y1520108D01*
Y1508547D01*
X538313Y1456990D01*
X536392Y1451620D01*
X532911Y1446546D01*
X532424Y1446455D01*
X531320Y1444846D01*
X531411Y1444359D01*
X531410D01*
X509930Y1413049D01*
X508867Y1410077D01*
Y1393603D01*
X514987Y1387483D01*
Y1385442D01*
X513842Y1384297D01*
G01X473662Y1596811D02*
Y1595307D01*
X474163Y1594806D01*
X475536D01*
X477833Y1592509D01*
Y1556782D01*
X489415Y1545946D01*
X524787Y1531042D01*
X533678Y1528171D01*
X538502Y1525976D01*
X541389Y1523573D01*
X542412Y1521624D01*
Y1508621D01*
X543702Y1456178D01*
X542497Y1452209D01*
X522217Y1414270D01*
Y1370203D01*
X528337Y1364083D01*
Y1361244D01*
X529482Y1360099D01*
G01X526082D02*
X527227Y1361244D01*
Y1363623D01*
X521107Y1369743D01*
Y1414549D01*
X530478Y1432081D01*
X530334Y1432554D01*
X531255Y1434275D01*
X531728Y1434419D01*
X532647Y1436138D01*
X532503Y1436611D01*
X533424Y1438332D01*
X533897Y1438476D01*
X534816Y1440195D01*
X534672Y1440669D01*
X535592Y1442390D01*
X536066Y1442533D01*
X541466Y1452636D01*
X542587Y1456330D01*
X541302Y1508607D01*
Y1521350D01*
X540509Y1522861D01*
X537907Y1525027D01*
X533276Y1527134D01*
X524400Y1530000D01*
X488800Y1545000D01*
X476723Y1556300D01*
Y1592049D01*
X475076Y1593696D01*
X474162D01*
X473662Y1593196D01*
Y1591693D01*
G01X638252Y1068288D02*
Y1064115D01*
X634464Y1037412D01*
X634767Y1006484D01*
X628468Y937675D01*
X558736Y568918D01*
X545814Y470679D01*
X525384Y403278D01*
Y403276D01*
X525337Y403121D01*
X525336Y403118D01*
X504953Y335873D01*
X505703Y242085D01*
Y236744D01*
X504650Y225836D01*
X505112Y196331D01*
X499998Y158489D01*
X499856Y149460D01*
X501922Y137825D01*
X502018Y125878D01*
X495627Y119487D01*
X486620D01*
X485475Y118342D01*
G01X637142Y1068288D02*
Y1064194D01*
X633353Y1037485D01*
X633656Y1006529D01*
X627367Y937829D01*
X557639Y569094D01*
X544725Y470914D01*
X524322Y403601D01*
X524321Y403598D01*
X524274Y403443D01*
Y403441D01*
X503841Y336033D01*
X504593Y242080D01*
Y236798D01*
X503539Y225881D01*
X504000Y196397D01*
X498889Y158572D01*
X498744Y149371D01*
X500812Y137723D01*
X500904Y126334D01*
X499151Y124581D01*
X498586D01*
X497206Y123201D01*
Y122636D01*
X495167Y120597D01*
X493217D01*
X492817Y120997D01*
X490867D01*
X490467Y120597D01*
X486620D01*
X485475Y121742D01*
G01X630771Y1068288D02*
Y1064854D01*
X629992Y1058363D01*
X628538Y1051286D01*
X626911Y1037711D01*
Y1032787D01*
X627170Y1006345D01*
X620978Y938717D01*
X551161Y569505D01*
X538350Y472104D01*
X517861Y404508D01*
X517860Y404506D01*
X497370Y336907D01*
X498116Y246490D01*
Y237178D01*
X497047Y225367D01*
X497502Y196278D01*
X492377Y158350D01*
X492080Y139194D01*
Y137740D01*
X488000Y133660D01*
X486620D01*
X485475Y132515D01*
G01X629661Y1068288D02*
Y1064922D01*
X629660Y1064921D01*
X628895Y1058541D01*
X627441Y1051464D01*
X625801Y1037778D01*
Y1032781D01*
X626059Y1006390D01*
X619877Y938871D01*
X602423Y846572D01*
X602422D01*
X584970Y754275D01*
X584969D01*
X550064Y569681D01*
X537261Y472339D01*
X516798Y404830D01*
X516797Y404827D01*
X496258Y337067D01*
X497006Y246485D01*
Y237229D01*
X495936Y225408D01*
X496390Y196344D01*
X491268Y158433D01*
X491215Y154975D01*
X490808Y154581D01*
X490778Y152631D01*
X491171Y152225D01*
X491141Y150276D01*
X490734Y149882D01*
X490704Y147931D01*
X491098Y147525D01*
X490970Y139203D01*
Y138200D01*
X487540Y134770D01*
X486620D01*
X485475Y135915D01*
G01X477122Y1348187D02*
X478267Y1347042D01*
Y1342233D01*
X479444Y1341056D01*
X522139Y1315466D01*
X590028Y1294873D01*
X657653Y1274360D01*
X665111Y1269890D01*
X668749Y1266252D01*
X670803Y1261293D01*
Y1259909D01*
G01X480522Y1396583D02*
X479377Y1395438D01*
Y1393003D01*
X485497Y1386883D01*
Y1345874D01*
X492396Y1338975D01*
X524115Y1319962D01*
X659647Y1278846D01*
X669075Y1273194D01*
X672745Y1269524D01*
X675653Y1262503D01*
Y1259852D01*
G01X480522Y1348187D02*
X479377Y1347042D01*
Y1342693D01*
X480132Y1341938D01*
X522593Y1316489D01*
X658107Y1275383D01*
X665799Y1270772D01*
X669690Y1266881D01*
X671913Y1261514D01*
Y1259909D01*
G01X477122Y1396583D02*
X478267Y1395438D01*
Y1392543D01*
X484387Y1386423D01*
Y1345414D01*
X491708Y1338093D01*
X523661Y1318939D01*
X591559Y1298341D01*
X659193Y1277823D01*
X668387Y1272312D01*
X671804Y1268895D01*
X674543Y1262282D01*
Y1259852D01*
G01X489362Y1372385D02*
X490507Y1371240D01*
Y1368583D01*
X496627Y1362463D01*
Y1343273D01*
X505969Y1333931D01*
X525200Y1322403D01*
X593089Y1301809D01*
X593088D01*
X660714Y1281296D01*
X670824Y1275237D01*
X675081Y1270980D01*
X678284Y1263247D01*
Y1259909D01*
G01X489362Y1384297D02*
X490507Y1385442D01*
Y1387483D01*
X484387Y1393603D01*
Y1410692D01*
X485202Y1413321D01*
X499121Y1433608D01*
X499043Y1434025D01*
X500147Y1435634D01*
X500564Y1435712D01*
X501667Y1437319D01*
X501589Y1437736D01*
X502693Y1439345D01*
X503110Y1439423D01*
X504213Y1441030D01*
X504135Y1441447D01*
X505239Y1443056D01*
X505656Y1443134D01*
X510301Y1449904D01*
X511368Y1452887D01*
Y1505042D01*
X509721Y1506689D01*
X508807D01*
X508307Y1506189D01*
Y1504685D01*
G01Y1509804D02*
Y1508300D01*
X508808Y1507799D01*
X510181D01*
X512478Y1505502D01*
Y1452694D01*
X511298Y1449395D01*
X486213Y1412831D01*
X485497Y1410523D01*
Y1394063D01*
X491617Y1387943D01*
Y1385442D01*
X492762Y1384297D01*
G01X499646Y1509016D02*
Y1510519D01*
X500146Y1511019D01*
X501060D01*
X502707Y1509372D01*
Y1454371D01*
X501816Y1451435D01*
X498759Y1446860D01*
X498343Y1446777D01*
X497259Y1445155D01*
X497342Y1444739D01*
X496259Y1443118D01*
X495843Y1443035D01*
X494759Y1441413D01*
X494841Y1440997D01*
X478267Y1416191D01*
Y1409640D01*
X477122Y1408495D01*
G01X480522D02*
X479377Y1409640D01*
Y1415854D01*
X502831Y1450955D01*
X503817Y1454206D01*
Y1509832D01*
X501520Y1512129D01*
X500147D01*
X499646Y1512630D01*
Y1514134D01*
G01X482323Y1601142D02*
Y1599638D01*
X482824Y1599137D01*
X484197D01*
X486494Y1596840D01*
Y1555576D01*
X493375Y1548695D01*
X529519Y1533466D01*
X537974Y1530737D01*
X540948Y1529020D01*
X544571Y1526006D01*
X545830Y1523609D01*
X546523Y1521319D01*
Y1508681D01*
X547856Y1454593D01*
X528337Y1411983D01*
Y1409640D01*
X529482Y1408495D01*
G01X526082D02*
X527227Y1409640D01*
Y1412226D01*
X535759Y1430853D01*
X535611Y1431251D01*
X536424Y1433025D01*
X536822Y1433172D01*
X546739Y1454822D01*
X545413Y1508667D01*
Y1521154D01*
X544797Y1523186D01*
X544798D01*
X543691Y1525294D01*
X540311Y1528106D01*
X537521Y1529716D01*
X529132Y1532424D01*
X492744Y1547756D01*
X485384Y1555116D01*
Y1596380D01*
X483737Y1598027D01*
X482823D01*
X482323Y1597527D01*
Y1596024D01*
G01X492775Y114655D02*
X493741Y113689D01*
X494173Y113510D01*
X495225D01*
X498410Y116695D01*
X501025Y120608D01*
X507104Y126687D01*
X508076Y128996D01*
X507863Y129520D01*
X508621Y131318D01*
X509145Y131531D01*
X509902Y133328D01*
X509688Y133851D01*
X510446Y135649D01*
X510970Y135863D01*
X516333Y148593D01*
X516241Y154086D01*
X507792Y194441D01*
X507304Y225731D01*
X508366Y236511D01*
Y243503D01*
X507620Y335489D01*
X548426Y470115D01*
X561367Y568497D01*
X631109Y937305D01*
X637432Y1006375D01*
X637129Y1037325D01*
X640881Y1061117D01*
Y1068476D01*
G01X492775Y111255D02*
X493929Y112409D01*
X493952Y112400D01*
X495685D01*
X499272Y115987D01*
X501887Y119900D01*
X508043Y126056D01*
X517447Y148378D01*
X517350Y154210D01*
X508901Y194565D01*
X508415Y225685D01*
X509476Y236456D01*
Y243508D01*
X508732Y335329D01*
X549515Y469880D01*
X562464Y568321D01*
X632210Y937151D01*
X638543Y1006330D01*
X638240Y1037243D01*
X641991Y1061030D01*
Y1068476D01*
G01X492775Y128828D02*
X493920Y127683D01*
X495722D01*
X497089Y129050D01*
X497037Y132427D01*
X496630Y132820D01*
X496600Y134771D01*
X496993Y135177D01*
X496952Y137874D01*
X496547Y140049D01*
X496079Y140369D01*
X495722Y142287D01*
X496042Y142754D01*
X494888Y148947D01*
X495034Y158145D01*
X500156Y196059D01*
X499700Y225245D01*
X500804Y237429D01*
Y244093D01*
X500046Y336579D01*
X520518Y404115D01*
Y404117D01*
X520565Y404272D01*
X520566Y404275D01*
X541008Y471716D01*
X553895Y569694D01*
X623609Y938355D01*
X625171Y955435D01*
X625172D01*
X629864Y1006683D01*
X629561Y1037546D01*
X633401Y1064584D01*
Y1068476D01*
G01X492775Y125428D02*
X493920Y126573D01*
X496182D01*
X498207Y128597D01*
X498061Y137985D01*
X496000Y149041D01*
X496143Y158062D01*
X501268Y195993D01*
X500811Y225203D01*
X501914Y237378D01*
Y244098D01*
X501158Y336419D01*
X521580Y403792D01*
X521581Y403795D01*
X521628Y403950D01*
Y403952D01*
X542097Y471481D01*
X554992Y569518D01*
X624710Y938201D01*
X630975Y1006638D01*
X630672Y1037473D01*
X634511Y1064505D01*
Y1068476D01*
G01X492762Y1372385D02*
X491617Y1371240D01*
Y1369043D01*
X497737Y1362923D01*
Y1343733D01*
X506657Y1334813D01*
X525654Y1323426D01*
X661168Y1282319D01*
X671512Y1276119D01*
X676022Y1271609D01*
X679394Y1263468D01*
Y1259909D01*
G01X501602Y1348187D02*
X502747Y1347042D01*
Y1342653D01*
X508752Y1336648D01*
X526735Y1325869D01*
X594624Y1305275D01*
X662249Y1284761D01*
X673765Y1277859D01*
X678296Y1273328D01*
X682024Y1264328D01*
Y1259852D01*
G01X505002Y1348187D02*
X503857Y1347042D01*
Y1343113D01*
X509440Y1337530D01*
X527189Y1326892D01*
X662703Y1285784D01*
X674453Y1278741D01*
X679237Y1273957D01*
X683134Y1264549D01*
Y1259852D01*
G01X516969Y1509016D02*
Y1510519D01*
X517469Y1511019D01*
X518383D01*
X520030Y1509372D01*
Y1451043D01*
X515455Y1444196D01*
X515039Y1444113D01*
X513955Y1442491D01*
X514037Y1442075D01*
X512954Y1440454D01*
X512538Y1440371D01*
X511454Y1438749D01*
X511536Y1438333D01*
X498203Y1418377D01*
X496627Y1413181D01*
Y1369743D01*
X502747Y1363623D01*
Y1361244D01*
X501602Y1360099D01*
G01X516969Y1514134D02*
Y1512630D01*
X517470Y1512129D01*
X518843D01*
X521140Y1509832D01*
Y1450706D01*
X499218Y1417897D01*
X497737Y1413016D01*
Y1370203D01*
X503857Y1364083D01*
Y1361244D01*
X505002Y1360099D01*
G01Y1396583D02*
X503857Y1395438D01*
Y1393003D01*
X509977Y1386883D01*
Y1345324D01*
X512568Y1342733D01*
X532160Y1330989D01*
X565279Y1320941D01*
X598398Y1310894D01*
Y1310895D01*
X664897Y1290721D01*
X677774Y1283002D01*
X683942Y1276834D01*
X686874Y1269756D01*
Y1259909D01*
G01X501602Y1396583D02*
X502747Y1395438D01*
Y1392543D01*
X508867Y1386423D01*
Y1344864D01*
X511880Y1341851D01*
X531706Y1329966D01*
X631259Y1299765D01*
X664443Y1289698D01*
X677086Y1282120D01*
X683001Y1276205D01*
X685764Y1269535D01*
Y1259909D01*
G01X538322Y1384297D02*
X539467Y1385442D01*
Y1387483D01*
X533347Y1393603D01*
Y1411034D01*
X539863Y1426766D01*
X539700Y1427158D01*
X540447Y1428961D01*
X540839Y1429123D01*
X541585Y1430924D01*
X541423Y1431316D01*
X542170Y1433119D01*
X542562Y1433281D01*
X543308Y1435082D01*
X543146Y1435474D01*
X543893Y1437276D01*
X544285Y1437439D01*
X551602Y1455104D01*
Y1455926D01*
X550300Y1508740D01*
Y1511318D01*
X549310Y1521263D01*
X548297Y1524612D01*
X546674Y1527705D01*
X542357Y1531295D01*
X538752Y1533378D01*
X504306Y1547894D01*
X494046Y1558154D01*
Y1592049D01*
X492399Y1593696D01*
X491485D01*
X490985Y1593196D01*
Y1591693D01*
G01Y1596811D02*
Y1595307D01*
X491486Y1594806D01*
X492859D01*
X495156Y1592509D01*
Y1558614D01*
X504937Y1548833D01*
X539247Y1534374D01*
X542994Y1532209D01*
X547554Y1528417D01*
X549330Y1525035D01*
X550404Y1521481D01*
X551410Y1511374D01*
Y1508754D01*
X552712Y1455940D01*
Y1454883D01*
X534457Y1410813D01*
Y1394063D01*
X540577Y1387943D01*
Y1385442D01*
X541722Y1384297D01*
G01X499646Y1601142D02*
Y1599638D01*
X500147Y1599137D01*
X501520D01*
X503817Y1596840D01*
Y1560382D01*
X504857Y1555017D01*
X508173Y1551701D01*
X540842Y1537863D01*
X545260Y1535306D01*
X550447Y1530996D01*
X552826Y1526466D01*
X554312Y1521556D01*
X555210Y1512532D01*
Y1508802D01*
X556500Y1456495D01*
Y1451071D01*
X549039Y1426476D01*
X546697Y1410690D01*
Y1370203D01*
X552817Y1364083D01*
Y1361244D01*
X553962Y1360099D01*
G01X550562D02*
X551707Y1361244D01*
Y1363623D01*
X545587Y1369743D01*
Y1410772D01*
X547953Y1426720D01*
X550266Y1434347D01*
X550066Y1434721D01*
X550632Y1436588D01*
X551008Y1436788D01*
X555390Y1451236D01*
Y1456481D01*
X554100Y1508788D01*
Y1512476D01*
X553218Y1521338D01*
X551794Y1526043D01*
X549567Y1530284D01*
X544623Y1534392D01*
X540345Y1536867D01*
X507541Y1550763D01*
X503831Y1554472D01*
X502707Y1560275D01*
Y1596380D01*
X501060Y1598027D01*
X500146D01*
X499646Y1597527D01*
Y1596024D01*
G01X517242Y1372385D02*
X516097Y1371240D01*
Y1369043D01*
X522217Y1362923D01*
Y1343353D01*
X526498Y1339072D01*
X534723Y1334142D01*
X666425Y1294190D01*
X680105Y1285989D01*
X687503Y1278591D01*
X690614Y1271080D01*
Y1259852D01*
G01X513842Y1372385D02*
X514987Y1371240D01*
Y1368583D01*
X521107Y1362463D01*
Y1342893D01*
X525810Y1338190D01*
X534269Y1333119D01*
X600252Y1313103D01*
X665971Y1293167D01*
X679417Y1285107D01*
X686562Y1277962D01*
X689504Y1270859D01*
Y1259852D01*
G01X516969Y1601142D02*
Y1599638D01*
X517470Y1599137D01*
X518843D01*
X521140Y1596840D01*
Y1560191D01*
X521935Y1555349D01*
X523423Y1553939D01*
X546654Y1543750D01*
X552706Y1539259D01*
X554947Y1537222D01*
X557324Y1535061D01*
X560041Y1528790D01*
X562170Y1522101D01*
X563010Y1511695D01*
Y1508900D01*
X564312Y1456224D01*
Y1447341D01*
X558937Y1411103D01*
Y1394063D01*
X565057Y1387943D01*
Y1385442D01*
X566202Y1384297D01*
G01X553962Y1408495D02*
X552817Y1409640D01*
Y1412897D01*
X560512Y1451578D01*
Y1456131D01*
X559210Y1508839D01*
Y1511676D01*
X558219Y1521630D01*
X556322Y1527898D01*
X554902Y1530602D01*
X553427Y1533409D01*
X546412Y1539241D01*
X542835Y1541310D01*
X520243Y1550828D01*
X514332Y1554812D01*
X512479Y1560283D01*
X512478Y1560284D01*
Y1592509D01*
X510181Y1594806D01*
X508808D01*
X508307Y1595307D01*
Y1596811D01*
G01X562802Y1384297D02*
X563947Y1385442D01*
Y1387483D01*
X557827Y1393603D01*
Y1411185D01*
X561002Y1432595D01*
X560750Y1432936D01*
X561036Y1434866D01*
X561377Y1435119D01*
X563202Y1447423D01*
Y1456210D01*
X561900Y1508886D01*
Y1511650D01*
X561073Y1521885D01*
X559000Y1528400D01*
X556400Y1534400D01*
X552000Y1538400D01*
X546093Y1542783D01*
X522800Y1553000D01*
X520900Y1554800D01*
X520030Y1560100D01*
Y1596380D01*
X518383Y1598027D01*
X517469D01*
X516969Y1597527D01*
Y1596024D01*
G01X508307Y1591693D02*
Y1593196D01*
X508807Y1593696D01*
X509721D01*
X511368Y1592049D01*
Y1560100D01*
X513400Y1554100D01*
X519712Y1549847D01*
X542340Y1540314D01*
X545775Y1538327D01*
X552547Y1532697D01*
X555290Y1527475D01*
X557125Y1521412D01*
X558100Y1511620D01*
Y1508825D01*
X559402Y1456117D01*
Y1451688D01*
X556539Y1437293D01*
X556185Y1437058D01*
X555805Y1435144D01*
X556040Y1434791D01*
X555660Y1432879D01*
X555306Y1432643D01*
X554926Y1430730D01*
X555162Y1430377D01*
X554782Y1428465D01*
X554428Y1428229D01*
X554048Y1426316D01*
X554284Y1425963D01*
X553904Y1424051D01*
X553550Y1423815D01*
X553170Y1421902D01*
X553406Y1421549D01*
X551707Y1413007D01*
Y1409640D01*
X550562Y1408495D01*
G01X526082Y1396583D02*
X527227Y1395438D01*
Y1392543D01*
X533347Y1386423D01*
Y1343753D01*
X535590Y1341510D01*
X538730Y1339627D01*
X571307Y1329745D01*
X669036Y1300100D01*
X684084Y1291081D01*
X693582Y1281583D01*
X696984Y1273370D01*
Y1259852D01*
G01X529482Y1396583D02*
X528337Y1395438D01*
Y1393003D01*
X534457Y1386883D01*
Y1344213D01*
X536278Y1342392D01*
X539184Y1340650D01*
X604206Y1320926D01*
X604205D01*
X669490Y1301123D01*
X684772Y1291963D01*
X694523Y1282212D01*
X698094Y1273591D01*
Y1259852D01*
G01X529482Y1348187D02*
X528337Y1347042D01*
Y1343463D01*
X531104Y1340696D01*
X536256Y1337608D01*
X667955Y1297658D01*
X682436Y1288978D01*
X691056Y1280358D01*
X694354Y1272396D01*
Y1259909D01*
G01X526082Y1348187D02*
X527227Y1347042D01*
Y1343003D01*
X530416Y1339814D01*
X535802Y1336585D01*
X601783Y1316569D01*
Y1316570D01*
X667501Y1296635D01*
X681748Y1288096D01*
X690115Y1279729D01*
X693244Y1272175D01*
Y1259909D01*
G01X538322Y1372385D02*
X539467Y1371240D01*
Y1368583D01*
X545587Y1362463D01*
Y1343390D01*
X547416Y1340924D01*
X547765Y1340818D01*
X547766D01*
X670571Y1303565D01*
X686421Y1294065D01*
X697072Y1283414D01*
X700724Y1274598D01*
Y1259909D01*
G01X553962Y1348187D02*
X552817Y1347042D01*
Y1344933D01*
X553350Y1344216D01*
X612955Y1326135D01*
X612956Y1326134D01*
X672559Y1308054D01*
X689438Y1297936D01*
X701669Y1285705D01*
X705575Y1276274D01*
Y1259852D01*
G01X541722Y1372385D02*
X540577Y1371240D01*
Y1369043D01*
X546697Y1362923D01*
Y1343757D01*
X548089Y1341880D01*
X671025Y1304588D01*
X687109Y1294947D01*
X698013Y1284043D01*
X701834Y1274819D01*
Y1259909D01*
G01X550562Y1348187D02*
X551707Y1347042D01*
Y1344566D01*
X552676Y1343259D01*
X672105Y1307031D01*
X688750Y1297054D01*
X700728Y1285076D01*
X704465Y1276053D01*
Y1259852D01*
G01X709315Y1259909D02*
Y1277501D01*
X705159Y1287535D01*
X691842Y1300852D01*
X674670Y1312326D01*
X649502Y1322751D01*
Y1322752D01*
X624409Y1333145D01*
X580161Y1348978D01*
X579979Y1349362D01*
X578142Y1350020D01*
X577759Y1349838D01*
X567866Y1353378D01*
X562041Y1355145D01*
X558937Y1358248D01*
Y1386883D01*
X552817Y1393003D01*
Y1395438D01*
X553962Y1396583D01*
G01X550562D02*
X551707Y1395438D01*
Y1392543D01*
X557827Y1386423D01*
Y1357788D01*
X561452Y1354163D01*
X567517Y1352323D01*
X624009Y1332109D01*
X649077Y1321725D01*
X649078Y1321724D01*
Y1321725D01*
X674144Y1311342D01*
X691134Y1299990D01*
X704218Y1286906D01*
X708205Y1277280D01*
Y1259909D01*
G01X566202Y1372385D02*
X565057Y1371240D01*
Y1369043D01*
X566378Y1367722D01*
Y1367723D01*
X676441Y1315666D01*
X694240Y1303772D01*
X708809Y1289203D01*
X713055Y1278952D01*
Y1259852D01*
G01X562802Y1372385D02*
X563947Y1371240D01*
Y1368583D01*
X565729Y1366801D01*
X565816Y1366760D01*
X675892Y1314697D01*
X693532Y1302910D01*
X707868Y1288574D01*
X711945Y1278731D01*
Y1259852D01*
G01X653212Y1068288D02*
Y1053816D01*
X651641Y1037862D01*
X652222Y1026028D01*
X653030Y984138D01*
X621706Y582561D01*
X622911Y470763D01*
X621125Y411824D01*
X608528Y254881D01*
X607112Y219506D01*
X607504Y194400D01*
X602322Y156051D01*
X602218Y149460D01*
X604284Y137825D01*
X604380Y125878D01*
X597989Y119487D01*
X588982D01*
X587837Y118342D01*
G01Y121742D02*
X588982Y120597D01*
X592812D01*
X593212Y120997D01*
X595162D01*
X595562Y120597D01*
X597529D01*
X599942Y123010D01*
Y123576D01*
X601322Y124956D01*
X601888D01*
X603266Y126334D01*
X603174Y137723D01*
X601106Y149371D01*
X601212Y156068D01*
X601211D01*
X601213Y156134D01*
X606392Y194466D01*
X606001Y219520D01*
X607419Y254948D01*
X620016Y411885D01*
X621800Y470774D01*
X620595Y582598D01*
X651919Y984171D01*
X651112Y1025990D01*
X650528Y1037889D01*
X652102Y1053871D01*
Y1068288D01*
G01X645732D02*
Y1054614D01*
X643927Y1036284D01*
Y1034736D01*
X645020Y978234D01*
X611952Y557756D01*
X612085Y545320D01*
X614861Y519629D01*
X615387Y470837D01*
X613664Y413930D01*
X601057Y256891D01*
X599517Y218424D01*
X599886Y194853D01*
X594711Y156555D01*
X594442Y139194D01*
Y137740D01*
X590362Y133660D01*
X588982D01*
X587837Y132515D01*
G01X644622Y1068288D02*
Y1054669D01*
X642817Y1036339D01*
Y1034725D01*
X643909Y978267D01*
X610841Y557794D01*
X610975Y545254D01*
X613751Y519563D01*
X614276Y470848D01*
X612555Y413991D01*
X599948Y256958D01*
X598406Y218438D01*
X598774Y194919D01*
X593602Y156638D01*
X593539Y152570D01*
X593132Y152176D01*
X593102Y150226D01*
X593496Y149820D01*
X593466Y147871D01*
X593059Y147477D01*
X593029Y145526D01*
X593423Y145120D01*
X593332Y139203D01*
Y138200D01*
X589902Y134770D01*
X588982D01*
X587837Y135915D01*
G01X595137Y111255D02*
X596282Y112400D01*
X598047D01*
X609460Y123813D01*
X619809Y148378D01*
X619751Y151877D01*
X611299Y192243D01*
X610908Y217291D01*
X612474Y256423D01*
X624851Y410630D01*
X626673Y470726D01*
X625469Y582435D01*
X656814Y984284D01*
X655687Y1042759D01*
X656952Y1055603D01*
Y1068476D01*
G01X595137Y114655D02*
X596154Y113638D01*
X596463Y113510D01*
X597587D01*
X600409Y116332D01*
Y116898D01*
X601789Y118278D01*
X602355D01*
X603733Y119656D01*
Y120222D01*
X605113Y121602D01*
X605679D01*
X608521Y124444D01*
X618695Y148593D01*
X618642Y151753D01*
X610190Y192119D01*
X609797Y217305D01*
X611365Y256490D01*
X623742Y410691D01*
X625562Y470737D01*
X624358Y582472D01*
X655703Y984317D01*
X654575Y1042803D01*
X655842Y1055658D01*
Y1068476D01*
G01X649471D02*
Y1054204D01*
X647725Y1036481D01*
X648601Y1018639D01*
X649266Y984240D01*
X617943Y582687D01*
X619149Y470800D01*
X617404Y413199D01*
X604829Y256534D01*
X603287Y217983D01*
X603651Y194629D01*
X598477Y156340D01*
X598362Y149041D01*
X600423Y137985D01*
X600569Y128597D01*
X598544Y126573D01*
X596282D01*
X595137Y125428D01*
G01X648361Y1068476D02*
Y1054259D01*
X646612Y1036508D01*
X647491Y1018601D01*
X648155Y984273D01*
X616832Y582724D01*
X618038Y470811D01*
X616295Y413260D01*
X603720Y256601D01*
X602176Y217997D01*
X602539Y194695D01*
X597368Y156423D01*
X597250Y148947D01*
X598452Y142495D01*
X598132Y142028D01*
X598490Y140110D01*
X598957Y139790D01*
X599314Y137874D01*
X599362Y134774D01*
X598968Y134368D01*
X598998Y132417D01*
X599405Y132023D01*
X599451Y129050D01*
X598084Y127683D01*
X596282D01*
X595137Y128828D01*
G01X638228Y1570434D02*
Y1568930D01*
X638729Y1568429D01*
X640102D01*
X642399Y1566132D01*
Y1556899D01*
X637414Y1551912D01*
X615468Y1537253D01*
X607881Y1529666D01*
X602090Y1515680D01*
Y1451789D01*
X605304Y1443568D01*
X611987Y1433365D01*
X631746Y1419485D01*
X645519Y1413741D01*
X646903Y1412357D01*
Y1370467D01*
X653023Y1364347D01*
Y1361244D01*
X654168Y1360099D01*
G01X629567Y1560985D02*
Y1562488D01*
X630067Y1562988D01*
X630981D01*
X632628Y1561341D01*
Y1555225D01*
X632127Y1554289D01*
X621360Y1547094D01*
X620875Y1547191D01*
X619252Y1546106D01*
X619156Y1545621D01*
X617535Y1544538D01*
X617049Y1544635D01*
X615427Y1543550D01*
X615330Y1543065D01*
X611007Y1540176D01*
X604102Y1533271D01*
X597220Y1516661D01*
Y1450718D01*
X600857Y1441410D01*
X608356Y1429961D01*
X633172Y1412504D01*
X633553Y1412123D01*
Y1394200D01*
X639673Y1388080D01*
Y1385442D01*
X638528Y1384297D01*
G01X629567Y1566103D02*
Y1564599D01*
X630068Y1564098D01*
X631441D01*
X633738Y1561801D01*
Y1554946D01*
X632975Y1553520D01*
X611715Y1539314D01*
X605043Y1532642D01*
X598330Y1516440D01*
Y1450928D01*
X601849Y1441922D01*
X609169Y1430747D01*
X633889Y1413357D01*
X634663Y1412583D01*
Y1394660D01*
X640783Y1388540D01*
Y1385442D01*
X641928Y1384297D01*
G01X650768Y1360099D02*
X651913Y1361244D01*
Y1363887D01*
X645793Y1370007D01*
Y1411897D01*
X644889Y1412801D01*
X631207Y1418507D01*
X611174Y1432578D01*
X604312Y1443056D01*
X600980Y1451579D01*
Y1515901D01*
X606940Y1530295D01*
X610135Y1533490D01*
Y1533985D01*
X611515Y1535365D01*
X612010D01*
X614760Y1538115D01*
X636706Y1552774D01*
X637875Y1553944D01*
Y1554439D01*
X639255Y1555819D01*
X639750D01*
X641289Y1557359D01*
Y1565672D01*
X639642Y1567319D01*
X638728D01*
X638228Y1566819D01*
Y1565315D01*
G01X646890Y1560985D02*
Y1562488D01*
X647390Y1562988D01*
X648304D01*
X649951Y1561341D01*
Y1555152D01*
X649385Y1554303D01*
X644864Y1551349D01*
X644379Y1551451D01*
X642746Y1550383D01*
X642644Y1549898D01*
X641012Y1548832D01*
X640528Y1548934D01*
X638894Y1547866D01*
X638793Y1547382D01*
X632176Y1543059D01*
X616952Y1534988D01*
X610128Y1528164D01*
X604740Y1515152D01*
Y1452289D01*
X607641Y1444871D01*
X614041Y1435162D01*
X632882Y1421926D01*
X650905Y1414402D01*
X651913Y1413394D01*
Y1409640D01*
X650768Y1408495D01*
G01X646890Y1566103D02*
Y1564599D01*
X647391Y1564098D01*
X648764D01*
X651061Y1561801D01*
Y1554816D01*
X650183Y1553498D01*
X632741Y1542102D01*
X617619Y1534085D01*
X611069Y1527535D01*
X605850Y1514931D01*
Y1452499D01*
X608633Y1445385D01*
X614852Y1435949D01*
X633421Y1422904D01*
X651535Y1415342D01*
X653023Y1413854D01*
Y1409640D01*
X654168Y1408495D01*
G01X672874Y1570434D02*
Y1568930D01*
X673375Y1568429D01*
X674748D01*
X677045Y1566132D01*
Y1556557D01*
X667905Y1547417D01*
X649180Y1536390D01*
X636777Y1529990D01*
X625083Y1525075D01*
X624125Y1524634D01*
X620638Y1521146D01*
X617300Y1513091D01*
Y1455578D01*
X617472Y1454755D01*
X620079Y1448791D01*
X623825Y1443479D01*
X639206Y1432842D01*
X672164Y1419074D01*
X677503Y1413673D01*
Y1409640D01*
X678648Y1408495D01*
G01X664213Y1566103D02*
Y1564599D01*
X664714Y1564098D01*
X666087D01*
X668384Y1561801D01*
Y1554847D01*
X667772Y1553550D01*
X649754Y1541510D01*
X632374Y1532221D01*
X622052Y1527881D01*
X617451Y1523280D01*
X614648Y1516515D01*
X613540Y1513841D01*
Y1454503D01*
X613700Y1454005D01*
X616311Y1447531D01*
X620502Y1441173D01*
X636635Y1429839D01*
X664524Y1418190D01*
X670214Y1414256D01*
X671383Y1413087D01*
Y1370487D01*
X677503Y1364367D01*
Y1361244D01*
X678648Y1360099D01*
G01X664213Y1560985D02*
Y1562488D01*
X664713Y1562988D01*
X665627D01*
X667274Y1561341D01*
Y1555096D01*
X666899Y1554302D01*
X661637Y1550786D01*
X661151Y1550882D01*
X659529Y1549798D01*
X659432Y1549313D01*
X657811Y1548230D01*
X657326Y1548327D01*
X655703Y1547242D01*
X655607Y1546757D01*
X649182Y1542464D01*
X631896Y1533225D01*
X621421Y1528820D01*
X616510Y1523909D01*
X613622Y1516940D01*
X612430Y1514062D01*
Y1454328D01*
X612654Y1453628D01*
X615322Y1447012D01*
X619691Y1440386D01*
X636096Y1428861D01*
X663988Y1417210D01*
X669500Y1413400D01*
X670273Y1412627D01*
Y1370027D01*
X676393Y1363907D01*
Y1361244D01*
X675248Y1360099D01*
G01X655551Y1565315D02*
Y1566819D01*
X656051Y1567319D01*
X656965D01*
X658612Y1565672D01*
Y1556638D01*
X652078Y1550104D01*
X646773Y1546559D01*
X644153Y1545166D01*
X643680Y1545311D01*
X641957Y1544395D01*
X641813Y1543921D01*
X640092Y1543006D01*
X639618Y1543151D01*
X637896Y1542234D01*
X637751Y1541761D01*
X619160Y1531877D01*
X613319Y1526037D01*
X609246Y1516204D01*
X608670Y1514813D01*
X608500Y1514403D01*
Y1453030D01*
X611397Y1446069D01*
X616867Y1437773D01*
X634269Y1425548D01*
X654684Y1417020D01*
X658033Y1413671D01*
Y1394167D01*
X664153Y1388047D01*
Y1385442D01*
X663008Y1384297D01*
G01X672874Y1565315D02*
Y1566819D01*
X673374Y1567319D01*
X674288D01*
X675935Y1565672D01*
Y1557017D01*
X667220Y1548302D01*
X662536Y1545544D01*
X662057Y1545668D01*
X660376Y1544677D01*
X660252Y1544198D01*
X658572Y1543209D01*
X658093Y1543333D01*
X656412Y1542343D01*
X656288Y1541863D01*
X648643Y1537362D01*
X636306Y1530997D01*
X632882Y1529558D01*
X632741Y1529499D01*
X624635Y1526092D01*
X623480Y1525560D01*
X623340Y1525420D01*
Y1525419D01*
X619697Y1521775D01*
X616190Y1513312D01*
Y1455463D01*
X616408Y1454415D01*
X619107Y1448243D01*
X623031Y1442678D01*
X638670Y1431862D01*
X671531Y1418135D01*
X676393Y1413216D01*
Y1409640D01*
X675248Y1408495D01*
G01X655551Y1570434D02*
Y1568930D01*
X656052Y1568429D01*
X657425D01*
X659722Y1566132D01*
Y1556178D01*
X652786Y1549242D01*
X647344Y1545604D01*
X619828Y1530975D01*
X614261Y1525409D01*
X610272Y1515779D01*
X610182Y1515562D01*
X609780Y1514591D01*
X609696Y1514388D01*
X609610Y1514182D01*
Y1453252D01*
X612382Y1446593D01*
X617678Y1438560D01*
X634808Y1426526D01*
X655314Y1417960D01*
X659143Y1414131D01*
Y1394627D01*
X665263Y1388507D01*
Y1385442D01*
X666408Y1384297D01*
G01X681535Y1560985D02*
Y1562488D01*
X682035Y1562988D01*
X682949D01*
X684596Y1561341D01*
Y1554814D01*
X683299Y1553700D01*
X678085Y1550213D01*
X677600Y1550310D01*
X675978Y1549225D01*
X675882Y1548739D01*
X674262Y1547655D01*
X673776Y1547752D01*
X672154Y1546667D01*
X672058Y1546181D01*
X667000Y1542799D01*
X640703Y1528745D01*
X625663Y1522424D01*
X622884Y1519643D01*
X619950Y1512561D01*
Y1456292D01*
X622693Y1450019D01*
X626178Y1445074D01*
X640485Y1435181D01*
X676736Y1420036D01*
X682513Y1414259D01*
Y1394087D01*
X688633Y1387967D01*
Y1385442D01*
X687488Y1384297D01*
G01X690197Y1570434D02*
Y1568930D01*
X690698Y1568429D01*
X692071D01*
X694368Y1566132D01*
Y1557598D01*
X685958Y1549188D01*
X670368Y1538744D01*
X642965Y1524410D01*
X628674Y1518405D01*
X627001Y1516732D01*
X624820Y1511585D01*
Y1457677D01*
X625529Y1455694D01*
X626958Y1452423D01*
X629665Y1448587D01*
X642836Y1439480D01*
X679917Y1423988D01*
X691699Y1416471D01*
X695863Y1412307D01*
Y1370307D01*
X701983Y1364187D01*
Y1361244D01*
X703128Y1360099D01*
G01X690197Y1565315D02*
Y1566819D01*
X690697Y1567319D01*
X691611D01*
X693258Y1565672D01*
Y1558058D01*
X685250Y1550050D01*
X681938Y1547831D01*
X681452Y1547927D01*
X679831Y1546841D01*
X679735Y1546355D01*
X678115Y1545270D01*
X677630Y1545366D01*
X676009Y1544280D01*
X675913Y1543794D01*
X669800Y1539700D01*
X642491Y1525416D01*
X628043Y1519344D01*
X626063Y1517364D01*
X623710Y1511811D01*
Y1457484D01*
X624496Y1455284D01*
X625986Y1451875D01*
X628871Y1447785D01*
X642300Y1438500D01*
X679400Y1423000D01*
X691000Y1415600D01*
X694753Y1411847D01*
Y1369847D01*
X700873Y1363727D01*
Y1361244D01*
X699728Y1360099D01*
G01X681535Y1566103D02*
Y1564599D01*
X682036Y1564098D01*
X683409D01*
X685706Y1561801D01*
Y1554304D01*
X683973Y1552814D01*
X667572Y1541846D01*
X641181Y1527741D01*
X626294Y1521485D01*
X623826Y1519014D01*
X621060Y1512340D01*
Y1456525D01*
X623665Y1450567D01*
X626972Y1445875D01*
X641021Y1436161D01*
X677366Y1420976D01*
X683623Y1414719D01*
Y1394547D01*
X689743Y1388427D01*
Y1385442D01*
X690888Y1384297D01*
G01X699728Y1408495D02*
X700873Y1409640D01*
Y1413006D01*
X697653Y1416120D01*
X697087Y1416110D01*
X695684Y1417467D01*
X695675Y1418032D01*
X692469Y1421132D01*
X671889Y1430635D01*
X671358Y1430440D01*
X669586Y1431258D01*
X669391Y1431789D01*
X667621Y1432606D01*
X667090Y1432411D01*
X665318Y1433229D01*
X665123Y1433760D01*
X663353Y1434577D01*
X662822Y1434382D01*
X661050Y1435200D01*
X660855Y1435731D01*
X659085Y1436548D01*
X658554Y1436353D01*
X656782Y1437171D01*
X656587Y1437702D01*
X654817Y1438519D01*
X654286Y1438324D01*
X652514Y1439142D01*
X652319Y1439673D01*
X650549Y1440490D01*
X650018Y1440295D01*
X648247Y1441113D01*
X648051Y1441644D01*
X643202Y1443883D01*
X636351Y1449392D01*
X632628Y1454300D01*
Y1458979D01*
X630981Y1460626D01*
X630067D01*
X629567Y1460126D01*
Y1458622D01*
G01Y1463741D02*
Y1462237D01*
X630068Y1461736D01*
X631441D01*
X633738Y1459439D01*
Y1454674D01*
X637153Y1450172D01*
X643791Y1444834D01*
X693106Y1422062D01*
X701983Y1413477D01*
Y1409640D01*
X703128Y1408495D01*
G01X638528Y1372385D02*
X639673Y1371240D01*
Y1347028D01*
X644742Y1341959D01*
X716860Y1293770D01*
X742803Y1267827D01*
X745606Y1261061D01*
Y1259909D01*
G01X654168Y1348187D02*
X653023Y1347042D01*
Y1342900D01*
X654881Y1341042D01*
X719960Y1297558D01*
X747282Y1270236D01*
X750457Y1262571D01*
Y1259852D01*
G01X650768Y1348187D02*
X651913Y1347042D01*
Y1342440D01*
X654173Y1340180D01*
X719252Y1296696D01*
X746341Y1269607D01*
X749347Y1262350D01*
Y1259852D01*
G01X641928Y1372385D02*
X640783Y1371240D01*
Y1347488D01*
X645450Y1342821D01*
X717568Y1294632D01*
X743744Y1268456D01*
X746716Y1261282D01*
Y1259909D01*
G01X654168Y1396583D02*
X653023Y1395438D01*
Y1392877D01*
X659143Y1386757D01*
Y1343956D01*
X662872Y1340227D01*
X722354Y1300482D01*
X750561Y1272275D01*
X754197Y1263497D01*
Y1259909D01*
G01X650768Y1396583D02*
X651913Y1395438D01*
Y1392417D01*
X658033Y1386297D01*
Y1343496D01*
X662164Y1339365D01*
X721646Y1299620D01*
X749620Y1271646D01*
X753087Y1263276D01*
Y1259909D01*
G01X646890Y1458622D02*
Y1460126D01*
X647390Y1460626D01*
X648304D01*
X649951Y1458979D01*
Y1450800D01*
X652135Y1448573D01*
X673898Y1438555D01*
X684339Y1434095D01*
X684497Y1433702D01*
X686291Y1432935D01*
X686685Y1433093D01*
X688598Y1432276D01*
X688835Y1431684D01*
X690630Y1430918D01*
X691220Y1431155D01*
X693013Y1430390D01*
X693250Y1429798D01*
X695045Y1429032D01*
X695635Y1429269D01*
X697428Y1428504D01*
X699197Y1427276D01*
X699310Y1426650D01*
X700913Y1425537D01*
X701540Y1425650D01*
X703141Y1424539D01*
X703254Y1423912D01*
X704857Y1422799D01*
X705484Y1422912D01*
X707085Y1421801D01*
X710914Y1418647D01*
X710976Y1418014D01*
X712482Y1416773D01*
X713115Y1416834D01*
X714620Y1415595D01*
X714681Y1414962D01*
X716187Y1413721D01*
X716821Y1413783D01*
X719233Y1411796D01*
Y1403625D01*
X718783Y1403175D01*
Y1401225D01*
X719233Y1400775D01*
Y1369867D01*
X725353Y1363747D01*
Y1361244D01*
X724208Y1360099D01*
G01X638228Y1468071D02*
Y1466567D01*
X638729Y1466066D01*
X640102D01*
X642399Y1463769D01*
Y1454108D01*
X647934Y1447588D01*
X696753Y1425115D01*
X708103Y1413870D01*
Y1394467D01*
X714223Y1388347D01*
Y1385442D01*
X715368Y1384297D01*
G01X638228Y1462953D02*
Y1464456D01*
X638728Y1464956D01*
X639642D01*
X641289Y1463309D01*
Y1453700D01*
X647247Y1446682D01*
X651059Y1444927D01*
Y1444928D01*
X651255Y1444397D01*
X653027Y1443581D01*
X653558Y1443777D01*
X655329Y1442962D01*
X655525Y1442431D01*
X657297Y1441615D01*
X657828Y1441811D01*
X659599Y1440996D01*
X659795Y1440465D01*
X661567Y1439649D01*
X662098Y1439845D01*
X663869Y1439030D01*
X664065Y1438499D01*
X665837Y1437683D01*
X666368Y1437879D01*
X668139Y1437064D01*
X668335Y1436533D01*
X670107Y1435717D01*
X670638Y1435913D01*
X696110Y1424188D01*
X698484Y1421836D01*
X698487Y1421270D01*
X699873Y1419897D01*
X700439Y1419900D01*
X701824Y1418528D01*
X701826Y1417962D01*
X703213Y1416589D01*
X703778Y1416592D01*
X706993Y1413407D01*
Y1394007D01*
X713113Y1387887D01*
Y1385442D01*
X711968Y1384297D01*
G01X646890Y1463741D02*
Y1462237D01*
X647391Y1461736D01*
X648764D01*
X651061Y1459439D01*
Y1451254D01*
X652785Y1449496D01*
X674348Y1439570D01*
X697969Y1429481D01*
X707756Y1422688D01*
X720343Y1412320D01*
Y1370327D01*
X726463Y1364207D01*
Y1361244D01*
X727608Y1360099D01*
G01X659583Y1068800D02*
Y1048297D01*
X700783Y268233D01*
X700681Y240138D01*
X701361Y196584D01*
X695964Y156638D01*
X695923Y153981D01*
X695516Y153588D01*
X695486Y151637D01*
X695880Y151231D01*
X695850Y149282D01*
X695443Y148888D01*
X695413Y146937D01*
X695807Y146531D01*
X695694Y139203D01*
Y138200D01*
X692264Y134770D01*
X691344D01*
X690199Y135915D01*
G01X660693Y1068800D02*
Y1048327D01*
X701894Y268260D01*
X701792Y240145D01*
X702473Y196518D01*
X697073Y156555D01*
X696804Y139194D01*
Y137740D01*
X692724Y133660D01*
X691344D01*
X690199Y132515D01*
G01X663322Y1068476D02*
Y1046322D01*
X663651Y1042568D01*
X704597Y267352D01*
X704491Y240195D01*
X705171Y196691D01*
X699730Y156423D01*
X699612Y148947D01*
X700711Y143048D01*
X700391Y142581D01*
X700749Y140663D01*
X701216Y140343D01*
X701676Y137874D01*
X701721Y134970D01*
X701327Y134564D01*
X701357Y132613D01*
X701764Y132219D01*
X701813Y129050D01*
X700446Y127683D01*
X698644D01*
X697499Y128828D01*
G01X664432Y1068476D02*
Y1046371D01*
X664759Y1042646D01*
X705708Y267379D01*
X705602Y240202D01*
X706283Y196625D01*
X700839Y156340D01*
X700724Y149041D01*
X702785Y137985D01*
X702931Y128597D01*
X700906Y126573D01*
X698644D01*
X697499Y125428D01*
G01X667063Y1068288D02*
Y1048739D01*
X667579Y1042859D01*
X708420Y269646D01*
X709145Y197355D01*
X703752Y157448D01*
X703554Y154809D01*
X703468Y149371D01*
X705536Y137723D01*
X705628Y126334D01*
X704250Y124956D01*
X703684D01*
X702304Y123576D01*
Y123010D01*
X699891Y120597D01*
X697941D01*
X697541Y120997D01*
X695591D01*
X695191Y120597D01*
X691344D01*
X690199Y121742D01*
G01X668173Y1068288D02*
Y1048788D01*
X668687Y1042937D01*
X709530Y269681D01*
X710256Y197286D01*
X704857Y157332D01*
X704664Y154759D01*
X704580Y149460D01*
X706646Y137825D01*
X706742Y125878D01*
X700351Y119487D01*
X691344D01*
X690199Y118342D01*
G01X663008Y1372385D02*
X664153Y1371240D01*
Y1368477D01*
X670273Y1362357D01*
Y1342140D01*
X681334Y1331079D01*
X724042Y1302542D01*
X752953Y1273631D01*
X756827Y1264279D01*
Y1259852D01*
G01X666408Y1372385D02*
X665263Y1371240D01*
Y1368937D01*
X671383Y1362817D01*
Y1342600D01*
X682042Y1331941D01*
X724750Y1303404D01*
X753894Y1274260D01*
X757937Y1264500D01*
Y1259852D01*
G01X655551Y1462953D02*
Y1464456D01*
X656051Y1464956D01*
X656965D01*
X658612Y1463309D01*
Y1452799D01*
X659946Y1451377D01*
X659930Y1450882D01*
X661265Y1449459D01*
X661759Y1449443D01*
X663675Y1447401D01*
X668661Y1445106D01*
X701419Y1431050D01*
X701603Y1430591D01*
X703396Y1429821D01*
X703855Y1430004D01*
X705647Y1429236D01*
X705831Y1428777D01*
X707624Y1428007D01*
X708083Y1428190D01*
X709875Y1427422D01*
X709900Y1427400D01*
Y1427399D01*
X711363Y1426024D01*
X711382Y1425388D01*
X712804Y1424051D01*
X713440Y1424070D01*
X714860Y1422735D01*
X714880Y1422099D01*
X716302Y1420763D01*
X716938Y1420782D01*
X718358Y1419447D01*
X718377Y1418810D01*
X719799Y1417474D01*
X720435Y1417493D01*
X721855Y1416158D01*
X721875Y1415522D01*
X723297Y1414186D01*
X723933Y1414205D01*
X725353Y1412870D01*
Y1409546D01*
X724208Y1408401D01*
G01X655551Y1468071D02*
Y1466567D01*
X656052Y1466066D01*
X657425D01*
X659722Y1463769D01*
Y1453239D01*
X664336Y1448319D01*
X669112Y1446121D01*
X710493Y1428366D01*
X726463Y1413350D01*
Y1409546D01*
X727608Y1408401D01*
G01X664213Y1463741D02*
Y1462237D01*
X664714Y1461736D01*
X666087D01*
X668384Y1459439D01*
Y1453228D01*
X673372Y1448391D01*
X714027Y1432021D01*
X732583Y1414442D01*
Y1394087D01*
X738703Y1387967D01*
Y1385442D01*
X739848Y1384297D01*
G01X664213Y1458622D02*
Y1460126D01*
X664713Y1460626D01*
X665627D01*
X667274Y1458979D01*
Y1452758D01*
X672755Y1447442D01*
X695789Y1438166D01*
X695790Y1438168D01*
X695984Y1437712D01*
X697794Y1436983D01*
X698250Y1437177D01*
X700058Y1436449D01*
X700307Y1435863D01*
X702117Y1435134D01*
X702703Y1435384D01*
X704511Y1434656D01*
X704760Y1434070D01*
X706570Y1433341D01*
X707156Y1433591D01*
X708964Y1432863D01*
X709213Y1432277D01*
X711023Y1431548D01*
X711609Y1431798D01*
X713417Y1431070D01*
Y1431069D01*
X717533Y1427170D01*
X717550Y1426534D01*
X718967Y1425192D01*
X719603Y1425210D01*
X719601Y1425209D01*
X721017Y1423868D01*
X721018Y1423869D01*
X721035Y1423233D01*
X722452Y1421891D01*
X723088Y1421908D01*
Y1421907D01*
X724501Y1420567D01*
X724503Y1420568D01*
X724520Y1419931D01*
X725937Y1418589D01*
X726573Y1418607D01*
Y1418606D01*
X727987Y1417266D01*
X727988D01*
X728005Y1416629D01*
X729422Y1415287D01*
X730058Y1415305D01*
X731473Y1413964D01*
Y1393627D01*
X737593Y1387507D01*
Y1385442D01*
X736448Y1384297D01*
G01X697499Y114655D02*
X698464Y113690D01*
X698898Y113510D01*
X699949D01*
X702690Y116251D01*
Y116817D01*
X704070Y118197D01*
X704636D01*
X706014Y119575D01*
Y120141D01*
X707394Y121521D01*
X707960D01*
X710883Y124444D01*
X721057Y148593D01*
X720965Y154087D01*
X712998Y192142D01*
X712212Y269156D01*
X671332Y1043119D01*
X670802Y1049163D01*
Y1068476D01*
G01X697499Y111255D02*
X698653Y112409D01*
X698676Y112400D01*
X700409D01*
X711822Y123813D01*
X722171Y148378D01*
X722074Y154211D01*
X714107Y192263D01*
X713322Y269191D01*
X672440Y1043197D01*
X671912Y1049212D01*
Y1068476D01*
G01X674543Y1068288D02*
Y1064958D01*
X675830Y1050086D01*
X752867Y607744D01*
X758289Y565603D01*
X759532Y458560D01*
X802785Y240542D01*
X803497Y194912D01*
X798230Y155924D01*
X798157Y150925D01*
X797700Y150481D01*
X797671Y148530D01*
X798114Y148074D01*
X798086Y146125D01*
X797629Y145681D01*
X797600Y143731D01*
X798044Y143274D01*
X797955Y137139D01*
X795587Y134770D01*
X794201D01*
X793356Y135120D01*
X792561Y135915D01*
G01X675653Y1068288D02*
Y1065006D01*
X676932Y1050229D01*
X753965Y607910D01*
X759399Y565681D01*
X760641Y458675D01*
X803894Y240660D01*
X804609Y194846D01*
X799339Y155841D01*
X799059Y136672D01*
X796047Y133660D01*
X793706D01*
X792561Y132515D01*
G01X799861Y128828D02*
X800749Y127940D01*
X801369Y127683D01*
X802300D01*
X804167Y129551D01*
X804118Y132772D01*
X803761Y133116D01*
X803731Y135067D01*
X804076Y135422D01*
X804042Y137625D01*
X803138Y142478D01*
X802612Y142838D01*
X802255Y144756D01*
X802615Y145281D01*
X801971Y148737D01*
X802091Y156357D01*
X802090D01*
X802092Y156423D01*
X807263Y194695D01*
X806541Y240936D01*
X763288Y458951D01*
X762048Y565868D01*
X756586Y608307D01*
X679578Y1050485D01*
X678283Y1065516D01*
Y1068476D01*
G01X679393D02*
Y1065564D01*
X680680Y1050628D01*
X757684Y608473D01*
X763158Y565946D01*
X764397Y459066D01*
X807650Y241054D01*
X808375Y194629D01*
X803201Y156340D01*
X803083Y148831D01*
X805151Y137736D01*
X805285Y129098D01*
X802760Y126573D01*
X801006D01*
X799861Y125428D01*
G01X682024Y1068288D02*
Y1066604D01*
X683360Y1051199D01*
X760392Y608883D01*
X765809Y566814D01*
X767052Y459302D01*
X810391Y240864D01*
X811116Y194466D01*
X805937Y156135D01*
X805841Y150116D01*
X808674Y134159D01*
X808706Y130130D01*
X807693Y127429D01*
X806638Y125790D01*
X806016Y125655D01*
X804959Y124014D01*
X805094Y123393D01*
X803295Y120597D01*
X800712D01*
X800262Y121047D01*
X798312D01*
X797862Y120597D01*
X793994D01*
X793502Y120801D01*
X792561Y121742D01*
G01X683134Y1068288D02*
Y1066653D01*
X684462Y1051342D01*
X761490Y609049D01*
X766919Y566892D01*
X768161Y459417D01*
X811500Y240982D01*
X812228Y194400D01*
X807046Y156051D01*
X806953Y150205D01*
X809784Y134261D01*
X809818Y129933D01*
X808691Y126928D01*
X803901Y119487D01*
X793706D01*
X792561Y118342D01*
G01X675248Y1348187D02*
X676393Y1347042D01*
Y1342440D01*
X687052Y1331781D01*
X726517Y1305411D01*
X756373Y1275555D01*
X760567Y1265431D01*
Y1259909D01*
G01X678648Y1348187D02*
X677503Y1347042D01*
Y1342900D01*
X687760Y1332643D01*
X727225Y1306273D01*
X757314Y1276184D01*
X761677Y1265652D01*
Y1259909D01*
G01X675248Y1396583D02*
X676393Y1395438D01*
Y1392417D01*
X682513Y1386297D01*
Y1342640D01*
X692467Y1332686D01*
X728914Y1308332D01*
X759661Y1277585D01*
X764307Y1266369D01*
Y1259852D01*
G01X678648Y1396583D02*
X677503Y1395438D01*
Y1392877D01*
X683623Y1386757D01*
Y1343100D01*
X693175Y1333548D01*
X729622Y1309194D01*
X760602Y1278214D01*
X765417Y1266590D01*
Y1259852D01*
G01X672874Y1468071D02*
Y1466567D01*
X673375Y1466066D01*
X674748D01*
X677045Y1463769D01*
Y1454984D01*
X678374Y1452550D01*
X682870Y1448653D01*
X717272Y1434767D01*
X741997Y1414554D01*
X744823Y1411728D01*
Y1369947D01*
X750943Y1363827D01*
Y1361244D01*
X752088Y1360099D01*
G01X748688D02*
X749833Y1361244D01*
Y1363367D01*
X743713Y1369487D01*
Y1411268D01*
X741251Y1413730D01*
X736447Y1417657D01*
X735814Y1417594D01*
X734303Y1418829D01*
X734239Y1419462D01*
X732730Y1420696D01*
X732096Y1420633D01*
X730586Y1421868D01*
X730522Y1422501D01*
X729013Y1423735D01*
X728380Y1423671D01*
X726869Y1424906D01*
X726805Y1425539D01*
X725296Y1426773D01*
X724663Y1426710D01*
X723152Y1427945D01*
X723088Y1428578D01*
X721579Y1429812D01*
X720946Y1429748D01*
X719435Y1430983D01*
X719371Y1431616D01*
X716700Y1433800D01*
X682282Y1447692D01*
X677495Y1451842D01*
X675935Y1454700D01*
Y1463309D01*
X674288Y1464956D01*
X673374D01*
X672874Y1464456D01*
Y1462953D01*
G01X681535Y1463741D02*
Y1462237D01*
X682036Y1461736D01*
X683409D01*
X685706Y1459439D01*
Y1454173D01*
X686931Y1451913D01*
X688659Y1450378D01*
X722605Y1436921D01*
X743445Y1419707D01*
X756257Y1406894D01*
X763183Y1390230D01*
Y1385442D01*
X764328Y1384297D01*
G01X681535Y1458622D02*
Y1460126D01*
X682035Y1460626D01*
X682949D01*
X684596Y1458979D01*
Y1453891D01*
X686047Y1451212D01*
X688068Y1449418D01*
X722033Y1435953D01*
X723713Y1434565D01*
X723774Y1433932D01*
X725278Y1432689D01*
X725912Y1432749D01*
X727415Y1431508D01*
X727475Y1430874D01*
X728980Y1429631D01*
X729613Y1429692D01*
X731116Y1428451D01*
X731176Y1427817D01*
X732681Y1426574D01*
X733314Y1426635D01*
X734817Y1425394D01*
X734877Y1424760D01*
X736382Y1423517D01*
X737015Y1423578D01*
X738518Y1422337D01*
X738578Y1421703D01*
X740083Y1420460D01*
X740716Y1420521D01*
X742697Y1418885D01*
X746618Y1414963D01*
Y1414398D01*
X747998Y1413018D01*
X748563D01*
X749942Y1411639D01*
Y1411074D01*
X751322Y1409694D01*
X751887D01*
X755316Y1406265D01*
X756064Y1404465D01*
X755848Y1403942D01*
X756597Y1402140D01*
X757120Y1401924D01*
X762073Y1390008D01*
Y1385442D01*
X760928Y1384297D01*
G01X685763Y1068476D02*
Y1063621D01*
X686470Y1060561D01*
X687387Y1049993D01*
X764111Y609446D01*
X769568Y567079D01*
X770809Y459693D01*
X814147Y241260D01*
X814878Y194441D01*
X822681Y157169D01*
X823501Y149856D01*
X823122Y147888D01*
X812651Y123034D01*
X809917Y120300D01*
X809280D01*
X807900Y118920D01*
Y118283D01*
X806522Y116905D01*
X805885D01*
X804505Y115525D01*
Y114888D01*
X803127Y113510D01*
X801746D01*
X800483Y114033D01*
X799861Y114655D01*
G01X686873Y1068476D02*
Y1063748D01*
X687570Y1060735D01*
X688489Y1050136D01*
X688490D01*
X765209Y609612D01*
X770678Y567157D01*
X771918Y459808D01*
X815256Y241378D01*
X815987Y194565D01*
X823779Y157345D01*
X824624Y149812D01*
X824190Y147564D01*
X813590Y122403D01*
X803587Y112400D01*
X801006D01*
X799861Y111255D01*
G01X690888Y1372385D02*
X689743Y1371240D01*
Y1368937D01*
X695863Y1362817D01*
Y1342600D01*
X714361Y1324102D01*
X731454Y1312680D01*
X764326Y1279808D01*
X769157Y1268146D01*
Y1259909D01*
G01X687488Y1372385D02*
X688633Y1371240D01*
Y1368477D01*
X694753Y1362357D01*
Y1342140D01*
X713653Y1323240D01*
X730746Y1311818D01*
X763385Y1279179D01*
X768047Y1267925D01*
Y1259909D01*
G01X699728Y1348187D02*
X700873Y1347042D01*
Y1343127D01*
X717676Y1326324D01*
X729376Y1318506D01*
X766961Y1280921D01*
X771787Y1269270D01*
Y1259852D01*
G01X699728Y1396583D02*
X700873Y1395438D01*
Y1392417D01*
X706993Y1386297D01*
Y1346262D01*
X708495Y1342635D01*
X723215Y1327915D01*
X729454Y1323746D01*
X771277Y1281923D01*
X779268Y1262631D01*
Y1255712D01*
G01X690197Y1462953D02*
Y1464456D01*
X690697Y1464956D01*
X691611D01*
X693258Y1463309D01*
Y1453642D01*
X696900Y1450000D01*
X724300Y1439100D01*
X738426Y1429774D01*
X739804Y1428396D01*
Y1427759D01*
X741184Y1426379D01*
X741821D01*
X743199Y1425001D01*
Y1424364D01*
X744579Y1422984D01*
X745216D01*
X746594Y1421606D01*
Y1420969D01*
X747974Y1419589D01*
X748611D01*
X749989Y1418211D01*
Y1417574D01*
X751369Y1416194D01*
X752006D01*
X758578Y1409622D01*
X760127Y1405889D01*
X759883Y1405300D01*
X760631Y1403498D01*
X761220Y1403255D01*
X761967Y1401454D01*
X761724Y1400866D01*
X762471Y1399064D01*
X763060Y1398821D01*
X763059Y1398820D01*
X763806Y1397020D01*
X763807D01*
X763564Y1396432D01*
X764311Y1394630D01*
X764900Y1394387D01*
X764898D01*
X774313Y1371696D01*
Y1361244D01*
X773168Y1360099D01*
G01X690197Y1468071D02*
Y1466567D01*
X690698Y1466066D01*
X692071D01*
X694368Y1463769D01*
Y1454102D01*
X697523Y1450947D01*
X724817Y1440090D01*
X739132Y1430639D01*
X759519Y1410251D01*
X775423Y1371918D01*
Y1361244D01*
X776568Y1360099D01*
G01X703128Y1348187D02*
X701983Y1347042D01*
Y1343587D01*
X718384Y1327186D01*
X730084Y1319368D01*
X767902Y1281550D01*
X772897Y1269491D01*
Y1259852D01*
G01X703128Y1396583D02*
X701983Y1395438D01*
Y1392877D01*
X708103Y1386757D01*
Y1346483D01*
X709436Y1343264D01*
X723923Y1328777D01*
X730162Y1324608D01*
X772218Y1282552D01*
X780378Y1262852D01*
Y1255712D01*
G01X715368Y1372385D02*
X714223Y1371240D01*
Y1368937D01*
X720343Y1362817D01*
Y1340357D01*
X777896Y1282804D01*
X787140Y1260493D01*
X788810Y1251462D01*
Y1238138D01*
X787178Y1234198D01*
Y1234078D01*
X784583Y1231483D01*
G01X711968Y1372385D02*
X713113Y1371240D01*
Y1368477D01*
X719233Y1362357D01*
Y1339897D01*
X776955Y1282175D01*
X786069Y1260176D01*
X787700Y1251360D01*
Y1238359D01*
X786152Y1234622D01*
X783798Y1232268D01*
G01X727608Y1348187D02*
X726463Y1347042D01*
Y1339555D01*
X781506Y1284512D01*
X790666Y1262402D01*
X793974Y1245823D01*
Y1233012D01*
X788361Y1219462D01*
X787536Y1218637D01*
X786512D01*
G01X724208Y1348187D02*
X725353Y1347042D01*
Y1339095D01*
X780565Y1283883D01*
X780564D01*
X785081Y1272981D01*
Y1272982D01*
X789598Y1262078D01*
X791231Y1253896D01*
X791230D01*
X792047Y1249804D01*
X792048D01*
X792864Y1245713D01*
Y1233233D01*
X787420Y1220091D01*
X787076Y1219747D01*
X786512D01*
G01X724208Y1396489D02*
X725353Y1395344D01*
Y1392323D01*
X731473Y1386203D01*
Y1346438D01*
X733227Y1342204D01*
X737071Y1338360D01*
X744069Y1333170D01*
X744141Y1332680D01*
X745709Y1331518D01*
X746198Y1331590D01*
X782476Y1304684D01*
X822375Y1278025D01*
X826118Y1274282D01*
X829290Y1266624D01*
Y1259655D01*
X826262Y1252238D01*
X820109Y1246062D01*
X818548Y1245413D01*
X789654Y1216433D01*
X788628Y1216007D01*
X786512D01*
G01X727608Y1396489D02*
X726463Y1395344D01*
Y1392783D01*
X732583Y1386663D01*
Y1346659D01*
X734168Y1342833D01*
X737798Y1339203D01*
X783116Y1305593D01*
X823083Y1278887D01*
X827059Y1274911D01*
X830400Y1266845D01*
Y1259437D01*
X827206Y1251612D01*
X820740Y1245121D01*
X819179Y1244472D01*
X790284Y1215491D01*
X788849Y1214897D01*
X786512D01*
G01X739848Y1372385D02*
X738703Y1371240D01*
Y1368937D01*
X744823Y1362817D01*
Y1345321D01*
X746410Y1341490D01*
Y1341491D01*
X791315Y1304638D01*
X825478Y1281810D01*
X830403Y1276885D01*
X834200Y1267719D01*
Y1258226D01*
X830739Y1249755D01*
X822403Y1241391D01*
X820723Y1240693D01*
X793557Y1213441D01*
X788041Y1211157D01*
X786512D01*
G01X748688Y1348187D02*
X749833Y1347042D01*
Y1344938D01*
X750716Y1343010D01*
X757384Y1337258D01*
X757431Y1336623D01*
X758909Y1335348D01*
X759543Y1335395D01*
X761019Y1334122D01*
X761066Y1333487D01*
X762543Y1332212D01*
X763178Y1332259D01*
X789428Y1309615D01*
X825571Y1285465D01*
X832718Y1278318D01*
X832717D01*
X837510Y1266749D01*
Y1259304D01*
X831671Y1245034D01*
X824716Y1238091D01*
X820069Y1236169D01*
X794902Y1211037D01*
X788838Y1208527D01*
X786512D01*
G01X736448Y1372385D02*
X737593Y1371240D01*
Y1368477D01*
X743713Y1362357D01*
Y1345100D01*
X745491Y1340808D01*
X790653Y1303745D01*
X824770Y1280948D01*
X829462Y1276256D01*
X833090Y1267498D01*
Y1258445D01*
X829795Y1250381D01*
X821772Y1242332D01*
X820092Y1241634D01*
X792927Y1214382D01*
X787820Y1212267D01*
X786512D01*
G01X764328Y1372385D02*
X763183Y1371240D01*
Y1368937D01*
X769303Y1362817D01*
Y1343498D01*
X774183Y1331717D01*
X792437Y1313463D01*
X828675Y1289249D01*
X836848Y1281076D01*
X842380Y1267722D01*
Y1258345D01*
X835286Y1240971D01*
X803624Y1209350D01*
X789913Y1203677D01*
X786612D01*
G01X776568Y1348187D02*
X775423Y1347042D01*
Y1343948D01*
X780233Y1332337D01*
X798903Y1313667D01*
X831067Y1292175D01*
X840039Y1283203D01*
X846140Y1268474D01*
Y1257544D01*
X838475Y1238836D01*
X805495Y1205856D01*
X791204Y1199936D01*
X786412D01*
G01X760928Y1372385D02*
X762073Y1371240D01*
Y1368477D01*
X768193Y1362357D01*
Y1343277D01*
X773242Y1331088D01*
X791729Y1312601D01*
X827967Y1288387D01*
X835907Y1280447D01*
X841270Y1267501D01*
Y1258563D01*
X834343Y1241598D01*
X802995Y1210292D01*
X789692Y1204787D01*
X786612D01*
G01X773168Y1348187D02*
X774313Y1347042D01*
Y1343727D01*
X779292Y1331708D01*
X798195Y1312805D01*
X830359Y1291313D01*
X839098Y1282574D01*
X845030Y1268253D01*
Y1257763D01*
X837532Y1239463D01*
X804866Y1206797D01*
X790983Y1201046D01*
X786412D01*
G01X752088Y1348187D02*
X750943Y1347042D01*
Y1345182D01*
X751625Y1343692D01*
Y1343693D01*
X790102Y1310501D01*
X826279Y1286327D01*
X833659Y1278947D01*
X838620Y1266970D01*
Y1259085D01*
X832614Y1244406D01*
X825345Y1237149D01*
X820698Y1235227D01*
X795531Y1210095D01*
X789059Y1207417D01*
X786512D01*
G01X815194Y1335150D02*
Y1335151D01*
G01X1095338Y1068288D02*
Y1064115D01*
X1091550Y1037412D01*
X1091853Y1006484D01*
X1085554Y937675D01*
X1015822Y568918D01*
X1002900Y470679D01*
X982470Y403278D01*
Y403276D01*
X982423Y403121D01*
X982422Y403118D01*
X962039Y335873D01*
X962789Y242085D01*
Y236744D01*
X961736Y225836D01*
X962198Y196331D01*
X957084Y158489D01*
X956942Y149460D01*
X959008Y137825D01*
X959104Y125878D01*
X952713Y119487D01*
X943706D01*
X942561Y118342D01*
G01X1087857Y1068288D02*
Y1064854D01*
X1087078Y1058363D01*
X1085624Y1051286D01*
X1083997Y1037711D01*
Y1032787D01*
X1084256Y1006345D01*
X1078064Y938717D01*
X1008247Y569505D01*
X995436Y472104D01*
X974947Y404508D01*
X974946Y404506D01*
X954456Y336907D01*
X955202Y246490D01*
Y237178D01*
X954133Y225367D01*
X954588Y196278D01*
X949463Y158350D01*
X949166Y139194D01*
Y137740D01*
X945086Y133660D01*
X943706D01*
X942561Y132515D01*
G01X1094228Y1068288D02*
Y1064194D01*
X1090439Y1037485D01*
X1090742Y1006529D01*
X1084453Y937829D01*
X1014725Y569094D01*
X1001811Y470914D01*
X981408Y403601D01*
X981407Y403598D01*
X981360Y403443D01*
Y403441D01*
X960927Y336033D01*
X961679Y242080D01*
Y236798D01*
X960625Y225881D01*
X961086Y196397D01*
X955975Y158572D01*
X955830Y149371D01*
X957898Y137723D01*
X957990Y126334D01*
X956237Y124581D01*
X955672D01*
X954292Y123201D01*
Y122636D01*
X952253Y120597D01*
X950303D01*
X949903Y120997D01*
X947953D01*
X947553Y120597D01*
X943706D01*
X942561Y121742D01*
G01X1086747Y1068288D02*
Y1064922D01*
X1086746Y1064921D01*
X1085981Y1058541D01*
X1084527Y1051464D01*
X1082887Y1037778D01*
Y1032781D01*
X1083145Y1006390D01*
X1076963Y938871D01*
X1059509Y846572D01*
X1059508D01*
X1042056Y754275D01*
X1042055D01*
X1007150Y569681D01*
X994347Y472339D01*
X973884Y404830D01*
X973883Y404827D01*
X953344Y337067D01*
X954092Y246485D01*
Y237229D01*
X953022Y225408D01*
X953476Y196344D01*
X948354Y158433D01*
X948301Y154975D01*
X947894Y154581D01*
X947864Y152631D01*
X948257Y152225D01*
X948227Y150276D01*
X947820Y149882D01*
X947790Y147931D01*
X948184Y147525D01*
X948056Y139203D01*
Y138200D01*
X944626Y134770D01*
X943706D01*
X942561Y135915D01*
G01X949861Y111255D02*
X951015Y112409D01*
X951038Y112400D01*
X952771D01*
X956358Y115987D01*
X958973Y119900D01*
X965129Y126056D01*
X974533Y148378D01*
X974436Y154210D01*
X965987Y194565D01*
X965501Y225685D01*
X966562Y236456D01*
Y243508D01*
X965818Y335329D01*
X1006601Y469880D01*
X1019550Y568321D01*
X1089296Y937151D01*
X1095629Y1006330D01*
X1095326Y1037243D01*
X1099077Y1061030D01*
Y1068476D01*
G01X949861Y114655D02*
X950827Y113689D01*
X951259Y113510D01*
X952311D01*
X955496Y116695D01*
X958111Y120608D01*
X964190Y126687D01*
X965162Y128996D01*
X964949Y129520D01*
X965707Y131318D01*
X966231Y131531D01*
X966988Y133328D01*
X966774Y133851D01*
X967532Y135649D01*
X968056Y135863D01*
X973419Y148593D01*
X973327Y154086D01*
X964878Y194441D01*
X964390Y225731D01*
X965452Y236511D01*
Y243503D01*
X964706Y335489D01*
X1005512Y470115D01*
X1018453Y568497D01*
X1088195Y937305D01*
X1094518Y1006375D01*
X1094215Y1037325D01*
X1097967Y1061117D01*
Y1068476D01*
G01X949861Y125428D02*
X951006Y126573D01*
X953268D01*
X955293Y128597D01*
X955147Y137985D01*
X953086Y149041D01*
X953229Y158062D01*
X958354Y195993D01*
X957897Y225203D01*
X959000Y237378D01*
Y243404D01*
X958244Y336419D01*
X978666Y403792D01*
X978667Y403795D01*
X978714Y403950D01*
Y403952D01*
X999183Y471481D01*
X1012078Y569518D01*
X1081796Y938201D01*
X1088061Y1006638D01*
X1087758Y1037473D01*
X1091597Y1064505D01*
Y1068476D01*
G01X949861Y128828D02*
X951006Y127683D01*
X952808D01*
X954175Y129050D01*
X954123Y132427D01*
X953716Y132820D01*
X953686Y134771D01*
X954079Y135177D01*
X954038Y137874D01*
X953633Y140049D01*
X953165Y140369D01*
X952808Y142287D01*
X953128Y142754D01*
X951974Y148947D01*
X952120Y158145D01*
X957242Y196059D01*
X956786Y225245D01*
X957890Y237429D01*
Y243399D01*
X957132Y336579D01*
X977604Y404115D01*
Y404117D01*
X977651Y404272D01*
X977652Y404275D01*
X998094Y471716D01*
X1010981Y569694D01*
X1080695Y938355D01*
X1082257Y955435D01*
X1082258D01*
X1086950Y1006683D01*
X1086647Y1037546D01*
X1090487Y1064584D01*
Y1068476D01*
G01X1058113Y1372385D02*
X1056968Y1371240D01*
Y1368334D01*
X1027409Y1336559D01*
X1023073Y1332223D01*
X987381Y1292842D01*
X979610Y1274084D01*
Y1248949D01*
X981863Y1243815D01*
X981862D01*
X982257Y1243661D01*
X983041Y1241874D01*
X982887Y1241479D01*
X982888Y1241480D01*
X983671Y1239695D01*
X983670Y1239694D01*
X984065Y1239540D01*
X984849Y1237753D01*
X984695Y1237358D01*
X984697D01*
X985481Y1235574D01*
X985478Y1235573D01*
X985873Y1235419D01*
X986657Y1233632D01*
X986503Y1233237D01*
X986505D01*
X987288Y1231454D01*
X987286Y1231452D01*
X987681Y1231298D01*
X988465Y1229511D01*
X988311Y1229116D01*
X988314Y1229117D01*
X989097Y1227333D01*
X989094Y1227331D01*
X989490Y1227177D01*
X990274Y1225390D01*
X990120Y1224995D01*
X990122D01*
X990905Y1223212D01*
X990903Y1223210D01*
X991299Y1223056D01*
X992083Y1221269D01*
X991929Y1220874D01*
X991930Y1220875D01*
X992714Y1219091D01*
X992712Y1219089D01*
X993108Y1218935D01*
X993892Y1217148D01*
X993738Y1216753D01*
X994521Y1214968D01*
X995189Y1214708D01*
X995807Y1213299D01*
X995547Y1212632D01*
X996330Y1210847D01*
X996725Y1210693D01*
X997510Y1208906D01*
X997356Y1208511D01*
X998139Y1206726D01*
X998141Y1206722D01*
X1012332Y1191870D01*
X1021076Y1188719D01*
X1047810Y1186086D01*
X1054588D01*
G01X1054713Y1372385D02*
X1055858Y1371240D01*
Y1368771D01*
X1026610Y1337330D01*
X1022269Y1332989D01*
X986429Y1293445D01*
X978500Y1274305D01*
Y1248716D01*
X997200Y1206100D01*
X997221Y1206078D01*
Y1206077D01*
X1011710Y1190914D01*
X1020829Y1187627D01*
X1047755Y1184976D01*
X1054588D01*
G01X1066953Y1348187D02*
X1068098Y1347042D01*
Y1344946D01*
X1062111Y1338686D01*
X1002199Y1304465D01*
X989136Y1289640D01*
X982890Y1274557D01*
Y1250736D01*
X1001279Y1208393D01*
X1009989Y1198898D01*
X1014507Y1194381D01*
X1022163Y1191389D01*
X1049296Y1188716D01*
X1054588D01*
G01X1066953Y1396583D02*
X1068098Y1395438D01*
Y1392969D01*
X1074218Y1386849D01*
Y1347736D01*
X1072451Y1343225D01*
X1066331Y1336608D01*
X1005059Y1301717D01*
X992466Y1287442D01*
X986800Y1273761D01*
Y1252452D01*
X1004900Y1210800D01*
X1011572Y1203286D01*
Y1203285D01*
X1013169Y1201487D01*
X1013168D01*
X1014550Y1199931D01*
X1018178Y1197446D01*
X1023289Y1195060D01*
X1049734Y1192456D01*
X1054588D01*
G01X1070353Y1348187D02*
X1069208Y1347042D01*
Y1344500D01*
X1062802Y1337802D01*
X1002910Y1303592D01*
X990092Y1289044D01*
X984000Y1274336D01*
Y1250967D01*
X987773Y1242282D01*
X987771Y1242279D01*
X988166Y1242124D01*
X988944Y1240334D01*
X988788Y1239939D01*
X989564Y1238151D01*
X989959Y1237996D01*
X990737Y1236206D01*
X990581Y1235811D01*
X990582Y1235812D01*
X991359Y1234025D01*
X991357Y1234023D01*
X991752Y1233867D01*
X992530Y1232078D01*
X992374Y1231683D01*
X992375D01*
X993151Y1229896D01*
X993150Y1229895D01*
X993545Y1229739D01*
X994322Y1227950D01*
X994167Y1227555D01*
X994168D01*
X994944Y1225767D01*
X994943D01*
X995338Y1225611D01*
X996115Y1223822D01*
X995960Y1223427D01*
X995961D01*
X996737Y1221639D01*
X996736D01*
X997131Y1221483D01*
X997908Y1219694D01*
X997753Y1219299D01*
X998529Y1217511D01*
X998924Y1217355D01*
X999701Y1215566D01*
X999546Y1215171D01*
X1000322Y1213383D01*
X1000716Y1213227D01*
X1001494Y1211438D01*
X1001339Y1211043D01*
X1002223Y1209006D01*
Y1209007D01*
X1010791Y1199666D01*
X1015128Y1195331D01*
X1022424Y1192479D01*
X1049351Y1189826D01*
X1054588D01*
G01X1070353Y1396583D02*
X1069208Y1395438D01*
Y1393429D01*
X1075328Y1387309D01*
Y1347526D01*
X1073409Y1342625D01*
X1067030Y1335728D01*
X1064903Y1334517D01*
X1064791Y1334108D01*
X1063095Y1333142D01*
X1062686Y1333254D01*
X1060992Y1332290D01*
X1060880Y1331880D01*
X1059184Y1330914D01*
X1058775Y1331027D01*
X1057081Y1330063D01*
X1056969Y1329653D01*
X1055273Y1328687D01*
X1054864Y1328800D01*
X1005770Y1300843D01*
X993421Y1286846D01*
X987910Y1273540D01*
Y1252683D01*
X996782Y1232268D01*
X996781Y1232267D01*
X997176Y1232111D01*
X997954Y1230322D01*
X997798Y1229927D01*
X997799D01*
X998576Y1228140D01*
X998575Y1228139D01*
X998970Y1227983D01*
X999748Y1226194D01*
X999592Y1225799D01*
X999593D01*
X1000370Y1224011D01*
X1000369D01*
X1000764Y1223855D01*
X1001542Y1222066D01*
X1001386Y1221671D01*
X1001387D01*
X1002164Y1219883D01*
X1002163D01*
X1002558Y1219727D01*
X1003336Y1217938D01*
X1003180Y1217543D01*
X1003181D01*
X1003958Y1215755D01*
X1003957D01*
X1004352Y1215600D01*
X1005130Y1213810D01*
X1004975Y1213415D01*
X1005848Y1211405D01*
X1008026Y1208952D01*
X1008449Y1208927D01*
X1009745Y1207468D01*
X1009720Y1207044D01*
X1011014Y1205586D01*
X1011438Y1205561D01*
X1012733Y1204102D01*
X1012708Y1203679D01*
X1013999Y1202225D01*
X1013998D01*
X1015290Y1200770D01*
X1018731Y1198414D01*
X1023587Y1196147D01*
X1049789Y1193566D01*
X1054588D01*
G01X1079193Y1372385D02*
X1080338Y1371240D01*
Y1368771D01*
X1086458Y1362651D01*
Y1347257D01*
X1084790Y1343380D01*
X1079267Y1338145D01*
X1007752Y1298698D01*
X996132Y1285706D01*
X993372Y1279041D01*
X993370D01*
X990600Y1272350D01*
Y1253362D01*
X1008600Y1213100D01*
X1017537Y1202589D01*
X1018868Y1201735D01*
X1020152Y1200911D01*
X1022918Y1199838D01*
X1031683Y1198974D01*
X1050406Y1196196D01*
X1054588D01*
G01X1082593Y1372385D02*
X1081448Y1371240D01*
Y1369231D01*
X1087568Y1363111D01*
Y1347028D01*
X1085720Y1342731D01*
X1079928Y1337241D01*
X1008454Y1297817D01*
X997086Y1285106D01*
X991710Y1272129D01*
Y1253599D01*
X994853Y1246570D01*
X995249Y1246418D01*
X996046Y1244637D01*
X995895Y1244241D01*
X996690Y1242461D01*
X997086Y1242309D01*
X997883Y1240528D01*
X997732Y1240132D01*
X998527Y1238352D01*
X998923Y1238200D01*
X999720Y1236419D01*
X999569Y1236023D01*
X1000364Y1234243D01*
X1000760Y1234091D01*
X1001557Y1232310D01*
X1001406Y1231914D01*
X1002201Y1230134D01*
X1002597Y1229982D01*
X1003394Y1228201D01*
X1003243Y1227805D01*
X1004038Y1226025D01*
X1004434Y1225873D01*
X1005231Y1224092D01*
X1005080Y1223696D01*
X1005875Y1221916D01*
X1006271Y1221764D01*
X1007068Y1219983D01*
X1006917Y1219587D01*
X1007712Y1217807D01*
X1008108Y1217655D01*
X1008905Y1215874D01*
X1008754Y1215478D01*
X1009549Y1213698D01*
X1012444Y1210293D01*
X1012867Y1210258D01*
X1014132Y1208772D01*
X1014097Y1208349D01*
X1015360Y1206864D01*
X1015783Y1206829D01*
X1017048Y1205343D01*
X1017013Y1204920D01*
X1017645Y1204177D01*
Y1204178D01*
X1017646Y1204176D01*
X1018276Y1203435D01*
X1020658Y1201906D01*
X1023178Y1200928D01*
X1031819Y1200076D01*
X1050488Y1197306D01*
X1054588D01*
G01X1094833Y1348187D02*
X1093688Y1347042D01*
Y1344700D01*
X1093180Y1343757D01*
X1085283Y1335748D01*
X1032607Y1306381D01*
X1032491Y1305973D01*
X1030787Y1305022D01*
X1030379Y1305138D01*
X1028676Y1304189D01*
X1028560Y1303781D01*
X1026856Y1302831D01*
X1026448Y1302947D01*
X1010996Y1294332D01*
X1000040Y1282027D01*
X995500Y1271066D01*
Y1256149D01*
X1000255Y1244562D01*
X1007267Y1231251D01*
X1007672Y1231125D01*
X1008582Y1229399D01*
X1008457Y1228994D01*
X1009365Y1227269D01*
X1009770Y1227143D01*
X1010680Y1225417D01*
X1010555Y1225012D01*
X1011463Y1223287D01*
X1012044Y1223106D01*
X1012832Y1221611D01*
X1012653Y1221030D01*
X1013561Y1219305D01*
X1014120Y1219131D01*
X1014924Y1217607D01*
X1014750Y1217048D01*
X1016002Y1214671D01*
X1017422Y1213276D01*
X1017846Y1213280D01*
X1019238Y1211912D01*
X1019242Y1211488D01*
X1020632Y1210122D01*
X1021056Y1210126D01*
X1022448Y1208758D01*
X1022452Y1208334D01*
X1024445Y1206353D01*
X1051115Y1201047D01*
X1054588D01*
G01X1091433Y1396583D02*
X1092578Y1395438D01*
Y1392969D01*
X1098698Y1386849D01*
Y1345346D01*
X1098140Y1344144D01*
X1088929Y1334242D01*
X1012403Y1291739D01*
X1002485Y1280616D01*
X998190Y1270246D01*
Y1256761D01*
X1003000Y1245400D01*
X1010924Y1230748D01*
X1010923D01*
X1018816Y1216157D01*
X1023572Y1211446D01*
X1025411Y1210690D01*
X1032287D01*
X1034153Y1210223D01*
X1039586Y1207317D01*
X1050602Y1203677D01*
X1054488D01*
G01X1091433Y1348187D02*
X1092578Y1347042D01*
Y1344980D01*
X1092277Y1344424D01*
X1084603Y1336641D01*
X1010291Y1295211D01*
X999086Y1282625D01*
X994390Y1271287D01*
Y1255930D01*
X999247Y1244091D01*
X1007146Y1229098D01*
X1015100Y1214000D01*
X1015223Y1213879D01*
X1015224D01*
X1021674Y1207543D01*
X1021673D01*
X1023899Y1205329D01*
X1051005Y1199937D01*
X1054588D01*
G01X1094833Y1396583D02*
X1093688Y1395438D01*
Y1393429D01*
X1099808Y1387309D01*
Y1345100D01*
X1099073Y1343517D01*
X1089622Y1333357D01*
X1030013Y1300249D01*
X1029897Y1299842D01*
X1028191Y1298894D01*
X1027783Y1299010D01*
X1026079Y1298064D01*
X1025963Y1297656D01*
X1024257Y1296709D01*
X1023849Y1296825D01*
X1013107Y1290859D01*
X1003439Y1280018D01*
X999300Y1270025D01*
Y1256988D01*
X1004002Y1245881D01*
X1006623Y1241036D01*
X1007029Y1240914D01*
X1007958Y1239198D01*
X1007837Y1238792D01*
X1008764Y1237077D01*
X1009170Y1236955D01*
X1010099Y1235239D01*
X1009978Y1234833D01*
X1010905Y1233118D01*
X1011311Y1232997D01*
X1012240Y1231280D01*
X1012119Y1230874D01*
X1013046Y1229159D01*
X1013555Y1229007D01*
X1014412Y1227424D01*
X1014260Y1226915D01*
X1015187Y1225200D01*
X1015631Y1225068D01*
X1016533Y1223400D01*
X1016401Y1222956D01*
X1017328Y1221241D01*
X1017825Y1221093D01*
X1018690Y1219494D01*
X1018542Y1218997D01*
X1019714Y1216830D01*
X1024198Y1212390D01*
X1025631Y1211800D01*
X1027624D01*
X1028074Y1212250D01*
X1030024D01*
X1030474Y1211800D01*
X1032424D01*
X1034556Y1211267D01*
X1040025Y1208341D01*
X1050781Y1204787D01*
X1054488D01*
G01X1107073Y1372385D02*
X1105928Y1371240D01*
Y1369231D01*
X1112048Y1363111D01*
Y1345500D01*
X1111455Y1344420D01*
X1087049Y1326250D01*
X1082695Y1323888D01*
X1082537Y1323354D01*
X1080723Y1322369D01*
X1080189Y1322528D01*
X1015477Y1287418D01*
X1006711Y1277686D01*
X1003110Y1268992D01*
Y1257735D01*
X1007483Y1247851D01*
X1009114Y1245390D01*
X1009610Y1245289D01*
X1010790Y1243509D01*
X1010689Y1243013D01*
X1011766Y1241388D01*
X1012280Y1241284D01*
X1013280Y1239776D01*
X1013176Y1239262D01*
X1014253Y1237637D01*
X1014807Y1237525D01*
X1015886Y1235898D01*
X1015773Y1235344D01*
X1016850Y1233719D01*
X1017404Y1233607D01*
X1018483Y1231980D01*
X1018370Y1231427D01*
X1019448Y1229801D01*
X1019447D01*
X1020001Y1229689D01*
X1021080Y1228062D01*
X1020967Y1227508D01*
X1020968D01*
X1022045Y1225884D01*
X1022044Y1225883D01*
X1022599Y1225771D01*
X1023677Y1224145D01*
X1023565Y1223590D01*
X1025908Y1220053D01*
X1025910Y1220051D01*
X1028565Y1218627D01*
X1030265Y1218200D01*
X1035325D01*
X1036660Y1217935D01*
X1045482Y1211391D01*
X1052049Y1208670D01*
X1052767Y1208527D01*
X1054388D01*
G01X1103673Y1372385D02*
X1104818Y1371240D01*
Y1368771D01*
X1110938Y1362651D01*
Y1345785D01*
X1110598Y1345166D01*
X1086450Y1327188D01*
X1014780Y1288303D01*
X1005758Y1278288D01*
X1002000Y1269213D01*
Y1257500D01*
X1006505Y1247316D01*
X1025136Y1219206D01*
X1028161Y1217583D01*
X1030128Y1217090D01*
X1035215D01*
X1035338Y1217065D01*
X1036199Y1216894D01*
X1044930Y1210417D01*
X1051725Y1207602D01*
X1052657Y1207417D01*
X1054388D01*
G01X1115913Y1348187D02*
X1117058Y1347042D01*
Y1345182D01*
X1116460Y1344079D01*
X1087138Y1322458D01*
X1017355Y1285332D01*
X1009074Y1276211D01*
X1005790Y1268282D01*
Y1259527D01*
X1010193Y1248877D01*
X1021641Y1235484D01*
X1024942Y1232551D01*
X1024943D01*
X1040907Y1218371D01*
X1048679Y1213176D01*
X1052947Y1211157D01*
X1054017D01*
G01X1119313Y1348187D02*
X1118168Y1347042D01*
Y1344900D01*
X1117319Y1343332D01*
X1117318D01*
X1087731Y1321516D01*
X1031514Y1291607D01*
X1031382Y1291176D01*
X1029428Y1290135D01*
X1028997Y1290267D01*
X1027276Y1289352D01*
X1027151Y1288942D01*
X1025169Y1287887D01*
X1024759Y1288012D01*
X1023038Y1287097D01*
X1022913Y1286687D01*
X1020930Y1285632D01*
X1020521Y1285757D01*
X1018048Y1284442D01*
X1010026Y1275608D01*
X1006900Y1268061D01*
Y1259748D01*
X1011152Y1249465D01*
X1012419Y1247983D01*
X1013053Y1247934D01*
X1014321Y1246450D01*
X1014271Y1245816D01*
X1015538Y1244334D01*
X1016172Y1244285D01*
X1017440Y1242801D01*
X1017390Y1242167D01*
X1018657Y1240685D01*
X1019291Y1240636D01*
X1020559Y1239152D01*
X1020509Y1238518D01*
X1022436Y1236264D01*
X1023893Y1234970D01*
X1024455Y1235003D01*
X1025992Y1233637D01*
X1026025Y1233076D01*
X1041588Y1219252D01*
X1049228Y1214145D01*
X1053197Y1212267D01*
X1054017D01*
G01X1115913Y1396583D02*
X1117058Y1395438D01*
Y1392969D01*
X1123178Y1386849D01*
Y1344444D01*
X1122261Y1342931D01*
X1086927Y1317595D01*
X1019462Y1281855D01*
X1012414Y1274107D01*
X1009600Y1267312D01*
Y1260277D01*
X1013047Y1252006D01*
X1022916Y1240560D01*
Y1240559D01*
X1025302Y1237792D01*
X1025357Y1237743D01*
X1025358D01*
X1038257Y1226332D01*
X1040093Y1225105D01*
X1040094D01*
X1040959Y1224527D01*
X1041823Y1223950D01*
X1042731Y1223205D01*
X1042730D01*
X1042732Y1223204D01*
X1043639Y1222461D01*
X1047690Y1218410D01*
X1049567Y1217155D01*
X1053792Y1214897D01*
X1054488D01*
G01X1119313Y1396583D02*
X1118168Y1395438D01*
Y1393429D01*
X1124288Y1387309D01*
Y1344134D01*
X1123094Y1342161D01*
X1087513Y1316649D01*
X1039690Y1291314D01*
X1039549Y1290856D01*
X1037629Y1289838D01*
X1037171Y1289979D01*
X1035448Y1289067D01*
X1035261Y1288459D01*
X1033537Y1287545D01*
X1032929Y1287732D01*
X1031206Y1286820D01*
X1031081Y1286413D01*
X1029093Y1285360D01*
X1028687Y1285485D01*
X1020153Y1280964D01*
X1013366Y1273503D01*
X1010710Y1267091D01*
Y1260500D01*
X1014004Y1252597D01*
X1016017Y1250262D01*
X1016018D01*
X1016511Y1250225D01*
X1017785Y1248747D01*
X1017749Y1248254D01*
X1019022Y1246778D01*
X1019515Y1246741D01*
X1020790Y1245263D01*
X1020753Y1244769D01*
X1022026Y1243293D01*
X1022519Y1243256D01*
X1023794Y1241778D01*
X1023757Y1241285D01*
Y1241284D01*
X1026094Y1238574D01*
X1038937Y1227214D01*
X1042485Y1224843D01*
X1044385Y1223285D01*
X1048398Y1219272D01*
X1050139Y1218109D01*
X1054071Y1216007D01*
X1054488D01*
G01X1052223Y111255D02*
X1053368Y112400D01*
X1055133D01*
X1066546Y123813D01*
X1076895Y148378D01*
X1076837Y151877D01*
X1068385Y192243D01*
X1067994Y217291D01*
X1069560Y256423D01*
X1081937Y410630D01*
X1083759Y470726D01*
X1082555Y582435D01*
X1113900Y984284D01*
X1112773Y1042759D01*
X1114038Y1055603D01*
Y1068476D01*
G01X1052223Y114655D02*
X1053240Y113638D01*
X1053549Y113510D01*
X1054673D01*
X1057495Y116332D01*
Y116898D01*
X1058875Y118278D01*
X1059441D01*
X1060819Y119656D01*
Y120222D01*
X1062199Y121602D01*
X1062765D01*
X1065607Y124444D01*
X1075781Y148593D01*
X1075728Y151753D01*
X1067276Y192119D01*
X1066883Y217305D01*
X1068451Y256490D01*
X1080828Y410691D01*
X1082648Y470737D01*
X1081444Y582472D01*
X1112789Y984317D01*
X1111661Y1042803D01*
X1112928Y1055658D01*
Y1068476D01*
G01X1110298Y1068288D02*
Y1053816D01*
X1108727Y1037862D01*
X1109308Y1026028D01*
X1110116Y984138D01*
X1078792Y582561D01*
X1079997Y470763D01*
X1078211Y411824D01*
X1065614Y254881D01*
X1064198Y219506D01*
X1064590Y194400D01*
X1059408Y156051D01*
X1059304Y149460D01*
X1061370Y137825D01*
X1061466Y125878D01*
X1055075Y119487D01*
X1046068D01*
X1044923Y118342D01*
G01X1106557Y1068476D02*
Y1054204D01*
X1104811Y1036481D01*
X1105687Y1018639D01*
X1106352Y984240D01*
X1075029Y582687D01*
X1076235Y470800D01*
X1074490Y413199D01*
X1061915Y256534D01*
X1060373Y217983D01*
X1060737Y194629D01*
X1055563Y156340D01*
X1055448Y149041D01*
X1057509Y137985D01*
X1057655Y128597D01*
X1055630Y126573D01*
X1053368D01*
X1052223Y125428D01*
G01X1105447Y1068476D02*
Y1054259D01*
X1103698Y1036508D01*
X1104577Y1018601D01*
X1105241Y984273D01*
X1073918Y582724D01*
X1075124Y470811D01*
X1073381Y413260D01*
X1060806Y256601D01*
X1059262Y217997D01*
X1059625Y194695D01*
X1054454Y156423D01*
X1054336Y148947D01*
X1055538Y142495D01*
X1055218Y142028D01*
X1055576Y140110D01*
X1056043Y139790D01*
X1056400Y137874D01*
X1056448Y134774D01*
X1056054Y134368D01*
X1056084Y132417D01*
X1056491Y132023D01*
X1056537Y129050D01*
X1055170Y127683D01*
X1053368D01*
X1052223Y128828D01*
G01X1102818Y1068288D02*
Y1054614D01*
X1101013Y1036284D01*
Y1034736D01*
X1102106Y978234D01*
X1069038Y557756D01*
X1069171Y545320D01*
X1071947Y519629D01*
X1072473Y470837D01*
X1070750Y413930D01*
X1058143Y256891D01*
X1056603Y218424D01*
X1056972Y194853D01*
X1051797Y156555D01*
X1051528Y139194D01*
Y137740D01*
X1047448Y133660D01*
X1046068D01*
X1044923Y132515D01*
G01Y121742D02*
X1046068Y120597D01*
X1049898D01*
X1050298Y120997D01*
X1052248D01*
X1052648Y120597D01*
X1054615D01*
X1057028Y123010D01*
Y123576D01*
X1058408Y124956D01*
X1058974D01*
X1060352Y126334D01*
X1060260Y137723D01*
X1058192Y149371D01*
X1058298Y156068D01*
X1058297D01*
X1058299Y156134D01*
X1063478Y194466D01*
X1063087Y219520D01*
X1064505Y254948D01*
X1077102Y411885D01*
X1078886Y470774D01*
X1077681Y582598D01*
X1109005Y984171D01*
X1108198Y1025990D01*
X1107614Y1037889D01*
X1109188Y1053871D01*
Y1068288D01*
G01X1101708D02*
Y1054669D01*
X1099903Y1036339D01*
Y1034725D01*
X1100995Y978267D01*
X1067927Y557794D01*
X1068061Y545254D01*
X1070837Y519563D01*
X1071362Y470848D01*
X1069641Y413991D01*
X1057034Y256958D01*
X1055492Y218438D01*
X1055860Y194919D01*
X1050688Y156638D01*
X1050625Y152570D01*
X1050218Y152176D01*
X1050188Y150226D01*
X1050582Y149820D01*
X1050552Y147871D01*
X1050145Y147477D01*
X1050115Y145526D01*
X1050509Y145120D01*
X1050418Y139203D01*
Y138200D01*
X1046988Y134770D01*
X1046068D01*
X1044923Y135915D01*
G01X1128153Y1372385D02*
X1129298Y1371240D01*
Y1368771D01*
X1135418Y1362651D01*
Y1348002D01*
X1133765Y1343603D01*
X1059959Y1277333D01*
X1053656Y1267900D01*
X1049183Y1257101D01*
X1047590Y1249091D01*
Y1246724D01*
X1052208Y1235578D01*
X1055827Y1231959D01*
G01X1131553Y1372385D02*
X1130408Y1371240D01*
Y1369231D01*
X1136528Y1363111D01*
Y1347800D01*
X1134710Y1342958D01*
X1060805Y1276600D01*
X1054640Y1267374D01*
X1050251Y1256777D01*
X1048700Y1248981D01*
Y1246945D01*
X1053149Y1236207D01*
X1056612Y1232744D01*
G01X1140393Y1348187D02*
X1141538Y1347042D01*
Y1345298D01*
X1140386Y1343206D01*
X1064599Y1276290D01*
X1057739Y1266684D01*
X1053138Y1255577D01*
X1052082Y1250266D01*
Y1246004D01*
X1054827Y1243259D01*
G01X1143793Y1348187D02*
X1142648Y1347042D01*
Y1345012D01*
X1141266Y1342501D01*
X1065429Y1275542D01*
X1058716Y1266142D01*
X1054206Y1255253D01*
X1053192Y1250156D01*
Y1246464D01*
X1055612Y1244044D01*
G01X1054713Y1384297D02*
X1055858Y1385442D01*
Y1411000D01*
X1092000Y1477100D01*
X1101289Y1524709D01*
X1104702Y1532984D01*
X1109301Y1537105D01*
X1109328Y1537600D01*
X1110781Y1538902D01*
X1111275Y1538875D01*
X1112727Y1540176D01*
X1112754Y1540671D01*
X1114207Y1541973D01*
X1114701Y1541946D01*
X1116235Y1543321D01*
X1121169Y1545801D01*
X1121324Y1546271D01*
X1123067Y1547147D01*
X1123537Y1546992D01*
X1125279Y1547867D01*
X1125435Y1548337D01*
X1127178Y1549213D01*
X1127648Y1549058D01*
X1129390Y1549933D01*
X1129545Y1550403D01*
X1131288Y1551280D01*
X1131758Y1551125D01*
X1133500Y1552000D01*
X1135173Y1554500D01*
Y1577214D01*
X1134044Y1578343D01*
X1132350D01*
X1131850Y1577843D01*
Y1576339D01*
G01Y1581457D02*
Y1579953D01*
X1132350Y1579453D01*
X1134504D01*
X1136283Y1577674D01*
Y1554162D01*
X1134261Y1551139D01*
X1116866Y1542395D01*
X1105632Y1532326D01*
X1102358Y1524388D01*
X1093057Y1476718D01*
X1056968Y1410716D01*
Y1385442D01*
X1058113Y1384297D01*
G01X1156033Y1372385D02*
X1154888Y1371240D01*
Y1369231D01*
X1161008Y1363111D01*
Y1346875D01*
X1159144Y1343957D01*
X1072817Y1271917D01*
X1071814Y1270914D01*
X1069157Y1264499D01*
Y1259612D01*
G01X1143793Y1396583D02*
X1142648Y1395438D01*
Y1393429D01*
X1148768Y1387309D01*
Y1347500D01*
X1145761Y1341032D01*
X1069751Y1274251D01*
X1068526Y1273026D01*
X1065417Y1265519D01*
Y1259512D01*
G01X1140393Y1396583D02*
X1141538Y1395438D01*
Y1392969D01*
X1147658Y1386849D01*
Y1347746D01*
X1144853Y1341712D01*
X1068991Y1275061D01*
X1067585Y1273655D01*
X1064307Y1265740D01*
Y1259512D01*
G01X1168273Y1348187D02*
X1167128Y1347042D01*
Y1344506D01*
X1163701Y1340018D01*
X1075685Y1269384D01*
X1074789Y1268488D01*
X1072897Y1263920D01*
Y1259512D01*
G01X1164873Y1348187D02*
X1166018Y1347042D01*
Y1344882D01*
X1164458Y1342840D01*
X1164459D01*
X1162900Y1340800D01*
X1074943Y1270212D01*
X1073848Y1269117D01*
X1071787Y1264141D01*
Y1259512D01*
G01X1152633Y1372385D02*
X1153778Y1371240D01*
Y1368771D01*
X1159898Y1362651D01*
Y1347200D01*
X1159498Y1346575D01*
X1158300Y1344700D01*
X1072067Y1272737D01*
X1070873Y1271543D01*
X1068047Y1264720D01*
Y1259612D01*
G01X1066953Y1360099D02*
X1068098Y1361244D01*
Y1363031D01*
X1061978Y1369151D01*
Y1411175D01*
X1096238Y1476167D01*
X1104711Y1522600D01*
X1107850Y1530180D01*
X1117649Y1539162D01*
X1128360Y1544688D01*
X1128511Y1545159D01*
X1130245Y1546054D01*
X1130717Y1545903D01*
X1132449Y1546797D01*
X1132599Y1547269D01*
X1134333Y1548164D01*
X1134805Y1548013D01*
X1136537Y1548907D01*
X1139468Y1551838D01*
Y1552333D01*
X1140848Y1553713D01*
X1141343D01*
X1142721Y1555091D01*
X1143834Y1558669D01*
Y1581545D01*
X1142705Y1582674D01*
X1141011D01*
X1140511Y1582174D01*
Y1580670D01*
G01Y1585788D02*
Y1584284D01*
X1141011Y1583784D01*
X1143165D01*
X1144944Y1582005D01*
Y1558500D01*
X1143700Y1554500D01*
X1137200Y1548000D01*
X1118290Y1538243D01*
X1108782Y1529527D01*
X1105782Y1522284D01*
X1097300Y1475800D01*
X1063088Y1410900D01*
Y1369611D01*
X1069208Y1363491D01*
Y1361244D01*
X1070353Y1360099D01*
G01X1157834Y1585788D02*
Y1584284D01*
X1158334Y1583784D01*
X1160488D01*
X1162267Y1582005D01*
Y1557700D01*
X1160800Y1553600D01*
X1152500Y1545300D01*
X1122405Y1531387D01*
X1115495Y1524800D01*
X1112757Y1518106D01*
X1105141Y1473475D01*
X1075328Y1409500D01*
Y1393809D01*
X1081448Y1387689D01*
Y1385442D01*
X1082593Y1384297D01*
G01X1157834Y1580670D02*
Y1582174D01*
X1158334Y1582674D01*
X1160028D01*
X1161157Y1581545D01*
Y1557893D01*
X1159838Y1554209D01*
X1159837Y1554207D01*
X1158459Y1552829D01*
X1157964D01*
X1156584Y1551449D01*
Y1550954D01*
X1155206Y1549576D01*
X1154711D01*
X1153331Y1548196D01*
Y1547701D01*
X1151855Y1546225D01*
X1148769Y1544799D01*
X1148304Y1544969D01*
X1146533Y1544150D01*
X1146362Y1543686D01*
X1144592Y1542868D01*
X1144128Y1543039D01*
X1142357Y1542220D01*
X1142186Y1541755D01*
X1140416Y1540937D01*
X1139952Y1541108D01*
X1138181Y1540289D01*
X1138010Y1539824D01*
Y1539825D01*
X1121772Y1532318D01*
X1114557Y1525440D01*
X1111683Y1518413D01*
X1104071Y1473809D01*
X1074218Y1409746D01*
Y1393349D01*
X1080338Y1387229D01*
Y1385442D01*
X1079193Y1384297D01*
G01X1066953Y1408495D02*
X1068098Y1409640D01*
Y1412000D01*
X1100400Y1475100D01*
X1108144Y1520370D01*
X1111229Y1527792D01*
X1120364Y1536229D01*
X1131428Y1541516D01*
X1131593Y1541983D01*
X1133353Y1542825D01*
X1133820Y1542660D01*
X1135579Y1543500D01*
X1135744Y1543967D01*
X1137504Y1544809D01*
X1137971Y1544644D01*
X1139730Y1545484D01*
X1139895Y1545951D01*
X1141655Y1546793D01*
X1142122Y1546628D01*
X1143881Y1547468D01*
X1144046Y1547934D01*
X1145806Y1548776D01*
X1146273Y1548611D01*
X1148064Y1549467D01*
X1149297Y1550977D01*
X1149247Y1551470D01*
X1150481Y1552981D01*
X1150973Y1553031D01*
X1152496Y1554896D01*
Y1577214D01*
X1151367Y1578343D01*
X1149673D01*
X1149173Y1577843D01*
Y1576339D01*
G01Y1581457D02*
Y1579953D01*
X1149673Y1579453D01*
X1151827D01*
X1153606Y1577674D01*
Y1554500D01*
X1148767Y1548572D01*
X1120994Y1535299D01*
X1112161Y1527141D01*
X1109218Y1520059D01*
X1101466Y1474745D01*
X1069208Y1411732D01*
Y1409640D01*
X1070353Y1408495D01*
G01X1177113Y1372385D02*
X1178258Y1371240D01*
Y1368771D01*
X1184378Y1362651D01*
Y1346200D01*
X1183889Y1345000D01*
X1183400Y1343799D01*
X1180000Y1340400D01*
X1080511Y1264981D01*
X1079832Y1264302D01*
X1079267Y1262937D01*
Y1259724D01*
G01X1180513Y1372385D02*
X1179368Y1371240D01*
Y1369231D01*
X1185488Y1363111D01*
Y1345982D01*
X1184344Y1343173D01*
X1180731Y1339561D01*
X1081242Y1264142D01*
X1080773Y1263673D01*
X1080377Y1262716D01*
Y1259724D01*
G01X1164873Y1396583D02*
X1166018Y1395438D01*
Y1392969D01*
X1172138Y1386849D01*
Y1345326D01*
X1172137Y1345325D01*
X1170768Y1342862D01*
X1169400Y1340400D01*
X1077659Y1267529D01*
X1076654Y1266524D01*
X1075527Y1263803D01*
Y1259324D01*
G01X1168273Y1396583D02*
X1167128Y1395438D01*
Y1393429D01*
X1173248Y1387309D01*
Y1345037D01*
X1170264Y1339667D01*
X1078399Y1266699D01*
X1077595Y1265895D01*
X1076637Y1263582D01*
Y1259324D01*
G01X1166496Y1576339D02*
Y1577843D01*
X1166996Y1578343D01*
X1168690D01*
X1169819Y1577214D01*
Y1556500D01*
X1169200Y1553800D01*
X1164600Y1549700D01*
X1162850Y1548518D01*
X1162364Y1548611D01*
X1160748Y1547518D01*
X1160654Y1547033D01*
X1159039Y1545941D01*
X1158553Y1546035D01*
X1156936Y1544942D01*
X1156842Y1544456D01*
X1153800Y1542400D01*
X1151856Y1541519D01*
X1151393Y1541693D01*
X1149616Y1540886D01*
X1149442Y1540423D01*
X1147667Y1539618D01*
X1147203Y1539792D01*
X1145426Y1538986D01*
X1145252Y1538522D01*
X1123810Y1528796D01*
X1118028Y1523266D01*
X1115434Y1517104D01*
X1108219Y1472873D01*
X1086458Y1409787D01*
Y1369151D01*
X1092578Y1363031D01*
Y1361244D01*
X1091433Y1360099D01*
G01X1166496Y1581457D02*
Y1579953D01*
X1166996Y1579453D01*
X1169150D01*
X1170929Y1577674D01*
Y1556374D01*
X1170203Y1553207D01*
X1165284Y1548821D01*
X1154344Y1541427D01*
X1124441Y1527863D01*
X1118962Y1522623D01*
X1116509Y1516795D01*
X1109300Y1472600D01*
X1087568Y1409600D01*
Y1369611D01*
X1093688Y1363491D01*
Y1361244D01*
X1094833Y1360099D01*
G01X1175157Y1580670D02*
Y1582174D01*
X1175657Y1582674D01*
X1177351D01*
X1178480Y1581545D01*
Y1557116D01*
X1177155Y1553825D01*
X1175777Y1552447D01*
X1175282D01*
X1173902Y1551067D01*
Y1550572D01*
X1172494Y1549164D01*
X1170868Y1548088D01*
X1170383Y1548187D01*
X1168756Y1547109D01*
X1168658Y1546624D01*
Y1546625D01*
X1167031Y1545548D01*
X1166547Y1545647D01*
X1164920Y1544570D01*
X1164822Y1544085D01*
X1163196Y1543009D01*
X1162711Y1543108D01*
X1161084Y1542031D01*
X1160986Y1541546D01*
X1158466Y1539878D01*
X1158465D01*
X1155932Y1538765D01*
X1155471Y1538944D01*
X1153684Y1538158D01*
X1153505Y1537697D01*
X1126203Y1525695D01*
X1121997Y1521790D01*
X1119043Y1515507D01*
X1112200Y1471900D01*
X1092578Y1411670D01*
Y1409640D01*
X1091433Y1408495D01*
G01X1183818Y1581457D02*
Y1579953D01*
X1184318Y1579453D01*
X1186472D01*
X1188251Y1577674D01*
Y1555645D01*
X1187396Y1553587D01*
X1183876Y1550084D01*
X1163600Y1536700D01*
X1128879Y1521491D01*
X1126016Y1518332D01*
X1123800Y1514000D01*
X1117100Y1470900D01*
X1099808Y1411000D01*
Y1393809D01*
X1105928Y1387689D01*
Y1385442D01*
X1107073Y1384297D01*
G01X1183818Y1576339D02*
Y1577843D01*
X1184318Y1578343D01*
X1186012D01*
X1187141Y1577214D01*
Y1555867D01*
X1186455Y1554218D01*
X1183171Y1550950D01*
X1181288Y1549707D01*
X1180803Y1549806D01*
X1179175Y1548731D01*
X1179075Y1548246D01*
X1177448Y1547172D01*
X1176963Y1547271D01*
X1175335Y1546196D01*
X1175236Y1545711D01*
X1173609Y1544637D01*
X1173124Y1544737D01*
X1171496Y1543661D01*
X1171396Y1543176D01*
X1169769Y1542102D01*
X1169284Y1542202D01*
X1167656Y1541126D01*
X1167556Y1540641D01*
X1163068Y1537679D01*
X1128215Y1522413D01*
X1125094Y1518969D01*
X1122730Y1514347D01*
X1116013Y1471140D01*
X1098698Y1411158D01*
Y1393349D01*
X1104818Y1387229D01*
Y1385442D01*
X1103673Y1384297D01*
G01X1175157Y1585788D02*
Y1584284D01*
X1175657Y1583784D01*
X1177811D01*
X1179590Y1582005D01*
Y1556900D01*
X1178100Y1553200D01*
X1173200Y1548300D01*
X1159000Y1538900D01*
X1126821Y1524754D01*
X1122910Y1521123D01*
X1120115Y1515178D01*
X1113283Y1471640D01*
X1093688Y1411493D01*
Y1409640D01*
X1094833Y1408495D01*
G01X1116669Y1068800D02*
Y1048297D01*
X1157869Y268233D01*
X1157767Y240138D01*
X1158447Y196584D01*
X1153050Y156638D01*
X1153009Y153981D01*
X1152602Y153588D01*
X1152572Y151637D01*
X1152966Y151231D01*
X1152936Y149282D01*
X1152529Y148888D01*
X1152499Y146937D01*
X1152893Y146531D01*
X1152780Y139203D01*
Y138200D01*
X1149350Y134770D01*
X1148430D01*
X1147285Y135915D01*
G01X1117779Y1068800D02*
Y1048327D01*
X1158980Y268260D01*
X1158878Y240145D01*
X1159559Y196518D01*
X1154159Y156555D01*
X1153890Y139194D01*
Y137740D01*
X1149810Y133660D01*
X1148430D01*
X1147285Y132515D01*
G01X1120408Y1068476D02*
Y1046322D01*
X1120737Y1042568D01*
X1161683Y267352D01*
X1161577Y240195D01*
X1162257Y196691D01*
X1156816Y156423D01*
X1156698Y148947D01*
X1157797Y143048D01*
X1157477Y142581D01*
X1157835Y140663D01*
X1158302Y140343D01*
X1158762Y137874D01*
X1158807Y134970D01*
X1158413Y134564D01*
X1158443Y132613D01*
X1158850Y132219D01*
X1158899Y129050D01*
X1157532Y127683D01*
X1155730D01*
X1154585Y128828D01*
G01X1121518Y1068476D02*
Y1046371D01*
X1121845Y1042646D01*
X1162794Y267379D01*
X1162688Y240202D01*
X1163369Y196625D01*
X1157925Y156340D01*
X1157810Y149041D01*
X1159871Y137985D01*
X1160017Y128597D01*
X1157992Y126573D01*
X1155730D01*
X1154585Y125428D01*
G01X1192480Y1580670D02*
Y1582174D01*
X1192980Y1582674D01*
X1194674D01*
X1195803Y1581545D01*
Y1558117D01*
X1194746Y1555516D01*
X1192152Y1552922D01*
X1191657D01*
X1190278Y1551543D01*
Y1551048D01*
X1186383Y1547153D01*
X1184768Y1546062D01*
X1184282Y1546156D01*
X1182665Y1545064D01*
X1182571Y1544578D01*
X1180956Y1543487D01*
X1180470Y1543581D01*
X1178853Y1542489D01*
X1178759Y1542003D01*
X1177144Y1540912D01*
X1176658Y1541006D01*
X1175041Y1539914D01*
X1174947Y1539428D01*
X1171762Y1537277D01*
X1130538Y1519222D01*
X1128282Y1516741D01*
X1126931Y1514151D01*
X1110938Y1410586D01*
Y1369151D01*
X1117058Y1363031D01*
Y1361244D01*
X1115913Y1360099D01*
G01X1192480Y1585788D02*
Y1584284D01*
X1192980Y1583784D01*
X1195134D01*
X1196913Y1582005D01*
Y1557900D01*
X1195690Y1554890D01*
X1187033Y1546233D01*
X1187005D01*
X1172300Y1536300D01*
X1131200Y1518300D01*
X1129200Y1516100D01*
X1128000Y1513800D01*
X1112048Y1410500D01*
Y1369611D01*
X1118168Y1363491D01*
Y1361244D01*
X1119313Y1360099D01*
G01X1140511Y1478308D02*
Y1479812D01*
X1141011Y1480312D01*
X1142705D01*
X1143834Y1479183D01*
Y1451670D01*
X1140904Y1445996D01*
X1140298Y1445802D01*
X1139402Y1444069D01*
X1139595Y1443463D01*
X1138701Y1441731D01*
X1138095Y1441537D01*
X1137199Y1439804D01*
X1137392Y1439198D01*
X1136498Y1437466D01*
X1135892Y1437272D01*
X1134996Y1435539D01*
X1135189Y1434932D01*
X1134295Y1433200D01*
X1133756Y1433028D01*
X1132860Y1431294D01*
X1133032Y1430755D01*
X1123178Y1411670D01*
Y1393349D01*
X1129298Y1387229D01*
Y1385442D01*
X1128153Y1384297D01*
G01X1115913Y1408495D02*
X1117058Y1409640D01*
Y1412445D01*
X1126382Y1432571D01*
X1126211Y1433035D01*
X1127032Y1434806D01*
X1127497Y1434976D01*
X1128316Y1436745D01*
X1128145Y1437209D01*
X1128966Y1438980D01*
X1129431Y1439150D01*
X1130250Y1440919D01*
X1130079Y1441383D01*
X1130900Y1443154D01*
X1131365Y1443324D01*
X1132184Y1445093D01*
X1132013Y1445558D01*
X1132834Y1447328D01*
X1133298Y1447498D01*
X1135173Y1451545D01*
Y1474852D01*
X1134044Y1475981D01*
X1132350D01*
X1131850Y1475481D01*
Y1473977D01*
G01X1119313Y1408495D02*
X1118168Y1409640D01*
Y1412200D01*
X1136283Y1451300D01*
Y1475312D01*
X1134504Y1477091D01*
X1132350D01*
X1131850Y1477591D01*
Y1479095D01*
G01X1124149Y1068288D02*
Y1048739D01*
X1124665Y1042859D01*
X1165506Y269646D01*
X1166231Y197355D01*
X1160838Y157448D01*
X1160640Y154809D01*
X1160554Y149371D01*
X1162622Y137723D01*
X1162714Y126334D01*
X1161336Y124956D01*
X1160770D01*
X1159390Y123576D01*
Y123010D01*
X1156977Y120597D01*
X1155027D01*
X1154627Y120997D01*
X1152677D01*
X1152277Y120597D01*
X1148430D01*
X1147285Y121742D01*
G01X1125259Y1068288D02*
Y1048788D01*
X1125773Y1042937D01*
X1166616Y269681D01*
X1167342Y197286D01*
X1161943Y157332D01*
X1161750Y154759D01*
X1161666Y149460D01*
X1163732Y137825D01*
X1163828Y125878D01*
X1157437Y119487D01*
X1148430D01*
X1147285Y118342D01*
G01X1154585Y114655D02*
X1155550Y113690D01*
X1155984Y113510D01*
X1157035D01*
X1159776Y116251D01*
Y116817D01*
X1161156Y118197D01*
X1161722D01*
X1163100Y119575D01*
Y120141D01*
X1164480Y121521D01*
X1165046D01*
X1167969Y124444D01*
X1178143Y148593D01*
X1178051Y154087D01*
X1170084Y192142D01*
X1169298Y269156D01*
X1128418Y1043119D01*
X1127888Y1049163D01*
Y1068476D01*
G01X1154585Y111255D02*
X1155739Y112409D01*
X1155762Y112400D01*
X1157495D01*
X1168908Y123813D01*
X1179257Y148378D01*
X1179160Y154211D01*
X1171193Y192263D01*
X1170408Y269191D01*
X1129526Y1043197D01*
X1128998Y1049212D01*
Y1068476D01*
G01X1249647Y135915D02*
X1250442Y135120D01*
X1251287Y134770D01*
X1252673D01*
X1255041Y137139D01*
X1255130Y143274D01*
X1254686Y143731D01*
X1254715Y145681D01*
X1255172Y146125D01*
X1255200Y148074D01*
X1254757Y148530D01*
X1254786Y150481D01*
X1255243Y150925D01*
X1255316Y155924D01*
X1260583Y194912D01*
X1259879Y240002D01*
X1216624Y458031D01*
X1215375Y565603D01*
X1209953Y607744D01*
X1132916Y1050086D01*
X1131629Y1064958D01*
Y1068288D01*
G01X1249647Y132515D02*
X1250792Y133660D01*
X1253133D01*
X1256145Y136672D01*
X1256425Y155841D01*
X1261695Y194846D01*
X1260988Y240120D01*
X1217733Y458146D01*
X1216485Y565681D01*
X1211051Y607910D01*
X1134018Y1050229D01*
X1132739Y1065006D01*
Y1068288D01*
G01X1256947Y128828D02*
X1257835Y127940D01*
X1258455Y127683D01*
X1259386D01*
X1261253Y129551D01*
X1261214Y132078D01*
X1260756Y132521D01*
X1260726Y134472D01*
X1261169Y134929D01*
X1261128Y137625D01*
X1260275Y142203D01*
X1259866Y142483D01*
X1259509Y144401D01*
X1259789Y144809D01*
X1259057Y148737D01*
X1259177Y156357D01*
X1259176D01*
X1259178Y156423D01*
X1264349Y194695D01*
X1263635Y240396D01*
X1220380Y458422D01*
X1219134Y565868D01*
X1213672Y608307D01*
X1136664Y1050485D01*
X1135369Y1065516D01*
Y1068476D01*
G01X1256947Y125428D02*
X1258092Y126573D01*
X1259846D01*
X1262371Y129098D01*
X1262237Y137736D01*
X1260169Y148831D01*
X1260228Y152586D01*
Y152587D01*
X1260287Y156340D01*
X1265461Y194629D01*
X1264744Y240514D01*
X1221489Y458537D01*
X1220244Y565946D01*
X1214770Y608473D01*
X1137766Y1050628D01*
X1136479Y1065564D01*
Y1068476D01*
G01X1249647Y121742D02*
X1250588Y120801D01*
X1251080Y120597D01*
X1254948D01*
X1255398Y121047D01*
X1257348D01*
X1257798Y120597D01*
X1260381D01*
X1262180Y123393D01*
X1262045Y124014D01*
X1263102Y125655D01*
X1263724Y125790D01*
X1264779Y127429D01*
X1265792Y130130D01*
X1265760Y134159D01*
X1262927Y150116D01*
X1263023Y156134D01*
X1268202Y194466D01*
X1267485Y240324D01*
X1224144Y458773D01*
X1222895Y566814D01*
X1217478Y608883D01*
X1140446Y1051199D01*
X1139110Y1066604D01*
Y1068288D01*
G01X1249647Y118342D02*
X1250792Y119487D01*
X1260987D01*
X1265777Y126928D01*
X1266904Y129933D01*
X1266870Y134261D01*
X1264039Y150205D01*
X1264132Y156051D01*
X1269314Y194400D01*
X1268594Y240442D01*
X1225253Y458888D01*
X1224005Y566892D01*
X1218576Y609049D01*
X1141548Y1051342D01*
X1140220Y1066653D01*
Y1068288D01*
G01X1149173Y1473977D02*
Y1475481D01*
X1149673Y1475981D01*
X1151367D01*
X1152496Y1474852D01*
Y1451529D01*
X1150813Y1447616D01*
X1150221Y1447381D01*
X1149450Y1445588D01*
X1149686Y1444997D01*
X1148916Y1443206D01*
X1148324Y1442971D01*
X1147553Y1441178D01*
X1147789Y1440587D01*
X1147019Y1438796D01*
X1146427Y1438561D01*
X1145656Y1436768D01*
X1145892Y1436177D01*
X1145122Y1434386D01*
X1144530Y1434151D01*
X1143759Y1432358D01*
X1143995Y1431767D01*
X1143225Y1429976D01*
X1142633Y1429741D01*
X1141862Y1427948D01*
X1142098Y1427357D01*
X1141328Y1425566D01*
X1140934Y1425409D01*
X1140162Y1423617D01*
X1140319Y1423223D01*
X1135418Y1411829D01*
Y1369151D01*
X1141538Y1363031D01*
Y1361244D01*
X1140393Y1360099D01*
G01X1143793D02*
X1142648Y1361244D01*
Y1363491D01*
X1136528Y1369611D01*
Y1411600D01*
X1153606Y1451300D01*
Y1475312D01*
X1151827Y1477091D01*
X1149673D01*
X1149173Y1477591D01*
Y1479095D01*
G01X1131553Y1384297D02*
X1130408Y1385442D01*
Y1387689D01*
X1124288Y1393809D01*
Y1411400D01*
X1144944Y1451400D01*
Y1479643D01*
X1143165Y1481422D01*
X1141011D01*
X1140511Y1481922D01*
Y1483426D01*
G01X1256947Y114655D02*
X1257569Y114033D01*
X1258832Y113510D01*
X1260213D01*
X1261591Y114888D01*
Y115525D01*
X1262971Y116905D01*
X1263608D01*
X1264986Y118283D01*
Y118920D01*
X1266366Y120300D01*
X1267003D01*
X1269737Y123034D01*
X1280208Y147888D01*
X1280587Y149856D01*
X1279767Y157169D01*
X1271964Y194441D01*
X1271241Y240720D01*
X1227901Y459164D01*
X1226654Y567079D01*
X1221197Y609446D01*
X1144473Y1049993D01*
X1143556Y1060561D01*
X1142849Y1063621D01*
Y1068476D01*
G01X1256947Y111255D02*
X1258092Y112400D01*
X1260673D01*
X1270676Y122403D01*
X1281276Y147564D01*
X1281710Y149812D01*
X1280865Y157345D01*
X1273073Y194565D01*
X1272350Y240838D01*
X1229010Y459279D01*
X1227764Y567157D01*
X1222295Y609612D01*
X1145576Y1050136D01*
X1145575D01*
X1144656Y1060735D01*
X1143959Y1063748D01*
Y1068476D01*
G01X1245966Y1348187D02*
X1244821Y1347042D01*
Y1345012D01*
X1243708Y1343282D01*
X1206349Y1326154D01*
X1206202Y1325756D01*
X1204428Y1324943D01*
X1204030Y1325090D01*
X1171033Y1309962D01*
X1156667Y1295596D01*
X1147700Y1273947D01*
Y1259312D01*
G01X1242566Y1348187D02*
X1243711Y1347042D01*
Y1345339D01*
X1242950Y1344156D01*
X1170389Y1310888D01*
X1155726Y1296225D01*
X1146590Y1274168D01*
Y1259312D01*
G01X1245966Y1396583D02*
X1244821Y1395438D01*
Y1393429D01*
X1250941Y1387309D01*
Y1346211D01*
X1249694Y1342650D01*
X1243772Y1338196D01*
X1204203Y1320558D01*
X1204051Y1320162D01*
X1202269Y1319367D01*
X1201873Y1319519D01*
X1173450Y1306850D01*
X1160242Y1293642D01*
X1151440Y1272391D01*
Y1259312D01*
G01X1230326Y1372385D02*
X1231471Y1371240D01*
Y1368771D01*
X1230195Y1367495D01*
X1166780Y1313311D01*
X1152914Y1299355D01*
X1142850Y1280665D01*
Y1259312D01*
G01X1254806Y1372385D02*
X1255951Y1371240D01*
Y1368771D01*
X1262071Y1362651D01*
Y1347710D01*
X1260351Y1343321D01*
X1256965Y1339935D01*
X1175747Y1304817D01*
X1163014Y1292084D01*
X1154070Y1270491D01*
Y1259312D01*
G01X1258206Y1372385D02*
X1257061Y1371240D01*
Y1369231D01*
X1263181Y1363111D01*
Y1347500D01*
X1261300Y1342700D01*
X1257600Y1339000D01*
X1200485Y1314304D01*
X1200329Y1313910D01*
X1198538Y1313135D01*
X1198144Y1313291D01*
X1176382Y1303882D01*
X1163955Y1291455D01*
X1155180Y1270270D01*
Y1259312D01*
G01X1233726Y1372385D02*
X1232581Y1371240D01*
Y1368311D01*
X1230949Y1366679D01*
X1167536Y1312496D01*
X1153816Y1298686D01*
X1143960Y1280385D01*
Y1259312D01*
G01X1242566Y1396583D02*
X1243711Y1395438D01*
Y1392969D01*
X1249831Y1386849D01*
Y1346401D01*
X1249830Y1346400D01*
X1249293Y1344867D01*
Y1344866D01*
X1248757Y1343335D01*
X1243205Y1339159D01*
X1172810Y1307781D01*
X1159301Y1294271D01*
X1150330Y1272612D01*
Y1259312D01*
G01X1156033Y1384297D02*
X1154888Y1385442D01*
Y1387689D01*
X1148768Y1393809D01*
Y1411700D01*
X1170929Y1451600D01*
Y1475312D01*
X1169150Y1477091D01*
X1166996D01*
X1166496Y1477591D01*
Y1479095D01*
G01X1152633Y1384297D02*
X1153778Y1385442D01*
Y1387229D01*
X1147658Y1393349D01*
Y1411988D01*
X1160295Y1434741D01*
X1160159Y1435217D01*
X1161107Y1436923D01*
X1161583Y1437059D01*
X1162529Y1438763D01*
X1162393Y1439239D01*
X1163341Y1440945D01*
X1163817Y1441081D01*
X1164763Y1442785D01*
X1164627Y1443261D01*
X1165575Y1444967D01*
X1166051Y1445103D01*
X1166997Y1446807D01*
X1166861Y1447283D01*
X1167809Y1448989D01*
X1168285Y1449125D01*
X1169819Y1451888D01*
Y1474852D01*
X1168690Y1475981D01*
X1166996D01*
X1166496Y1475481D01*
Y1473977D01*
G01X1143793Y1408495D02*
X1142648Y1409640D01*
Y1412300D01*
X1162267Y1451400D01*
Y1479643D01*
X1160488Y1481422D01*
X1158334D01*
X1157834Y1481922D01*
Y1483426D01*
G01Y1478308D02*
Y1479812D01*
X1158334Y1480312D01*
X1160028D01*
X1161157Y1479183D01*
Y1451663D01*
X1158706Y1446778D01*
X1158209Y1446613D01*
X1157352Y1444906D01*
X1157517Y1444409D01*
X1141538Y1412563D01*
Y1409640D01*
X1140393Y1408495D01*
G01X1267046Y1348187D02*
X1268191Y1347042D01*
Y1345309D01*
X1267245Y1343667D01*
X1261554Y1337776D01*
X1259256Y1336208D01*
X1177931Y1301101D01*
X1166072Y1289242D01*
X1157810Y1269295D01*
Y1259312D01*
G01X1267046Y1396583D02*
X1268191Y1395438D01*
Y1392969D01*
X1274311Y1386849D01*
Y1345530D01*
X1271438Y1341113D01*
X1267556Y1337388D01*
Y1337387D01*
X1263674Y1333663D01*
X1262540Y1332919D01*
X1179967Y1297568D01*
X1169192Y1286792D01*
X1161551Y1268346D01*
Y1259312D01*
G01X1279286Y1372385D02*
X1280431Y1371240D01*
Y1368771D01*
X1286551Y1362651D01*
Y1346519D01*
X1282656Y1340285D01*
X1266429Y1329511D01*
X1181767Y1293837D01*
X1172736Y1284806D01*
X1165291Y1266832D01*
Y1259412D01*
G01X1270446Y1348187D02*
X1269301Y1347042D01*
Y1345012D01*
X1268139Y1342994D01*
X1262274Y1336922D01*
X1259794Y1335231D01*
X1198379Y1308719D01*
X1198222Y1308325D01*
X1196431Y1307551D01*
X1196037Y1307708D01*
X1178566Y1300166D01*
X1167013Y1288613D01*
X1158920Y1269074D01*
Y1259312D01*
G01X1291526Y1348187D02*
X1292671Y1347042D01*
Y1345145D01*
X1290819Y1341141D01*
X1266438Y1324283D01*
X1184334Y1290434D01*
X1175562Y1281662D01*
X1169031Y1265895D01*
Y1259412D01*
G01X1270446Y1396583D02*
X1269301Y1395438D01*
Y1393429D01*
X1275421Y1387309D01*
Y1345200D01*
X1272300Y1340400D01*
X1268325Y1336586D01*
X1264369Y1332790D01*
X1263067Y1331937D01*
X1196923Y1303619D01*
X1196765Y1303225D01*
X1194971Y1302457D01*
X1194577Y1302614D01*
X1180601Y1296631D01*
X1170133Y1286163D01*
X1162661Y1268125D01*
Y1259312D01*
G01X1294926Y1348187D02*
X1293781Y1347042D01*
Y1344900D01*
X1291700Y1340400D01*
X1266971Y1323302D01*
X1184962Y1289492D01*
X1181322Y1285852D01*
Y1285357D01*
X1179943Y1283978D01*
X1179448D01*
X1176503Y1281033D01*
X1170141Y1265674D01*
Y1259412D01*
G01X1282686Y1372385D02*
X1281541Y1371240D01*
Y1369231D01*
X1287661Y1363111D01*
Y1346200D01*
X1283470Y1339493D01*
X1266957Y1328528D01*
X1196029Y1298642D01*
X1195869Y1298249D01*
X1194071Y1297491D01*
X1193679Y1297651D01*
X1182398Y1292898D01*
X1173677Y1284177D01*
X1166401Y1266611D01*
Y1259412D01*
G01X1175157Y1478308D02*
Y1479812D01*
X1175657Y1480312D01*
X1177351D01*
X1178480Y1479183D01*
Y1451948D01*
X1176239Y1447171D01*
X1175773Y1447003D01*
X1174944Y1445236D01*
X1175112Y1444771D01*
X1174284Y1443006D01*
X1173958Y1442888D01*
X1172954Y1440752D01*
X1173072Y1440425D01*
X1159898Y1412348D01*
Y1369151D01*
X1166018Y1363031D01*
Y1361244D01*
X1164873Y1360099D01*
G01X1168273D02*
X1167128Y1361244D01*
Y1363491D01*
X1161008Y1369611D01*
Y1412100D01*
X1179590Y1451700D01*
Y1479643D01*
X1177811Y1481422D01*
X1175657D01*
X1175157Y1481922D01*
Y1483426D01*
G01X1192480Y1478308D02*
Y1479812D01*
X1192980Y1480312D01*
X1194674D01*
X1195803Y1479183D01*
Y1452008D01*
X1191210Y1444341D01*
X1190638Y1444197D01*
X1189703Y1442637D01*
X1189847Y1442066D01*
X1172138Y1412508D01*
Y1393349D01*
X1178258Y1387229D01*
Y1385442D01*
X1177113Y1384297D01*
G01X1168273Y1408495D02*
X1167128Y1409640D01*
Y1412300D01*
X1188251Y1451800D01*
Y1475312D01*
X1186472Y1477091D01*
X1184318D01*
X1183818Y1477591D01*
Y1479095D01*
G01X1164873Y1408495D02*
X1166018Y1409640D01*
Y1412579D01*
X1175828Y1430926D01*
X1175685Y1431400D01*
X1176605Y1433120D01*
X1177079Y1433264D01*
X1177998Y1434983D01*
X1177855Y1435457D01*
X1178775Y1437177D01*
X1179249Y1437321D01*
X1180168Y1439040D01*
X1180025Y1439514D01*
X1180945Y1441234D01*
X1181419Y1441378D01*
X1182338Y1443097D01*
X1182194Y1443571D01*
X1183115Y1445292D01*
X1183588Y1445435D01*
X1187141Y1452079D01*
Y1474852D01*
X1186012Y1475981D01*
X1184318D01*
X1183818Y1475481D01*
Y1473977D01*
G01X1319406Y1348187D02*
X1318261Y1347042D01*
Y1345012D01*
X1317295Y1342543D01*
X1317294Y1342540D01*
X1317200Y1342300D01*
X1310400Y1336100D01*
X1280413Y1316198D01*
X1239390Y1299446D01*
Y1299447D01*
X1239198Y1298991D01*
X1237392Y1298253D01*
X1236936Y1298444D01*
X1194139Y1280969D01*
X1185327Y1272157D01*
X1181361Y1262583D01*
Y1259612D01*
G01X1319406Y1396583D02*
X1318261Y1395438D01*
Y1393429D01*
X1324381Y1387309D01*
Y1346200D01*
X1322900Y1342300D01*
X1313500Y1333600D01*
X1280914Y1311876D01*
X1238356Y1294534D01*
X1238192Y1294143D01*
X1236385Y1293406D01*
X1235994Y1293571D01*
X1195955Y1277255D01*
X1188514Y1269814D01*
X1185102Y1261578D01*
Y1259612D01*
G01X1307166Y1372385D02*
X1306021Y1371240D01*
Y1369231D01*
X1312141Y1363111D01*
Y1346800D01*
X1309977Y1341798D01*
X1278519Y1319715D01*
X1191243Y1283873D01*
X1188687Y1281317D01*
Y1280893D01*
X1187307Y1279513D01*
X1186883D01*
X1182323Y1274953D01*
X1177621Y1263602D01*
Y1259512D01*
G01X1316006Y1396583D02*
X1317151Y1395438D01*
Y1392969D01*
X1323271Y1386849D01*
Y1346404D01*
X1321954Y1342938D01*
X1312811Y1334475D01*
X1280391Y1312862D01*
X1195328Y1278199D01*
X1187573Y1270443D01*
X1183992Y1261799D01*
Y1259612D01*
G01X1294926Y1396583D02*
X1293781Y1395438D01*
Y1393429D01*
X1299901Y1387309D01*
Y1346800D01*
X1297800Y1341600D01*
X1292587Y1334536D01*
X1274718Y1322372D01*
X1188047Y1286677D01*
X1184872Y1283502D01*
Y1283007D01*
X1183493Y1281628D01*
X1182998D01*
X1179494Y1278124D01*
X1173881Y1264572D01*
Y1259512D01*
G01X1303766Y1372385D02*
X1304911Y1371240D01*
Y1368771D01*
X1311031Y1362651D01*
Y1347030D01*
X1309082Y1342527D01*
X1277983Y1320695D01*
X1190615Y1284816D01*
X1181382Y1275582D01*
X1176511Y1263823D01*
Y1259512D01*
G01X1316006Y1348187D02*
X1317151Y1347042D01*
Y1345222D01*
X1316261Y1342949D01*
X1316260Y1342946D01*
X1309715Y1336978D01*
X1279891Y1317184D01*
X1193512Y1281912D01*
X1184386Y1272786D01*
X1180251Y1262804D01*
Y1259612D01*
G01X1331646Y1372385D02*
X1330501Y1371240D01*
Y1369231D01*
X1336621Y1363111D01*
Y1346800D01*
X1335500Y1344200D01*
X1332699Y1341200D01*
X1281705Y1307810D01*
X1244683Y1292723D01*
X1244518Y1292332D01*
X1242711Y1291595D01*
X1242320Y1291760D01*
X1197778Y1273608D01*
X1191053Y1266883D01*
X1188842Y1261546D01*
Y1259512D01*
G01X1291526Y1396583D02*
X1292671Y1395438D01*
Y1392969D01*
X1298791Y1386849D01*
Y1347017D01*
X1298790Y1347016D01*
X1296823Y1342146D01*
X1296822D01*
X1294313Y1338747D01*
Y1338746D01*
X1291805Y1335348D01*
X1274188Y1323355D01*
X1187419Y1287619D01*
X1178553Y1278753D01*
X1172771Y1264793D01*
Y1259512D01*
G01X1328246Y1372385D02*
X1329391Y1371240D01*
Y1368771D01*
X1335511Y1362651D01*
Y1347030D01*
X1334556Y1344817D01*
X1331978Y1342056D01*
X1281186Y1308798D01*
X1197151Y1274552D01*
X1190112Y1267512D01*
X1187732Y1261767D01*
Y1259512D01*
G01X1180513Y1384297D02*
X1179368Y1385442D01*
Y1387689D01*
X1173248Y1393809D01*
Y1412200D01*
X1196913Y1451700D01*
Y1479643D01*
X1195134Y1481422D01*
X1192980D01*
X1192480Y1481922D01*
Y1483426D01*
G01X1340486Y1396583D02*
X1341631Y1395438D01*
Y1392969D01*
X1347751Y1386849D01*
Y1345325D01*
X1347745Y1345313D01*
X1347075Y1343724D01*
Y1343723D01*
X1346405Y1342136D01*
X1287372Y1302284D01*
X1199794Y1266258D01*
X1195212Y1261676D01*
Y1259512D01*
G01X1343886Y1348187D02*
X1342741Y1347042D01*
Y1345012D01*
X1341300Y1342100D01*
X1313024Y1323148D01*
Y1323149D01*
X1284900Y1304300D01*
X1227052Y1280787D01*
X1226859Y1280331D01*
X1225052Y1279595D01*
X1224596Y1279788D01*
X1198973Y1269373D01*
X1193556Y1263956D01*
X1192582Y1261604D01*
Y1259324D01*
G01X1356126Y1372385D02*
X1354981Y1371240D01*
Y1369231D01*
X1361101Y1363111D01*
Y1346500D01*
X1359400Y1343500D01*
X1289819Y1296746D01*
X1218999Y1268240D01*
X1218749Y1267653D01*
X1216939Y1266925D01*
X1216354Y1267174D01*
X1203434Y1261974D01*
X1200062Y1259745D01*
Y1259412D01*
G01X1340486Y1348187D02*
X1341631Y1347042D01*
Y1345273D01*
X1341630Y1345272D01*
X1340435Y1342858D01*
X1284376Y1305286D01*
X1198347Y1270317D01*
X1192615Y1264585D01*
X1191472Y1261825D01*
Y1259324D01*
G01X1196322Y1259512D02*
Y1261216D01*
X1200422Y1265316D01*
X1208194Y1268513D01*
X1208782Y1268268D01*
X1210586Y1269010D01*
X1210831Y1269598D01*
X1287900Y1301300D01*
X1347300Y1341400D01*
X1348861Y1345100D01*
Y1387309D01*
X1342741Y1393429D01*
Y1395438D01*
X1343886Y1396583D01*
G01X1352726Y1372385D02*
X1353871Y1371240D01*
Y1368771D01*
X1359991Y1362651D01*
Y1346793D01*
X1358563Y1344276D01*
X1358562Y1344274D01*
X1289296Y1297733D01*
X1218585Y1269270D01*
X1218584D01*
X1209480Y1265605D01*
Y1265604D01*
X1202915Y1262962D01*
X1198952Y1260342D01*
Y1259412D01*
G01X1313740Y1596024D02*
Y1597528D01*
X1314240Y1598028D01*
X1315934D01*
X1317063Y1596899D01*
Y1558660D01*
X1315660Y1555120D01*
X1314265Y1553759D01*
X1313770Y1553765D01*
X1312373Y1552402D01*
X1312367Y1551907D01*
X1310301Y1549891D01*
X1308496Y1549155D01*
X1308040Y1549346D01*
X1306233Y1548609D01*
X1306042Y1548152D01*
X1293798Y1543156D01*
X1282333Y1531756D01*
X1277464Y1520072D01*
X1237591Y1412910D01*
Y1369151D01*
X1243711Y1363031D01*
Y1361244D01*
X1242566Y1360099D01*
G01X1230326Y1384297D02*
X1231471Y1385442D01*
Y1412879D01*
X1273810Y1521670D01*
X1279073Y1534136D01*
X1288703Y1543981D01*
X1288697Y1544476D01*
X1290062Y1545871D01*
X1290557Y1545876D01*
X1291920Y1547270D01*
X1296972Y1549316D01*
X1297165Y1549772D01*
X1298973Y1550505D01*
X1299429Y1550312D01*
X1301236Y1551043D01*
X1301429Y1551499D01*
X1303237Y1552232D01*
X1303693Y1552039D01*
X1307400Y1553540D01*
X1308402Y1555630D01*
Y1592568D01*
X1307273Y1593697D01*
X1305579D01*
X1305079Y1593197D01*
Y1591693D01*
G01Y1596811D02*
Y1595307D01*
X1305579Y1594807D01*
X1307733D01*
X1309512Y1593028D01*
Y1555377D01*
X1308216Y1552672D01*
X1292552Y1546328D01*
X1280014Y1533510D01*
X1274839Y1521253D01*
X1232581Y1412670D01*
Y1385442D01*
X1233726Y1384297D01*
G01X1313740Y1601142D02*
Y1599638D01*
X1314240Y1599138D01*
X1316394D01*
X1318173Y1597359D01*
Y1558448D01*
X1316605Y1554491D01*
X1310921Y1548945D01*
X1294423Y1542212D01*
X1283273Y1531125D01*
X1278497Y1519665D01*
X1238701Y1412710D01*
Y1369611D01*
X1244821Y1363491D01*
Y1361244D01*
X1245966Y1360099D01*
G01X1331063Y1596024D02*
Y1597528D01*
X1331563Y1598028D01*
X1333257D01*
X1334386Y1596899D01*
Y1558903D01*
X1333520Y1556830D01*
X1331284Y1554591D01*
X1330789Y1554590D01*
X1329411Y1553209D01*
Y1552714D01*
X1328034Y1551335D01*
X1327539Y1551334D01*
X1326160Y1549953D01*
Y1549458D01*
X1322599Y1545891D01*
X1296492Y1535021D01*
X1289309Y1527890D01*
X1285029Y1517500D01*
X1249831Y1413183D01*
Y1393349D01*
X1255951Y1387229D01*
Y1385442D01*
X1254806Y1384297D01*
G01X1331063Y1601142D02*
Y1599638D01*
X1331563Y1599138D01*
X1333717D01*
X1335496Y1597359D01*
Y1558680D01*
X1334460Y1556200D01*
X1323230Y1544950D01*
X1297120Y1534080D01*
X1290250Y1527260D01*
X1286070Y1517110D01*
X1250941Y1413000D01*
Y1393809D01*
X1257061Y1387689D01*
Y1385442D01*
X1258206Y1384297D01*
G01X1322402Y1591693D02*
Y1593197D01*
X1322902Y1593697D01*
X1324596D01*
X1325725Y1592568D01*
Y1556200D01*
X1325033Y1554333D01*
X1323289Y1552586D01*
X1322794D01*
X1321415Y1551205D01*
X1321416Y1550710D01*
X1319990Y1549282D01*
X1318189Y1548536D01*
X1317732Y1548725D01*
X1315930Y1547977D01*
X1315740Y1547520D01*
X1313939Y1546774D01*
X1313482Y1546963D01*
X1311680Y1546215D01*
X1311490Y1545757D01*
X1309689Y1545011D01*
X1309232Y1545200D01*
X1307430Y1544452D01*
X1307240Y1543995D01*
X1294931Y1538891D01*
X1285695Y1529665D01*
X1281066Y1518938D01*
X1243711Y1414614D01*
Y1409640D01*
X1242566Y1408495D01*
G01X1322402Y1596811D02*
Y1595307D01*
X1322902Y1594807D01*
X1325056D01*
X1326835Y1593028D01*
Y1556000D01*
X1325990Y1553720D01*
X1320620Y1548340D01*
X1295560Y1537950D01*
X1286630Y1529030D01*
X1282100Y1518530D01*
X1244821Y1414419D01*
Y1409640D01*
X1245966Y1408495D01*
G01X1339725Y1596811D02*
Y1595307D01*
X1340225Y1594807D01*
X1342379D01*
X1344158Y1593028D01*
Y1555460D01*
X1341820Y1552110D01*
X1325950Y1541500D01*
X1299310Y1530420D01*
X1293270Y1524370D01*
X1289190Y1514580D01*
X1263181Y1412800D01*
Y1369611D01*
X1269301Y1363491D01*
Y1361244D01*
X1270446Y1360099D01*
G01X1339725Y1591693D02*
Y1593197D01*
X1340225Y1593697D01*
X1341919D01*
X1343048Y1592568D01*
Y1555810D01*
X1341029Y1552917D01*
X1338045Y1550922D01*
X1337560Y1551019D01*
X1335938Y1549934D01*
X1335841Y1549449D01*
X1334220Y1548366D01*
X1333735Y1548462D01*
X1332113Y1547377D01*
X1332017Y1546892D01*
X1330396Y1545809D01*
X1329911Y1545905D01*
X1328289Y1544820D01*
X1328193Y1544335D01*
X1325423Y1542483D01*
X1320426Y1540405D01*
X1319968Y1540594D01*
X1318167Y1539844D01*
X1317978Y1539386D01*
X1298680Y1531361D01*
X1292329Y1525000D01*
X1288134Y1514933D01*
X1262071Y1412940D01*
Y1369151D01*
X1268191Y1363031D01*
Y1361244D01*
X1267046Y1360099D01*
G01X1270446Y1408495D02*
X1269301Y1409640D01*
Y1412810D01*
X1293448Y1514910D01*
X1296075Y1521255D01*
X1301997Y1527207D01*
X1328820Y1538350D01*
X1349716Y1552229D01*
X1352819Y1556869D01*
Y1597359D01*
X1351040Y1599138D01*
X1348886D01*
X1348386Y1599638D01*
Y1601142D01*
G01X1267046Y1408495D02*
X1268191Y1409640D01*
Y1412940D01*
X1292388Y1515252D01*
X1295133Y1521882D01*
X1301366Y1528147D01*
X1328295Y1539334D01*
X1339333Y1546666D01*
X1339431Y1547151D01*
X1341056Y1548231D01*
X1341541Y1548134D01*
X1343165Y1549212D01*
X1343263Y1549697D01*
X1344888Y1550777D01*
X1345373Y1550679D01*
X1348916Y1553032D01*
X1351709Y1557206D01*
Y1596899D01*
X1350580Y1598028D01*
X1348886D01*
X1348386Y1597528D01*
Y1596024D01*
G01X1282686Y1384297D02*
X1281541Y1385442D01*
Y1387689D01*
X1275421Y1393809D01*
Y1412882D01*
X1296953Y1513262D01*
X1299277Y1519049D01*
X1303312Y1523140D01*
X1326918Y1532890D01*
X1359299Y1551283D01*
X1361480Y1554300D01*
Y1593028D01*
X1359701Y1594807D01*
X1357547D01*
X1357047Y1595307D01*
Y1596811D01*
G01Y1591693D02*
Y1593197D01*
X1357547Y1593697D01*
X1359241D01*
X1360370Y1592568D01*
Y1554660D01*
X1358540Y1552130D01*
X1352294Y1548582D01*
X1351817Y1548714D01*
X1350120Y1547749D01*
X1349989Y1547272D01*
X1348294Y1546309D01*
X1347817Y1546441D01*
X1346120Y1545477D01*
X1345989Y1545000D01*
X1344294Y1544037D01*
X1343817Y1544169D01*
X1342120Y1543205D01*
X1341989Y1542728D01*
X1340294Y1541765D01*
X1339817Y1541897D01*
X1338120Y1540933D01*
X1337989Y1540456D01*
X1326430Y1533890D01*
X1302680Y1524080D01*
X1298330Y1519670D01*
X1295887Y1513588D01*
X1274311Y1413000D01*
Y1393349D01*
X1280431Y1387229D01*
Y1385442D01*
X1279286Y1384297D01*
G01X1297687Y-33656D02*
X1298832Y-32511D01*
X1311582D01*
X1313518Y-34447D01*
X1316311Y-50278D01*
X1318569Y-51861D01*
X1323474Y-50994D01*
X1325057Y-48735D01*
X1319954Y-19791D01*
X1321008Y-18287D01*
X1325011Y-17580D01*
X1326515Y-18634D01*
X1332110Y-50361D01*
X1334367Y-51943D01*
X1339271Y-51075D01*
X1340855Y-48815D01*
X1335740Y-19805D01*
X1336794Y-18301D01*
X1340797Y-17594D01*
X1342301Y-18648D01*
X1347966Y-50768D01*
X1350224Y-52351D01*
X1355129Y-51484D01*
X1356712Y-49226D01*
X1351529Y-19830D01*
X1352583Y-18326D01*
X1356586Y-17619D01*
X1358090Y-18673D01*
X1363759Y-50829D01*
X1366020Y-52412D01*
X1370925Y-51545D01*
X1372508Y-49289D01*
X1367309Y-19804D01*
X1368363Y-18300D01*
X1372366Y-17593D01*
X1373870Y-18647D01*
X1379511Y-50642D01*
X1381770Y-52225D01*
X1386675Y-51358D01*
X1388258Y-49100D01*
X1383089Y-19785D01*
X1384143Y-18281D01*
X1388146Y-17574D01*
X1389650Y-18628D01*
X1395280Y-50559D01*
X1397539Y-52142D01*
X1402444Y-51275D01*
X1404027Y-49017D01*
X1398878Y-19816D01*
X1399932Y-18312D01*
X1403935Y-17605D01*
X1405440Y-18660D01*
X1411080Y-50647D01*
X1413339Y-52230D01*
X1418244Y-51363D01*
X1419827Y-49105D01*
X1414667Y-19842D01*
X1415721Y-18338D01*
X1419724Y-17631D01*
X1421229Y-18685D01*
X1426895Y-50822D01*
X1429154Y-52405D01*
X1434059Y-51538D01*
X1435642Y-49280D01*
X1430448Y-19821D01*
X1431502Y-18317D01*
X1435505Y-17610D01*
X1437009Y-18664D01*
X1442661Y-50720D01*
X1444920Y-52303D01*
X1449825Y-51436D01*
X1451408Y-49178D01*
X1446223Y-19767D01*
X1447277Y-18263D01*
X1451280Y-17556D01*
X1452784Y-18610D01*
X1458426Y-50610D01*
X1460685Y-52193D01*
X1465590Y-51326D01*
X1467173Y-49068D01*
X1462010Y-19786D01*
X1463064Y-18282D01*
X1467067Y-17575D01*
X1468571Y-18629D01*
X1474198Y-50545D01*
X1476457Y-52128D01*
X1481362Y-51261D01*
X1482946Y-49002D01*
X1477797Y-19812D01*
X1478851Y-18308D01*
X1482854Y-17601D01*
X1484360Y-18656D01*
X1489993Y-50605D01*
X1492252Y-52188D01*
X1497157Y-51321D01*
X1498740Y-49063D01*
X1493597Y-19895D01*
X1494651Y-18391D01*
X1498653Y-17684D01*
X1500159Y-18740D01*
X1502382Y-31346D01*
X1504190Y-32613D01*
X1516116D01*
X1517261Y-33758D01*
G01X1297687Y-30256D02*
X1298832Y-31401D01*
X1312042D01*
X1314551Y-33909D01*
X1317325Y-49632D01*
X1318829Y-50687D01*
X1322828Y-49980D01*
X1323883Y-48474D01*
X1318780Y-19530D01*
X1320362Y-17273D01*
X1325271Y-16406D01*
X1327529Y-17988D01*
X1333124Y-49715D01*
X1334627Y-50769D01*
X1338625Y-50062D01*
X1339681Y-48555D01*
X1334566Y-19544D01*
X1336148Y-17287D01*
X1341057Y-16420D01*
X1343315Y-18002D01*
X1348980Y-50122D01*
X1350484Y-51177D01*
X1354483Y-50470D01*
X1355538Y-48965D01*
X1350355Y-19569D01*
X1351937Y-17312D01*
X1356846Y-16445D01*
X1359104Y-18027D01*
X1364773Y-50183D01*
X1366280Y-51238D01*
X1370279Y-50531D01*
X1371334Y-49028D01*
X1366135Y-19543D01*
X1367717Y-17286D01*
X1372626Y-16419D01*
X1374884Y-18001D01*
X1380525Y-49996D01*
X1382030Y-51051D01*
X1386029Y-50344D01*
X1387084Y-48839D01*
X1381915Y-19524D01*
X1383497Y-17267D01*
X1388406Y-16400D01*
X1390664Y-17982D01*
X1396294Y-49913D01*
X1397799Y-50968D01*
X1401798Y-50261D01*
X1402853Y-48756D01*
X1397704Y-19555D01*
X1399286Y-17298D01*
X1404196Y-16431D01*
X1406454Y-18014D01*
X1412094Y-50001D01*
X1413599Y-51056D01*
X1417598Y-50349D01*
X1418653Y-48844D01*
X1413493Y-19581D01*
X1415075Y-17324D01*
X1419984Y-16457D01*
X1422243Y-18039D01*
X1427909Y-50176D01*
X1429414Y-51231D01*
X1433413Y-50524D01*
X1434468Y-49019D01*
X1429274Y-19560D01*
X1430856Y-17303D01*
X1435765Y-16436D01*
X1438023Y-18018D01*
X1443675Y-50074D01*
X1445180Y-51129D01*
X1449179Y-50422D01*
X1450234Y-48917D01*
X1445049Y-19506D01*
X1446631Y-17249D01*
X1451540Y-16382D01*
X1453798Y-17964D01*
X1459440Y-49964D01*
X1460945Y-51019D01*
X1464944Y-50312D01*
X1465999Y-48807D01*
X1460836Y-19525D01*
X1462418Y-17268D01*
X1467327Y-16401D01*
X1469585Y-17983D01*
X1475212Y-49899D01*
X1476717Y-50954D01*
X1480716Y-50247D01*
X1481772Y-48741D01*
X1476623Y-19552D01*
X1478205Y-17294D01*
X1483114Y-16427D01*
X1485374Y-18010D01*
X1491007Y-49959D01*
X1492512Y-51014D01*
X1496511Y-50307D01*
X1497566Y-48802D01*
X1492423Y-19634D01*
X1494005Y-17377D01*
X1498914Y-16510D01*
X1501173Y-18094D01*
X1503396Y-30700D01*
X1504541Y-31503D01*
X1516116D01*
X1517261Y-30358D01*
G01X1365709Y1596024D02*
Y1597528D01*
X1366209Y1598028D01*
X1367903D01*
X1369032Y1596899D01*
Y1554160D01*
X1364864Y1550180D01*
X1363230Y1549096D01*
X1361516Y1548168D01*
X1361041Y1548309D01*
X1359326Y1547380D01*
X1359184Y1546905D01*
X1357470Y1545977D01*
X1356995Y1546118D01*
X1355280Y1545189D01*
X1355138Y1544714D01*
X1327625Y1529816D01*
X1304409Y1520372D01*
X1301518Y1517426D01*
X1299737Y1512869D01*
X1286551Y1413984D01*
Y1369151D01*
X1292671Y1363031D01*
Y1361244D01*
X1291526Y1360099D01*
G01X1294926D02*
X1293781Y1361244D01*
Y1363491D01*
X1287661Y1369611D01*
Y1413910D01*
X1300820Y1512590D01*
X1302470Y1516810D01*
X1305040Y1519430D01*
X1328100Y1528810D01*
X1363803Y1548143D01*
X1365560Y1549309D01*
X1370142Y1553685D01*
Y1597359D01*
X1368363Y1599138D01*
X1366209D01*
X1365709Y1599638D01*
Y1601142D01*
G01X1313740Y1493662D02*
Y1495166D01*
X1314240Y1495666D01*
X1315934D01*
X1317063Y1494537D01*
Y1450687D01*
X1312959Y1441728D01*
X1312547Y1441575D01*
X1311660Y1439639D01*
X1311813Y1439227D01*
X1311001Y1437455D01*
X1310608Y1437309D01*
X1309668Y1435255D01*
X1309814Y1434863D01*
X1298791Y1410798D01*
Y1393349D01*
X1304911Y1387229D01*
Y1385442D01*
X1303766Y1384297D01*
G01X1307166D02*
X1306021Y1385442D01*
Y1387689D01*
X1299901Y1393809D01*
Y1410555D01*
X1318173Y1450444D01*
Y1494997D01*
X1316394Y1496776D01*
X1314240D01*
X1313740Y1497276D01*
Y1498780D01*
G01X1291526Y1408495D02*
X1292671Y1409640D01*
Y1412874D01*
X1298931Y1427992D01*
X1298742Y1428449D01*
X1299489Y1430251D01*
X1299946Y1430441D01*
X1300692Y1432242D01*
X1300503Y1432699D01*
X1301250Y1434501D01*
X1301707Y1434691D01*
X1302453Y1436492D01*
X1302264Y1436949D01*
X1303011Y1438752D01*
X1303468Y1438941D01*
X1304214Y1440742D01*
X1304025Y1441199D01*
X1304772Y1443002D01*
X1305229Y1443191D01*
X1308402Y1450852D01*
Y1490206D01*
X1307273Y1491335D01*
X1305579D01*
X1305079Y1490835D01*
Y1489331D01*
G01X1294926Y1408495D02*
X1293781Y1409640D01*
Y1412653D01*
X1309512Y1450631D01*
Y1490666D01*
X1307733Y1492445D01*
X1305579D01*
X1305079Y1492945D01*
Y1494449D01*
G01X1319406Y1360099D02*
X1318261Y1361244D01*
Y1363491D01*
X1312141Y1369611D01*
Y1410086D01*
X1326835Y1451154D01*
Y1490666D01*
X1325056Y1492445D01*
X1322902D01*
X1322402Y1492945D01*
Y1494449D01*
G01X1316006Y1360099D02*
X1317151Y1361244D01*
Y1363031D01*
X1311031Y1369151D01*
Y1410279D01*
X1316996Y1426951D01*
X1316784Y1427399D01*
X1317441Y1429236D01*
X1317890Y1429447D01*
X1318546Y1431283D01*
X1318334Y1431731D01*
X1318991Y1433568D01*
X1319440Y1433779D01*
X1319439D01*
X1320096Y1435615D01*
X1319884Y1436063D01*
X1320541Y1437900D01*
X1320990Y1438111D01*
X1320989D01*
X1321645Y1439947D01*
X1321646D01*
X1321434Y1440395D01*
X1322091Y1442232D01*
X1322540Y1442443D01*
X1322539D01*
X1325725Y1451347D01*
Y1490206D01*
X1324596Y1491335D01*
X1322902D01*
X1322402Y1490835D01*
Y1489331D01*
G01X1316006Y1408495D02*
X1317151Y1409640D01*
Y1413426D01*
X1329935Y1441336D01*
X1329713Y1441933D01*
X1330525Y1443707D01*
X1331123Y1443929D01*
X1334386Y1451053D01*
Y1494537D01*
X1333257Y1495666D01*
X1331563D01*
X1331063Y1495166D01*
Y1493662D01*
G01Y1498780D02*
Y1497276D01*
X1331563Y1496776D01*
X1333717D01*
X1335496Y1494997D01*
Y1450810D01*
X1318261Y1413183D01*
Y1409640D01*
X1319406Y1408495D01*
G01X1339725Y1494449D02*
Y1492945D01*
X1340225Y1492445D01*
X1342379D01*
X1344158Y1490666D01*
Y1451113D01*
X1324381Y1412415D01*
Y1393809D01*
X1330501Y1387689D01*
Y1385442D01*
X1331646Y1384297D01*
G01X1339725Y1489331D02*
Y1490835D01*
X1340225Y1491335D01*
X1341919D01*
X1343048Y1490206D01*
Y1451381D01*
X1339108Y1443671D01*
X1338637Y1443519D01*
X1337749Y1441782D01*
X1337901Y1441311D01*
X1337014Y1439575D01*
X1336543Y1439423D01*
X1335655Y1437685D01*
X1335807Y1437214D01*
X1334920Y1435478D01*
X1334449Y1435326D01*
X1333561Y1433588D01*
X1333713Y1433117D01*
X1332826Y1431381D01*
X1332423Y1431250D01*
X1331534Y1429513D01*
X1331665Y1429109D01*
X1323271Y1412683D01*
Y1393349D01*
X1329391Y1387229D01*
Y1385442D01*
X1328246Y1384297D01*
G01X1337687Y-69306D02*
X1338832Y-70451D01*
X1354106D01*
X1355268Y-71425D01*
X1357676Y-85080D01*
X1359181Y-86135D01*
X1363180Y-85428D01*
X1364235Y-83923D01*
X1360367Y-61984D01*
X1361949Y-59727D01*
X1366860Y-58860D01*
X1369117Y-60443D01*
X1373476Y-85168D01*
X1374981Y-86223D01*
X1378980Y-85516D01*
X1380035Y-84011D01*
X1376148Y-61964D01*
X1377730Y-59707D01*
X1382639Y-58840D01*
X1384897Y-60422D01*
X1389291Y-85343D01*
X1390796Y-86398D01*
X1394795Y-85691D01*
X1395850Y-84186D01*
X1391932Y-61961D01*
X1393514Y-59704D01*
X1398423Y-58837D01*
X1400681Y-60419D01*
X1405057Y-85241D01*
X1406562Y-86296D01*
X1410561Y-85589D01*
X1411616Y-84083D01*
X1407716Y-61958D01*
X1409298Y-59701D01*
X1414207Y-58834D01*
X1416465Y-60416D01*
X1420831Y-85180D01*
X1422335Y-86235D01*
X1426334Y-85528D01*
X1427389Y-84022D01*
X1423498Y-61949D01*
X1425080Y-59692D01*
X1429989Y-58825D01*
X1432247Y-60407D01*
X1436612Y-85163D01*
X1438116Y-86218D01*
X1442115Y-85511D01*
X1443171Y-84005D01*
X1439283Y-61965D01*
X1440865Y-59707D01*
X1445774Y-58840D01*
X1448034Y-60423D01*
X1452406Y-85223D01*
X1453911Y-86278D01*
X1457910Y-85571D01*
X1458965Y-84066D01*
X1455065Y-61949D01*
X1456647Y-59692D01*
X1461556Y-58825D01*
X1463815Y-60409D01*
X1465440Y-69620D01*
X1466585Y-70423D01*
X1480760D01*
X1481905Y-69278D01*
G01X1337687Y-72706D02*
X1338832Y-71561D01*
X1353702D01*
X1354245Y-72016D01*
X1356662Y-85726D01*
X1358921Y-87309D01*
X1363826Y-86442D01*
X1365409Y-84184D01*
X1361541Y-62245D01*
X1362595Y-60741D01*
X1366599Y-60034D01*
X1368103Y-61089D01*
X1372462Y-85814D01*
X1374721Y-87397D01*
X1379626Y-86530D01*
X1381209Y-84272D01*
X1377322Y-62225D01*
X1378376Y-60721D01*
X1382379Y-60014D01*
X1383883Y-61068D01*
X1388277Y-85989D01*
X1390536Y-87572D01*
X1395441Y-86705D01*
X1397024Y-84447D01*
X1393106Y-62222D01*
X1394160Y-60718D01*
X1398163Y-60011D01*
X1399667Y-61065D01*
X1404043Y-85887D01*
X1406302Y-87470D01*
X1411207Y-86603D01*
X1412790Y-84344D01*
X1408890Y-62219D01*
X1409944Y-60715D01*
X1413947Y-60008D01*
X1415451Y-61062D01*
X1419817Y-85826D01*
X1422075Y-87409D01*
X1426980Y-86542D01*
X1428563Y-84283D01*
X1424672Y-62210D01*
X1425726Y-60706D01*
X1429729Y-59999D01*
X1431233Y-61053D01*
X1435598Y-85809D01*
X1437856Y-87392D01*
X1442761Y-86525D01*
X1444345Y-84266D01*
X1440457Y-62225D01*
X1441511Y-60721D01*
X1445514Y-60014D01*
X1447020Y-61069D01*
X1451392Y-85869D01*
X1453651Y-87452D01*
X1458556Y-86585D01*
X1460139Y-84327D01*
X1456239Y-62210D01*
X1457293Y-60706D01*
X1461295Y-59999D01*
X1462801Y-61055D01*
X1464426Y-70266D01*
X1466234Y-71533D01*
X1480760D01*
X1481905Y-72678D01*
G01X1348386Y1498780D02*
Y1497276D01*
X1348886Y1496776D01*
X1351040D01*
X1352819Y1494997D01*
Y1452293D01*
X1336621Y1413184D01*
Y1369611D01*
X1342741Y1363491D01*
Y1361244D01*
X1343886Y1360099D01*
G01X1348386Y1493662D02*
Y1495166D01*
X1348886Y1495666D01*
X1350580D01*
X1351709Y1494537D01*
Y1452514D01*
X1347805Y1443089D01*
X1347414Y1442926D01*
X1346666Y1441124D01*
X1346829Y1440732D01*
X1346083Y1438931D01*
X1345691Y1438769D01*
X1344944Y1436966D01*
X1345107Y1436574D01*
X1335511Y1413405D01*
Y1369151D01*
X1341631Y1363031D01*
Y1361244D01*
X1340486Y1360099D01*
G01X1365709Y1493662D02*
Y1495166D01*
X1366209Y1495666D01*
X1367903D01*
X1369032Y1494537D01*
Y1453093D01*
X1361426Y1438862D01*
X1360952Y1438718D01*
X1360032Y1436997D01*
X1360175Y1436524D01*
X1359256Y1434805D01*
X1358783Y1434661D01*
X1357862Y1432940D01*
X1358006Y1432467D01*
X1347751Y1413279D01*
Y1393349D01*
X1353871Y1387229D01*
Y1385442D01*
X1352726Y1384297D01*
G01X1356126D02*
X1354981Y1385442D01*
Y1387689D01*
X1348861Y1393809D01*
Y1413000D01*
X1370142Y1452814D01*
Y1494997D01*
X1368363Y1496776D01*
X1366209D01*
X1365709Y1497276D01*
Y1498780D01*
G01X1357047Y1494449D02*
Y1492945D01*
X1357547Y1492445D01*
X1359701D01*
X1361480Y1490666D01*
Y1452534D01*
X1361219Y1451904D01*
X1361218Y1451903D01*
Y1451889D01*
X1361205Y1451876D01*
X1342741Y1412836D01*
Y1409640D01*
X1343886Y1408495D01*
G01X1357047Y1489331D02*
Y1490835D01*
X1357547Y1491335D01*
X1359241D01*
X1360370Y1490206D01*
Y1452755D01*
X1360203Y1452354D01*
X1356413Y1444340D01*
X1355947Y1444173D01*
X1355112Y1442410D01*
X1355279Y1441943D01*
X1354446Y1440181D01*
X1353980Y1440014D01*
X1353145Y1438250D01*
X1353312Y1437784D01*
X1352479Y1436022D01*
X1351880Y1435807D01*
X1351045Y1434044D01*
X1351259Y1433444D01*
X1350426Y1431682D01*
X1349933Y1431505D01*
X1349030Y1429597D01*
X1349206Y1429104D01*
X1341631Y1413086D01*
Y1409640D01*
X1340486Y1408495D01*
G01X1544944Y1068288D02*
Y1064854D01*
X1544165Y1058363D01*
X1542711Y1051286D01*
X1541084Y1037711D01*
Y1032787D01*
X1541343Y1006345D01*
X1535151Y938717D01*
X1465334Y569505D01*
X1452523Y472104D01*
X1432034Y404508D01*
X1432033Y404506D01*
X1411543Y336907D01*
X1412289Y246490D01*
Y237178D01*
X1411220Y225367D01*
X1411675Y196278D01*
X1406550Y158350D01*
X1406253Y139194D01*
Y137740D01*
X1402173Y133660D01*
X1400793D01*
X1399648Y132515D01*
G01X1551315Y1068288D02*
Y1064194D01*
X1547526Y1037485D01*
X1547829Y1006529D01*
X1541540Y937829D01*
X1471812Y569094D01*
X1458898Y470914D01*
X1438495Y403601D01*
X1438494Y403598D01*
X1438447Y403443D01*
Y403441D01*
X1418014Y336033D01*
X1418766Y242080D01*
Y236798D01*
X1417712Y225881D01*
X1418173Y196397D01*
X1413062Y158572D01*
X1412917Y149371D01*
X1414985Y137723D01*
X1415077Y126334D01*
X1413324Y124581D01*
X1412759D01*
X1411379Y123201D01*
Y122636D01*
X1409340Y120597D01*
X1407390D01*
X1406990Y120997D01*
X1405040D01*
X1404640Y120597D01*
X1400793D01*
X1399648Y121742D01*
G01X1552425Y1068288D02*
Y1064115D01*
X1548637Y1037412D01*
X1548940Y1006484D01*
X1542641Y937675D01*
X1472909Y568918D01*
X1459987Y470679D01*
X1439557Y403278D01*
Y403276D01*
X1439510Y403121D01*
X1439509Y403118D01*
X1419126Y335873D01*
X1419876Y242085D01*
Y236744D01*
X1418823Y225836D01*
X1419285Y196331D01*
X1414171Y158489D01*
X1414029Y149460D01*
X1416095Y137825D01*
X1416191Y125878D01*
X1409800Y119487D01*
X1400793D01*
X1399648Y118342D01*
G01X1543834Y1068288D02*
Y1064922D01*
X1543833Y1064921D01*
X1543068Y1058541D01*
X1541614Y1051464D01*
X1539974Y1037778D01*
Y1032781D01*
X1540232Y1006390D01*
X1534050Y938871D01*
X1516596Y846572D01*
X1516595D01*
X1499143Y754275D01*
X1499142D01*
X1464237Y569681D01*
X1451434Y472339D01*
X1430971Y404830D01*
X1430970Y404827D01*
X1410431Y337067D01*
X1411179Y246485D01*
Y237229D01*
X1410109Y225408D01*
X1410563Y196344D01*
X1405441Y158433D01*
X1405388Y154975D01*
X1404981Y154581D01*
X1404951Y152631D01*
X1405344Y152225D01*
X1405314Y150276D01*
X1404907Y149882D01*
X1404877Y147931D01*
X1405271Y147525D01*
X1405143Y139203D01*
Y138200D01*
X1401713Y134770D01*
X1400793D01*
X1399648Y135915D01*
G01X1406948Y111255D02*
X1408102Y112409D01*
X1408125Y112400D01*
X1409858D01*
X1413445Y115987D01*
X1416060Y119900D01*
X1422216Y126056D01*
X1431620Y148378D01*
X1431523Y154210D01*
X1423074Y194565D01*
X1422588Y225685D01*
X1423649Y236456D01*
Y243508D01*
X1422905Y335329D01*
X1463688Y469880D01*
X1476637Y568321D01*
X1546383Y937151D01*
X1552716Y1006330D01*
X1552413Y1037243D01*
X1556164Y1061030D01*
Y1068476D01*
G01X1555054D02*
Y1061117D01*
X1551302Y1037325D01*
X1551605Y1006375D01*
X1545282Y937305D01*
X1475540Y568497D01*
X1462599Y470115D01*
X1421793Y335489D01*
X1422539Y243503D01*
Y236511D01*
X1421477Y225731D01*
X1421965Y194441D01*
X1430414Y154086D01*
X1430506Y148593D01*
X1424855Y135181D01*
X1424397Y134994D01*
X1423639Y133196D01*
X1423826Y132738D01*
X1423069Y130941D01*
X1422611Y130754D01*
X1421853Y128956D01*
X1422040Y128498D01*
X1421277Y126687D01*
X1415198Y120608D01*
X1412583Y116695D01*
X1409398Y113510D01*
X1408346D01*
X1407914Y113689D01*
X1406948Y114655D01*
G01Y128828D02*
X1408093Y127683D01*
X1409895D01*
X1411262Y129050D01*
X1411210Y132427D01*
X1410803Y132820D01*
X1410773Y134771D01*
X1411166Y135177D01*
X1411125Y137874D01*
X1410720Y140049D01*
X1410252Y140369D01*
X1409895Y142287D01*
X1410215Y142754D01*
X1409061Y148947D01*
X1409207Y158145D01*
X1414329Y196059D01*
X1413873Y225245D01*
X1414977Y237429D01*
Y243000D01*
X1414219Y336579D01*
X1434691Y404115D01*
Y404117D01*
X1434738Y404272D01*
X1434739Y404275D01*
X1455181Y471716D01*
X1468068Y569694D01*
X1537782Y938355D01*
X1539344Y955435D01*
X1539345D01*
X1544037Y1006683D01*
X1543734Y1037546D01*
X1547574Y1064584D01*
Y1068476D01*
G01X1406948Y125428D02*
X1408093Y126573D01*
X1410355D01*
X1412380Y128597D01*
X1412234Y137985D01*
X1410173Y149041D01*
X1410316Y158062D01*
X1415441Y195993D01*
X1414984Y225203D01*
X1416087Y237378D01*
Y243005D01*
X1415331Y336419D01*
X1435753Y403792D01*
X1435754Y403795D01*
X1435801Y403950D01*
Y403952D01*
X1456270Y471481D01*
X1469165Y569518D01*
X1538883Y938201D01*
X1545148Y1006638D01*
X1544845Y1037473D01*
X1548684Y1064505D01*
Y1068476D01*
G01X1461370Y1372385D02*
X1462515Y1371240D01*
Y1368771D01*
X1468635Y1362651D01*
Y1343312D01*
X1565409Y1264776D01*
X1570016Y1260169D01*
Y1259752D01*
G01X1464770Y1372385D02*
X1463625Y1371240D01*
Y1369231D01*
X1469745Y1363111D01*
Y1343841D01*
X1566153Y1265602D01*
X1571126Y1260629D01*
Y1259752D01*
G01X1464770Y1384297D02*
X1463625Y1385442D01*
Y1411353D01*
X1482740Y1452403D01*
Y1506021D01*
X1480961Y1507800D01*
X1478807D01*
X1478307Y1508300D01*
Y1509804D01*
G01Y1504685D02*
Y1506190D01*
X1478807Y1506690D01*
X1480501D01*
X1481630Y1505561D01*
Y1452649D01*
X1474165Y1436617D01*
X1473567Y1436399D01*
X1472743Y1434630D01*
X1472961Y1434032D01*
X1472138Y1432265D01*
X1471540Y1432047D01*
X1470716Y1430278D01*
X1470934Y1429680D01*
X1462515Y1411599D01*
Y1385442D01*
X1461370Y1384297D01*
G01X1477010Y1348187D02*
X1475865Y1347042D01*
Y1344010D01*
X1569237Y1268013D01*
X1574866Y1262384D01*
Y1259800D01*
G01X1473610Y1396583D02*
X1474755Y1395438D01*
Y1392969D01*
X1480875Y1386849D01*
Y1344860D01*
X1571073Y1269987D01*
X1576375Y1264685D01*
X1577496Y1261980D01*
Y1259800D01*
G01X1473610Y1348187D02*
X1474755Y1347042D01*
Y1343482D01*
X1568492Y1267188D01*
X1573756Y1261924D01*
Y1259800D01*
G01X1486968Y1509016D02*
Y1510520D01*
X1487468Y1511020D01*
X1489162D01*
X1490291Y1509891D01*
Y1451998D01*
X1486363Y1444622D01*
X1485755Y1444436D01*
X1484837Y1442714D01*
X1485023Y1442105D01*
X1468635Y1411328D01*
Y1369151D01*
X1474755Y1363031D01*
Y1361244D01*
X1473610Y1360099D01*
G01X1477010D02*
X1475865Y1361244D01*
Y1363491D01*
X1469745Y1369611D01*
Y1411050D01*
X1491401Y1451720D01*
Y1510351D01*
X1489622Y1512130D01*
X1487468D01*
X1486968Y1512630D01*
Y1514134D01*
G01X1477010Y1396583D02*
X1475865Y1395438D01*
Y1393429D01*
X1481985Y1387309D01*
Y1345382D01*
X1571822Y1270808D01*
X1577316Y1265314D01*
X1578606Y1262201D01*
Y1259800D01*
G01X1504291Y1509016D02*
Y1510520D01*
X1504791Y1511020D01*
X1506485D01*
X1507614Y1509891D01*
Y1452341D01*
X1502995Y1445284D01*
X1502372Y1445154D01*
X1501303Y1443521D01*
X1501433Y1442898D01*
X1501432D01*
X1480875Y1411491D01*
Y1393349D01*
X1486995Y1387229D01*
Y1385442D01*
X1485850Y1384297D01*
G01X1495630Y1504685D02*
Y1506190D01*
X1496130Y1506690D01*
X1497824D01*
X1498953Y1505561D01*
Y1451940D01*
X1495820Y1446750D01*
X1495202Y1446597D01*
X1494193Y1444927D01*
X1494346Y1444309D01*
X1493339Y1442640D01*
X1492721Y1442487D01*
X1491712Y1440817D01*
X1491865Y1440199D01*
X1474755Y1411855D01*
Y1409640D01*
X1473610Y1408495D01*
G01X1495630Y1509804D02*
Y1508300D01*
X1496130Y1507800D01*
X1498284D01*
X1500063Y1506021D01*
Y1451630D01*
X1475865Y1411545D01*
Y1409640D01*
X1477010Y1408495D01*
G01X1478307Y1596811D02*
Y1595307D01*
X1478807Y1594807D01*
X1480961D01*
X1482740Y1593028D01*
Y1559175D01*
X1484803Y1553268D01*
X1509087Y1537672D01*
X1549628Y1519873D01*
X1551941Y1517560D01*
X1552620Y1452841D01*
X1552624Y1452495D01*
X1524825Y1411399D01*
Y1409640D01*
X1525970Y1408495D01*
G01X1522570D02*
X1523715Y1409640D01*
Y1411740D01*
X1537434Y1432022D01*
X1537340Y1432508D01*
X1538434Y1434125D01*
X1538920Y1434218D01*
X1540012Y1435833D01*
X1539918Y1436319D01*
X1541012Y1437936D01*
X1541498Y1438029D01*
X1542590Y1439644D01*
X1542497Y1440130D01*
X1543590Y1441746D01*
X1544076Y1441840D01*
X1551510Y1452830D01*
X1550835Y1517095D01*
X1548990Y1518940D01*
X1508560Y1536690D01*
X1483880Y1552540D01*
X1481630Y1558986D01*
Y1592568D01*
X1480501Y1593697D01*
X1478807D01*
X1478307Y1593197D01*
Y1591693D01*
G01X1489250Y1372385D02*
X1488105Y1371240D01*
Y1369231D01*
X1494225Y1363111D01*
Y1344889D01*
X1573579Y1274441D01*
X1580670Y1267350D01*
X1582346Y1263305D01*
Y1259800D01*
G01X1485850Y1372385D02*
X1486995Y1371240D01*
Y1368771D01*
X1493115Y1362651D01*
Y1344390D01*
X1572817Y1273633D01*
X1579729Y1266721D01*
X1581236Y1263084D01*
Y1259800D01*
G01X1512953Y1509804D02*
Y1508300D01*
X1513453Y1507800D01*
X1515607D01*
X1517386Y1506021D01*
Y1451644D01*
X1494225Y1411224D01*
Y1369611D01*
X1500345Y1363491D01*
Y1361244D01*
X1501490Y1360099D01*
G01X1512953Y1504685D02*
Y1506190D01*
X1513453Y1506690D01*
X1515147D01*
X1516276Y1505561D01*
Y1451940D01*
X1513286Y1446721D01*
X1512672Y1446554D01*
X1511701Y1444861D01*
X1511868Y1444247D01*
X1510899Y1442556D01*
X1510285Y1442389D01*
X1509314Y1440696D01*
X1509481Y1440082D01*
X1493115Y1411520D01*
Y1369151D01*
X1499235Y1363031D01*
Y1361244D01*
X1498090Y1360099D01*
G01X1489250Y1384297D02*
X1488105Y1385442D01*
Y1387689D01*
X1481985Y1393809D01*
Y1411160D01*
X1508724Y1452010D01*
Y1510351D01*
X1506945Y1512130D01*
X1504791D01*
X1504291Y1512630D01*
Y1514134D01*
G01X1534810Y1384297D02*
X1535955Y1385442D01*
Y1387229D01*
X1529835Y1393349D01*
Y1410980D01*
X1548898Y1437226D01*
X1548821Y1437715D01*
X1549968Y1439293D01*
X1550457Y1439371D01*
X1558090Y1449880D01*
X1560080Y1456070D01*
X1559320Y1519190D01*
X1558450Y1521240D01*
X1509680Y1540770D01*
X1491407Y1553526D01*
X1490291Y1559300D01*
Y1596899D01*
X1489162Y1598028D01*
X1487468D01*
X1486968Y1597528D01*
Y1596024D01*
G01Y1601142D02*
Y1599638D01*
X1487468Y1599138D01*
X1489622D01*
X1491401Y1597359D01*
Y1559407D01*
X1492412Y1554179D01*
X1510211Y1541754D01*
X1558862Y1522271D01*
X1559292Y1522099D01*
X1560428Y1519422D01*
X1561193Y1455902D01*
X1559093Y1449371D01*
X1530945Y1410619D01*
Y1393809D01*
X1537065Y1387689D01*
Y1385442D01*
X1538210Y1384297D01*
G01X1495630Y1596811D02*
Y1595307D01*
X1496130Y1594807D01*
X1498284D01*
X1500063Y1593028D01*
Y1560827D01*
X1501989Y1556523D01*
X1513826Y1544794D01*
X1562119Y1525166D01*
X1564374Y1520928D01*
X1565333Y1456121D01*
X1563258Y1448411D01*
X1543185Y1412014D01*
Y1369611D01*
X1549305Y1363491D01*
Y1361244D01*
X1550450Y1360099D01*
G01X1547050D02*
X1548195Y1361244D01*
Y1363031D01*
X1542075Y1369151D01*
Y1412300D01*
X1548268Y1423532D01*
X1548131Y1424008D01*
X1549073Y1425716D01*
X1549549Y1425854D01*
X1550490Y1427561D01*
X1550353Y1428037D01*
X1551295Y1429745D01*
X1551771Y1429883D01*
X1552712Y1431590D01*
X1552575Y1432065D01*
X1553518Y1433774D01*
X1553993Y1433911D01*
X1562220Y1448830D01*
X1564220Y1456260D01*
X1563268Y1520643D01*
X1561328Y1524289D01*
X1513202Y1543849D01*
X1501060Y1555880D01*
X1498953Y1560590D01*
Y1592568D01*
X1497824Y1593697D01*
X1496130D01*
X1495630Y1593197D01*
Y1591693D01*
G01X1509310Y114655D02*
X1510327Y113638D01*
X1510636Y113510D01*
X1511760D01*
X1514582Y116332D01*
Y116898D01*
X1515962Y118278D01*
X1516528D01*
X1517906Y119656D01*
Y120222D01*
X1519286Y121602D01*
X1519852D01*
X1522694Y124444D01*
X1532868Y148593D01*
X1532815Y151753D01*
X1524363Y192119D01*
X1523970Y217305D01*
X1525538Y256490D01*
X1537915Y410691D01*
X1539735Y470737D01*
X1538531Y582472D01*
X1569876Y984317D01*
X1568748Y1042803D01*
X1570015Y1055658D01*
Y1068476D01*
G01X1509310Y111255D02*
X1510455Y112400D01*
X1512220D01*
X1523633Y123813D01*
X1533982Y148378D01*
X1533924Y151877D01*
X1525472Y192243D01*
X1525081Y217291D01*
X1526647Y256423D01*
X1539024Y410630D01*
X1540846Y470726D01*
X1539642Y582435D01*
X1570987Y984284D01*
X1569860Y1042759D01*
X1571125Y1055603D01*
Y1068476D01*
G01X1502010Y121742D02*
X1503155Y120597D01*
X1506985D01*
X1507385Y120997D01*
X1509335D01*
X1509735Y120597D01*
X1511702D01*
X1514165Y123060D01*
Y123555D01*
X1515545Y124935D01*
X1516040D01*
X1517439Y126334D01*
X1517347Y137723D01*
X1515279Y149371D01*
X1515385Y156068D01*
X1515384D01*
X1515386Y156134D01*
X1520565Y194466D01*
X1520174Y219520D01*
X1521592Y254948D01*
X1534189Y411885D01*
X1535973Y470774D01*
X1534768Y582598D01*
X1566092Y984171D01*
X1565285Y1025990D01*
X1564701Y1037889D01*
X1566275Y1053871D01*
Y1068288D01*
G01X1563644Y1068476D02*
Y1054204D01*
X1561898Y1036481D01*
X1562774Y1018639D01*
X1563439Y984240D01*
X1532116Y582687D01*
X1533322Y470800D01*
X1531577Y413199D01*
X1519002Y256534D01*
X1517460Y217983D01*
X1517824Y194629D01*
X1512650Y156340D01*
X1512535Y149041D01*
X1514596Y137985D01*
X1514742Y128597D01*
X1512717Y126573D01*
X1510455D01*
X1509310Y125428D01*
G01X1562534Y1068476D02*
Y1054259D01*
X1560785Y1036508D01*
X1561664Y1018601D01*
X1562328Y984273D01*
X1531005Y582724D01*
X1532211Y470811D01*
X1530468Y413260D01*
X1517893Y256601D01*
X1516349Y217997D01*
X1516712Y194695D01*
X1511541Y156423D01*
X1511423Y148947D01*
X1512625Y142495D01*
X1512305Y142028D01*
X1512663Y140110D01*
X1513130Y139790D01*
X1513487Y137874D01*
X1513535Y134774D01*
X1513141Y134368D01*
X1513171Y132417D01*
X1513578Y132023D01*
X1513624Y129050D01*
X1512257Y127683D01*
X1510455D01*
X1509310Y128828D01*
G01X1567385Y1068288D02*
Y1053816D01*
X1565814Y1037862D01*
X1566395Y1026028D01*
X1567203Y984138D01*
X1535879Y582561D01*
X1537084Y470763D01*
X1535298Y411824D01*
X1522701Y254881D01*
X1521285Y219506D01*
X1521677Y194400D01*
X1516495Y156051D01*
X1516391Y149460D01*
X1518457Y137825D01*
X1518553Y125878D01*
X1512162Y119487D01*
X1503155D01*
X1502010Y118342D01*
G01X1559905Y1068288D02*
Y1054614D01*
X1558100Y1036284D01*
Y1034736D01*
X1559193Y978234D01*
X1526125Y557756D01*
X1526258Y545320D01*
X1529034Y519629D01*
X1529560Y470837D01*
X1527837Y413930D01*
X1515230Y256891D01*
X1513690Y218424D01*
X1514059Y194853D01*
X1508884Y156555D01*
X1508615Y139194D01*
Y137740D01*
X1504535Y133660D01*
X1503155D01*
X1502010Y132515D01*
G01X1558795Y1068288D02*
Y1054669D01*
X1556990Y1036339D01*
Y1034725D01*
X1558082Y978267D01*
X1525014Y557794D01*
X1525148Y545254D01*
X1527924Y519563D01*
X1528449Y470848D01*
X1526728Y413991D01*
X1514121Y256958D01*
X1512579Y218438D01*
X1512947Y194919D01*
X1507775Y156638D01*
X1507664Y149521D01*
X1507665D01*
X1507309Y149176D01*
X1507278Y147226D01*
X1507623Y146870D01*
X1507593Y144921D01*
X1507594D01*
X1507238Y144577D01*
X1507207Y142626D01*
X1507552Y142270D01*
X1507505Y139203D01*
Y138200D01*
X1504075Y134770D01*
X1503155D01*
X1502010Y135915D01*
G01X1501490Y1348187D02*
X1500345Y1347042D01*
Y1344978D01*
X1576802Y1276729D01*
X1583867Y1269664D01*
X1586086Y1264307D01*
Y1259800D01*
G01X1498090Y1348187D02*
X1499235Y1347042D01*
Y1344480D01*
X1576039Y1275922D01*
X1582926Y1269035D01*
X1584976Y1264086D01*
Y1259800D01*
G01X1498090Y1396583D02*
X1499235Y1395438D01*
Y1392969D01*
X1505355Y1386849D01*
Y1344071D01*
X1578626Y1279164D01*
X1586060Y1271730D01*
X1588716Y1265319D01*
Y1259800D01*
G01X1501490Y1396583D02*
X1500345Y1395438D01*
Y1393429D01*
X1506465Y1387309D01*
Y1344571D01*
X1579387Y1279973D01*
X1587001Y1272359D01*
X1589826Y1265540D01*
Y1259800D01*
G01X1510330Y1372385D02*
X1511475Y1371240D01*
Y1368771D01*
X1517595Y1362651D01*
Y1342055D01*
X1580298Y1282862D01*
X1589639Y1273521D01*
X1592457Y1266719D01*
Y1259800D01*
G01X1513730Y1372385D02*
X1512585Y1371240D01*
Y1369231D01*
X1518705Y1363111D01*
Y1342534D01*
X1581072Y1283658D01*
X1590580Y1274150D01*
X1593567Y1266940D01*
Y1259800D01*
G01X1513730Y1384297D02*
X1512585Y1385442D01*
Y1387689D01*
X1506465Y1393809D01*
Y1411880D01*
X1534708Y1452380D01*
Y1506021D01*
X1532929Y1507800D01*
X1530775D01*
X1530275Y1508300D01*
Y1509804D01*
G01X1510330Y1384297D02*
X1511475Y1385442D01*
Y1387229D01*
X1505355Y1393349D01*
Y1412229D01*
X1524705Y1439976D01*
X1524593Y1440603D01*
X1525710Y1442203D01*
X1526336Y1442315D01*
X1527451Y1443914D01*
X1527339Y1444541D01*
X1528456Y1446141D01*
X1529082Y1446253D01*
X1533598Y1452729D01*
Y1505561D01*
X1532469Y1506690D01*
X1530775D01*
X1530275Y1506190D01*
Y1504685D01*
G01X1498090Y1408495D02*
X1499235Y1409640D01*
Y1412450D01*
X1519052Y1443121D01*
X1518918Y1443744D01*
X1519977Y1445383D01*
X1520599Y1445516D01*
X1524937Y1452230D01*
Y1509891D01*
X1523808Y1511020D01*
X1522114D01*
X1521614Y1510520D01*
Y1509016D01*
G01Y1514134D02*
Y1512630D01*
X1522114Y1512130D01*
X1524268D01*
X1526047Y1510351D01*
Y1451902D01*
X1500345Y1412122D01*
Y1409640D01*
X1501490Y1408495D01*
G01X1504291Y1601142D02*
Y1599638D01*
X1504791Y1599138D01*
X1506945D01*
X1508724Y1597359D01*
Y1557664D01*
X1510439Y1553581D01*
X1515309Y1548712D01*
X1564723Y1528337D01*
X1568120Y1522200D01*
X1569183Y1455725D01*
X1567128Y1447311D01*
X1549305Y1412417D01*
Y1409640D01*
X1550450Y1408495D01*
G01X1547050D02*
X1548195Y1409640D01*
Y1412685D01*
X1557302Y1430515D01*
X1557149Y1430986D01*
X1558037Y1432723D01*
X1558508Y1432876D01*
X1566080Y1447700D01*
X1568070Y1455850D01*
X1567014Y1521905D01*
X1563940Y1527459D01*
X1514681Y1547770D01*
X1509500Y1552950D01*
X1507614Y1557440D01*
Y1596899D01*
X1506485Y1598028D01*
X1504791D01*
X1504291Y1597528D01*
Y1596024D01*
G01X1512953Y1596811D02*
Y1595307D01*
X1513453Y1594807D01*
X1515607D01*
X1517386Y1593028D01*
Y1557483D01*
X1526516Y1548710D01*
X1567551Y1531390D01*
X1571884Y1523649D01*
X1572992Y1455452D01*
X1571091Y1446519D01*
X1555425Y1412278D01*
Y1393809D01*
X1561545Y1387689D01*
Y1385442D01*
X1562690Y1384297D01*
G01X1559290D02*
X1560435Y1385442D01*
Y1387229D01*
X1554315Y1393349D01*
Y1412520D01*
X1558753Y1422220D01*
X1558580Y1422684D01*
X1559392Y1424459D01*
X1559856Y1424631D01*
X1560667Y1426404D01*
X1560494Y1426868D01*
X1561306Y1428643D01*
X1561770Y1428815D01*
X1562581Y1430588D01*
X1562408Y1431052D01*
X1563220Y1432826D01*
X1563684Y1432999D01*
X1570030Y1446870D01*
X1571880Y1455560D01*
X1570778Y1523351D01*
X1566768Y1530515D01*
X1525895Y1547767D01*
X1516276Y1557010D01*
Y1592568D01*
X1515147Y1593697D01*
X1513453D01*
X1512953Y1593197D01*
Y1591693D01*
G01X1525970Y1348187D02*
X1524825Y1347042D01*
Y1344490D01*
X1593479Y1276896D01*
X1597307Y1267655D01*
Y1259800D01*
G01X1522570Y1396583D02*
X1523715Y1395438D01*
Y1392969D01*
X1529863Y1386821D01*
Y1345614D01*
X1594149Y1282294D01*
X1596075Y1279448D01*
X1599937Y1270126D01*
Y1259800D01*
G01X1522570Y1348187D02*
X1523715Y1347042D01*
Y1344025D01*
X1592539Y1276263D01*
X1596197Y1267434D01*
Y1259800D01*
G01X1522570Y1360099D02*
X1523715Y1361244D01*
Y1363031D01*
X1517595Y1369151D01*
Y1412384D01*
X1536122Y1442543D01*
X1535974Y1443162D01*
X1536996Y1444825D01*
X1537615Y1444973D01*
X1542260Y1452534D01*
Y1509891D01*
X1541131Y1511020D01*
X1539437D01*
X1538937Y1510520D01*
Y1509016D01*
G01X1525970Y1360099D02*
X1524825Y1361244D01*
Y1363491D01*
X1518705Y1369611D01*
Y1412070D01*
X1543370Y1452220D01*
Y1510351D01*
X1541591Y1512130D01*
X1539437D01*
X1538937Y1512630D01*
Y1514134D01*
G01X1525970Y1396583D02*
X1524825Y1395438D01*
Y1393429D01*
X1530973Y1387281D01*
Y1346079D01*
X1595007Y1283008D01*
X1597058Y1279977D01*
X1601047Y1270347D01*
Y1259800D01*
G01X1521614Y1601142D02*
Y1599638D01*
X1522114Y1599138D01*
X1524268D01*
X1526047Y1597359D01*
Y1555461D01*
X1530068Y1551317D01*
X1570493Y1534483D01*
X1576318Y1524125D01*
X1576830Y1454988D01*
X1576831Y1454865D01*
X1567665Y1412747D01*
Y1369611D01*
X1573785Y1363491D01*
Y1361244D01*
X1574930Y1360099D01*
G01X1571530D02*
X1572675Y1361244D01*
Y1363031D01*
X1566555Y1369151D01*
Y1412867D01*
X1570277Y1429970D01*
X1570009Y1430387D01*
X1570424Y1432293D01*
X1570841Y1432561D01*
X1575720Y1454980D01*
X1575210Y1523830D01*
X1569713Y1533605D01*
X1529430Y1550380D01*
X1524937Y1555010D01*
Y1596899D01*
X1523808Y1598028D01*
X1522114D01*
X1521614Y1597528D01*
Y1596024D01*
G01X1538210Y1372385D02*
X1537065Y1371240D01*
Y1369231D01*
X1543185Y1363111D01*
Y1344969D01*
X1596009Y1287753D01*
X1598569Y1284740D01*
X1600351Y1282073D01*
X1604787Y1271363D01*
Y1259800D01*
G01X1534810Y1372385D02*
X1535955Y1371240D01*
Y1368771D01*
X1542075Y1362651D01*
Y1344534D01*
X1595188Y1287004D01*
X1597681Y1284070D01*
X1599367Y1281547D01*
X1603677Y1271142D01*
Y1259800D01*
G01X1538937Y1596024D02*
Y1597528D01*
X1539437Y1598028D01*
X1541131D01*
X1542260Y1596899D01*
Y1555159D01*
X1544744Y1552839D01*
X1544958Y1552846D01*
X1575135Y1539970D01*
X1583036Y1526373D01*
X1583387Y1453149D01*
X1580688Y1429363D01*
X1580300Y1429055D01*
X1580080Y1427116D01*
X1580388Y1426729D01*
X1580169Y1424792D01*
X1579781Y1424484D01*
X1579561Y1422545D01*
X1579869Y1422158D01*
X1578795Y1412693D01*
Y1393545D01*
X1584915Y1387425D01*
Y1385442D01*
X1583770Y1384297D01*
G01X1571530Y1408495D02*
X1572675Y1409640D01*
Y1412839D01*
X1573924Y1420402D01*
X1573635Y1420804D01*
X1573953Y1422729D01*
X1574357Y1423018D01*
X1574674Y1424941D01*
X1574386Y1425344D01*
X1574704Y1427269D01*
X1575107Y1427557D01*
X1575424Y1429480D01*
X1575136Y1429883D01*
X1575454Y1431808D01*
X1575857Y1432096D01*
X1579487Y1454082D01*
X1579148Y1525031D01*
X1572357Y1536717D01*
X1541871Y1549828D01*
Y1549827D01*
X1541679Y1549910D01*
X1534959Y1556507D01*
X1533598Y1560600D01*
Y1592568D01*
X1532469Y1593697D01*
X1530775D01*
X1530275Y1593197D01*
Y1591693D01*
G01Y1596811D02*
Y1595307D01*
X1530775Y1594807D01*
X1532929D01*
X1534708Y1593028D01*
Y1560780D01*
X1535929Y1557112D01*
X1542309Y1550848D01*
X1573133Y1537593D01*
X1580257Y1525333D01*
X1580598Y1453994D01*
X1573785Y1412747D01*
Y1409640D01*
X1574930Y1408495D01*
G01X1538937Y1601142D02*
Y1599638D01*
X1539437Y1599138D01*
X1541591D01*
X1543370Y1597359D01*
Y1555642D01*
X1545167Y1553964D01*
X1545297D01*
X1545394Y1553867D01*
X1575910Y1540847D01*
X1580028Y1533761D01*
X1584145Y1526675D01*
X1584498Y1453089D01*
X1579905Y1412630D01*
Y1394005D01*
X1586025Y1387885D01*
Y1385442D01*
X1587170Y1384297D01*
G01X1550450Y1348187D02*
X1549305Y1347042D01*
Y1344261D01*
X1600972Y1287956D01*
X1604424Y1282789D01*
X1608527Y1272883D01*
Y1259800D01*
G01X1547050Y1348187D02*
X1548195Y1347042D01*
Y1343828D01*
X1574319Y1315357D01*
X1574320D01*
X1600096Y1287268D01*
X1603440Y1282263D01*
X1607417Y1272662D01*
Y1259800D01*
G01X1550450Y1396583D02*
X1549305Y1395438D01*
Y1393429D01*
X1555425Y1387309D01*
Y1345631D01*
X1603058Y1291708D01*
X1608172Y1284055D01*
X1612267Y1274168D01*
Y1259800D01*
G01X1547050Y1396583D02*
X1548195Y1395438D01*
Y1392969D01*
X1554315Y1386849D01*
Y1345210D01*
X1578407Y1317934D01*
X1578410D01*
X1602176Y1291029D01*
X1607188Y1283529D01*
X1611157Y1273947D01*
Y1259800D01*
G01X1559290Y1372385D02*
X1560435Y1371240D01*
Y1368771D01*
X1566555Y1362651D01*
Y1344100D01*
X1585897Y1318759D01*
X1585899Y1318761D01*
X1604992Y1293748D01*
X1611294Y1284317D01*
X1614897Y1275619D01*
Y1259800D01*
G01X1562690Y1372385D02*
X1561545Y1371240D01*
Y1369231D01*
X1567665Y1363111D01*
Y1344476D01*
X1605896Y1294394D01*
X1612278Y1284843D01*
X1616007Y1275840D01*
Y1259800D01*
G01X1573756Y1068800D02*
Y1048297D01*
X1614956Y268233D01*
X1614854Y240138D01*
X1615534Y196584D01*
X1610137Y156638D01*
X1610096Y153981D01*
X1609689Y153588D01*
X1609659Y151637D01*
X1610053Y151231D01*
X1610023Y149282D01*
X1609616Y148888D01*
X1609586Y146937D01*
X1609980Y146531D01*
X1609867Y139203D01*
Y138200D01*
X1606437Y134770D01*
X1605517D01*
X1604372Y135915D01*
G01X1574866Y1068800D02*
Y1048327D01*
X1616067Y268260D01*
X1615965Y240145D01*
X1616646Y196518D01*
X1611246Y156555D01*
X1610977Y139194D01*
Y137740D01*
X1606897Y133660D01*
X1605517D01*
X1604372Y132515D01*
G01X1577495Y1068476D02*
Y1046322D01*
X1577824Y1042568D01*
X1618770Y267352D01*
X1618664Y240195D01*
X1619344Y196691D01*
X1613903Y156423D01*
X1613785Y148947D01*
X1614884Y143048D01*
X1614564Y142581D01*
X1614922Y140663D01*
X1615389Y140343D01*
X1615849Y137874D01*
X1615894Y134970D01*
X1615500Y134564D01*
X1615530Y132613D01*
X1615937Y132219D01*
X1615986Y129050D01*
X1614619Y127683D01*
X1612817D01*
X1611672Y128828D01*
G01X1578605Y1068476D02*
Y1046371D01*
X1578932Y1042646D01*
X1619881Y267379D01*
X1619775Y240202D01*
X1620456Y196625D01*
X1615012Y156340D01*
X1614897Y149041D01*
X1616958Y137985D01*
X1617104Y128597D01*
X1615079Y126573D01*
X1612817D01*
X1611672Y125428D01*
G01X1571530Y1396583D02*
X1572675Y1395438D01*
Y1392969D01*
X1578795Y1386849D01*
Y1344430D01*
X1578997Y1344143D01*
X1578998D01*
X1610656Y1299380D01*
X1617758Y1288751D01*
X1622378Y1277598D01*
Y1259800D01*
G01X1574930Y1348187D02*
X1573785Y1347042D01*
Y1344139D01*
X1608349Y1297782D01*
X1615429Y1287187D01*
X1619748Y1276760D01*
Y1259800D01*
G01X1571530Y1348187D02*
X1572675Y1347042D01*
Y1343770D01*
X1590176Y1320295D01*
Y1320296D01*
X1607442Y1297141D01*
X1614445Y1286661D01*
X1618638Y1276539D01*
Y1259800D01*
G01X1574930Y1396583D02*
X1573785Y1395438D01*
Y1393429D01*
X1579905Y1387309D01*
Y1344783D01*
X1611571Y1300009D01*
X1618742Y1289277D01*
X1623488Y1277819D01*
Y1259800D01*
G01X1581236Y1068288D02*
Y1048739D01*
X1581752Y1042859D01*
X1622593Y269646D01*
X1623318Y197355D01*
X1617925Y157448D01*
X1617727Y154809D01*
X1617641Y149371D01*
X1619709Y137723D01*
X1619801Y126334D01*
X1618423Y124956D01*
X1617857D01*
X1616477Y123576D01*
Y123010D01*
X1614064Y120597D01*
X1612114D01*
X1611714Y120997D01*
X1609764D01*
X1609364Y120597D01*
X1605517D01*
X1604372Y121742D01*
G01X1582346Y1068288D02*
Y1048788D01*
X1582860Y1042937D01*
X1623703Y269681D01*
X1624429Y197286D01*
X1619030Y157332D01*
X1618837Y154759D01*
X1618753Y149460D01*
X1620819Y137825D01*
X1620915Y125878D01*
X1614524Y119487D01*
X1605517D01*
X1604372Y118342D01*
G01X1611672Y114655D02*
X1612637Y113690D01*
X1613071Y113510D01*
X1614122D01*
X1616863Y116251D01*
Y116817D01*
X1618243Y118197D01*
X1618809D01*
X1620187Y119575D01*
Y120141D01*
X1621567Y121521D01*
X1622133D01*
X1625056Y124444D01*
X1635230Y148593D01*
X1635138Y154087D01*
X1627171Y192142D01*
X1626385Y269156D01*
X1585505Y1043119D01*
X1584975Y1049163D01*
Y1068476D01*
G01X1611672Y111255D02*
X1612826Y112409D01*
X1612849Y112400D01*
X1614582D01*
X1625995Y123813D01*
X1636344Y148378D01*
X1636247Y154211D01*
X1628280Y192263D01*
X1627495Y269191D01*
X1586613Y1043197D01*
X1586085Y1049212D01*
Y1068476D01*
G01X1588716Y1068288D02*
Y1064958D01*
X1590003Y1050086D01*
X1667040Y607744D01*
X1672462Y565603D01*
X1673705Y458560D01*
X1716958Y240542D01*
X1717670Y194912D01*
X1712403Y155924D01*
X1712277Y147328D01*
X1712278D01*
X1711922Y146983D01*
X1711893Y145032D01*
X1712238Y144677D01*
X1712210Y142728D01*
X1711854Y142384D01*
X1711826Y140433D01*
X1712171Y140078D01*
X1712128Y137139D01*
X1709760Y134770D01*
X1708374D01*
X1707529Y135120D01*
X1706734Y135915D01*
G01X1589826Y1068288D02*
Y1065006D01*
X1591105Y1050229D01*
X1668138Y607910D01*
X1673572Y565681D01*
X1674814Y458675D01*
X1718067Y240660D01*
X1718782Y194846D01*
X1713512Y155841D01*
X1713232Y136672D01*
X1710220Y133660D01*
X1707879D01*
X1706734Y132515D01*
G01X1593566Y1068476D02*
Y1065564D01*
X1594853Y1050628D01*
X1671857Y608473D01*
X1677331Y565946D01*
X1678570Y459066D01*
X1721823Y241054D01*
X1722548Y194629D01*
X1717374Y156340D01*
X1717256Y148831D01*
X1719324Y137736D01*
X1719458Y129098D01*
X1716933Y126573D01*
X1715179D01*
X1714034Y125428D01*
G01Y128828D02*
X1714922Y127940D01*
X1715542Y127683D01*
X1716473D01*
X1718340Y129551D01*
X1718301Y132078D01*
X1717843Y132521D01*
X1717813Y134472D01*
X1718256Y134929D01*
X1718215Y137625D01*
X1717311Y142478D01*
X1716785Y142838D01*
X1716428Y144756D01*
X1716788Y145281D01*
X1716144Y148737D01*
X1716264Y156357D01*
X1716263D01*
X1716265Y156423D01*
X1721436Y194695D01*
X1720714Y240936D01*
X1677461Y458951D01*
X1676221Y565868D01*
X1670759Y608307D01*
X1593751Y1050485D01*
X1592456Y1065516D01*
Y1068476D01*
G01X1587170Y1372385D02*
X1586025Y1371240D01*
Y1369231D01*
X1592680Y1362576D01*
X1596522Y1353265D01*
X1596992Y1353070D01*
X1597737Y1351266D01*
X1597542Y1350796D01*
X1627228Y1278861D01*
Y1260112D01*
G01X1583770Y1372385D02*
X1584915Y1371240D01*
Y1368771D01*
X1591738Y1361948D01*
X1626118Y1278640D01*
Y1260112D01*
G01X1596197Y1068288D02*
Y1066604D01*
X1597533Y1051199D01*
X1674565Y608883D01*
X1679982Y566814D01*
X1681225Y459302D01*
X1724564Y240864D01*
X1725289Y194466D01*
X1720110Y156135D01*
X1720014Y150116D01*
X1722847Y134159D01*
X1722879Y130130D01*
X1721866Y127429D01*
X1720811Y125790D01*
X1720189Y125655D01*
X1719132Y124014D01*
X1719267Y123393D01*
X1717468Y120597D01*
X1714885D01*
X1714435Y121047D01*
X1712485D01*
X1712035Y120597D01*
X1708167D01*
X1707675Y120801D01*
X1706734Y121742D01*
G01X1597307Y1068288D02*
Y1066653D01*
X1598635Y1051342D01*
X1675663Y609049D01*
X1681092Y566892D01*
X1682334Y459417D01*
X1725673Y240982D01*
X1726401Y194400D01*
X1721219Y156051D01*
X1721126Y150205D01*
X1723957Y134261D01*
X1723991Y129933D01*
X1722864Y126928D01*
X1718074Y119487D01*
X1707879D01*
X1706734Y118342D01*
G01X1601046Y1068476D02*
Y1063748D01*
X1601743Y1060735D01*
X1602662Y1050136D01*
X1602663D01*
X1679382Y609612D01*
X1684851Y567157D01*
X1686091Y459808D01*
X1729429Y241378D01*
X1730160Y194565D01*
X1737952Y157345D01*
X1738797Y149812D01*
X1738363Y147564D01*
X1727763Y122403D01*
X1717760Y112400D01*
X1715179D01*
X1714034Y111255D01*
G01Y114655D02*
X1714656Y114033D01*
X1715919Y113510D01*
X1717300D01*
X1718678Y114888D01*
Y115525D01*
X1720058Y116905D01*
X1720695D01*
X1722073Y118283D01*
Y118778D01*
X1723453Y120158D01*
X1723948D01*
X1726824Y123034D01*
X1737295Y147888D01*
X1737674Y149856D01*
X1736854Y157169D01*
X1729051Y194441D01*
X1728320Y241260D01*
X1684982Y459693D01*
X1683741Y567079D01*
X1678284Y609446D01*
X1601560Y1049993D01*
X1600643Y1060561D01*
X1599936Y1063621D01*
Y1068476D01*
G01X1614798Y1372385D02*
X1613653Y1371240D01*
Y1369231D01*
X1619773Y1363111D01*
Y1343588D01*
X1659850Y1266739D01*
X1660889Y1262499D01*
Y1259824D01*
G01X1611398Y1372385D02*
X1612543Y1371240D01*
Y1368771D01*
X1618663Y1362651D01*
Y1343315D01*
X1658803Y1266344D01*
X1659779Y1262364D01*
Y1259824D01*
G01X1623638Y1348187D02*
X1624783Y1347042D01*
Y1344305D01*
X1662437Y1267744D01*
X1663520Y1263090D01*
Y1259600D01*
G01X1627038Y1348187D02*
X1625893Y1347042D01*
Y1344564D01*
X1663490Y1268120D01*
X1664630Y1263218D01*
Y1259600D01*
G01X1660196Y1565315D02*
Y1566820D01*
X1660696Y1567320D01*
X1662390D01*
X1663519Y1566191D01*
Y1557409D01*
X1662092Y1555982D01*
X1661597D01*
X1660218Y1554603D01*
Y1554108D01*
X1658217Y1552107D01*
X1633655Y1535773D01*
X1625122Y1525426D01*
X1620803Y1511227D01*
X1619217Y1437021D01*
X1619218D01*
X1618859Y1436679D01*
X1618818Y1434728D01*
X1619160Y1434371D01*
X1618663Y1411089D01*
Y1369151D01*
X1624783Y1363031D01*
Y1361244D01*
X1623638Y1360099D01*
G01X1660196Y1570434D02*
Y1568930D01*
X1660696Y1568430D01*
X1662850D01*
X1664629Y1566651D01*
Y1556949D01*
X1658924Y1551244D01*
X1634407Y1534940D01*
X1626120Y1524890D01*
X1621910Y1511050D01*
X1619773Y1411077D01*
Y1369611D01*
X1625893Y1363491D01*
Y1361244D01*
X1627038Y1360099D01*
G01X1651535Y1560985D02*
Y1562489D01*
X1652035Y1562989D01*
X1653729D01*
X1654858Y1561860D01*
Y1555048D01*
X1653500Y1553690D01*
X1649297Y1550894D01*
X1648812Y1550991D01*
X1647188Y1549910D01*
X1647090Y1549425D01*
X1645467Y1548345D01*
X1644982Y1548443D01*
X1643357Y1547361D01*
X1643260Y1546876D01*
X1631014Y1538727D01*
X1621722Y1528015D01*
X1616825Y1511268D01*
X1612543Y1389140D01*
Y1385442D01*
X1611398Y1384297D01*
G01X1627038Y1396583D02*
X1625893Y1395438D01*
Y1393429D01*
X1632013Y1387309D01*
Y1345391D01*
X1667115Y1269267D01*
X1668370Y1263551D01*
Y1259600D01*
G01X1651535Y1566103D02*
Y1564599D01*
X1652035Y1564099D01*
X1654189D01*
X1655968Y1562320D01*
Y1554588D01*
X1654207Y1552827D01*
X1631754Y1537886D01*
X1622720Y1527470D01*
X1617930Y1511090D01*
X1613653Y1389120D01*
Y1385442D01*
X1614798Y1384297D01*
G01X1623638Y1396583D02*
X1624783Y1395438D01*
Y1392969D01*
X1630903Y1386849D01*
Y1345147D01*
X1666056Y1268911D01*
X1667260Y1263430D01*
Y1259600D01*
G01X1668858Y1566103D02*
Y1564599D01*
X1669358Y1564099D01*
X1671512D01*
X1673291Y1562320D01*
Y1554661D01*
X1667850Y1549220D01*
X1636870Y1531947D01*
X1629435Y1522628D01*
X1625893Y1510521D01*
Y1409640D01*
X1627038Y1408495D01*
G01X1668858Y1560985D02*
Y1562489D01*
X1669358Y1562989D01*
X1671052D01*
X1672181Y1561860D01*
Y1555121D01*
X1667175Y1550115D01*
X1665428Y1549141D01*
X1664952Y1549276D01*
X1663247Y1548326D01*
X1663112Y1547850D01*
X1661409Y1546901D01*
X1660933Y1547036D01*
X1659229Y1546086D01*
X1659094Y1545609D01*
X1636138Y1532811D01*
X1628430Y1523150D01*
X1624783Y1510680D01*
Y1409640D01*
X1623638Y1408495D01*
G01X1635878Y1372385D02*
X1637023Y1371240D01*
Y1368771D01*
X1643143Y1362651D01*
Y1345130D01*
X1669934Y1270130D01*
X1671000Y1263980D01*
Y1259600D01*
G01X1639278Y1372385D02*
X1638133Y1371240D01*
Y1369231D01*
X1644253Y1363111D01*
Y1345323D01*
X1671012Y1270414D01*
X1672110Y1264076D01*
Y1259600D01*
G01X1686181Y1560985D02*
Y1562489D01*
X1686681Y1562989D01*
X1688375D01*
X1689504Y1561860D01*
Y1554584D01*
X1686866Y1551946D01*
X1685160Y1551004D01*
X1684684Y1551141D01*
X1682976Y1550197D01*
X1682839Y1549721D01*
X1681133Y1548779D01*
X1680657Y1548916D01*
X1678949Y1547972D01*
X1678812Y1547496D01*
X1641303Y1526776D01*
X1635422Y1519161D01*
X1632815Y1510133D01*
X1634310Y1453691D01*
X1634313Y1453588D01*
X1643143Y1412294D01*
Y1369151D01*
X1649263Y1363031D01*
Y1361244D01*
X1648118Y1360099D01*
G01X1677519Y1565315D02*
Y1566820D01*
X1678019Y1567320D01*
X1679713D01*
X1680842Y1566191D01*
Y1556102D01*
X1678757Y1554017D01*
X1678262D01*
X1676883Y1552638D01*
Y1552143D01*
X1673721Y1548981D01*
X1671668Y1547847D01*
X1671192Y1547984D01*
X1669484Y1547040D01*
X1669347Y1546564D01*
X1638676Y1529621D01*
X1632125Y1521340D01*
X1628981Y1511008D01*
X1628980Y1511005D01*
X1628929Y1510837D01*
X1630903Y1411298D01*
Y1393349D01*
X1637023Y1387229D01*
Y1385442D01*
X1635878Y1384297D01*
G01X1677519Y1570434D02*
Y1568930D01*
X1678019Y1568430D01*
X1680173D01*
X1681952Y1566651D01*
Y1555642D01*
X1674395Y1548085D01*
X1639408Y1528757D01*
X1633126Y1520816D01*
X1630044Y1510686D01*
X1630043Y1510683D01*
X1630044D01*
X1630043Y1510682D01*
X1632013Y1411310D01*
Y1393809D01*
X1638133Y1387689D01*
Y1385442D01*
X1639278Y1384297D01*
G01X1686181Y1566103D02*
Y1564599D01*
X1686681Y1564099D01*
X1688835D01*
X1690614Y1562320D01*
Y1554124D01*
X1687540Y1551050D01*
X1642042Y1525915D01*
X1636430Y1518650D01*
X1633930Y1509990D01*
X1635420Y1453720D01*
X1644253Y1412412D01*
Y1369611D01*
X1650373Y1363491D01*
Y1361244D01*
X1651518Y1360099D01*
G01X1694842Y1565315D02*
Y1566820D01*
X1695342Y1567320D01*
X1697036D01*
X1698165Y1566191D01*
Y1557065D01*
X1695187Y1554087D01*
X1694692D01*
X1693313Y1552708D01*
Y1552213D01*
X1690522Y1549422D01*
X1643780Y1523758D01*
X1639006Y1517407D01*
X1636853Y1510233D01*
X1638180Y1454054D01*
X1644059Y1431979D01*
X1643775Y1431490D01*
X1644277Y1429605D01*
X1644767Y1429321D01*
X1649263Y1412440D01*
Y1409640D01*
X1648118Y1408495D01*
G01X1694842Y1570434D02*
Y1568930D01*
X1695342Y1568430D01*
X1697496D01*
X1699275Y1566651D01*
Y1556605D01*
X1691195Y1548525D01*
X1644524Y1522900D01*
X1640013Y1516898D01*
X1637967Y1510083D01*
X1639287Y1454212D01*
X1650373Y1412586D01*
Y1409640D01*
X1651518Y1408495D01*
G01X1663758Y1384297D02*
X1662613Y1385442D01*
Y1387689D01*
X1656493Y1393809D01*
Y1412680D01*
X1643293Y1454485D01*
X1642165Y1509680D01*
X1643837Y1515370D01*
X1646862Y1519704D01*
X1706140Y1551810D01*
X1707936Y1553606D01*
Y1562320D01*
X1706157Y1564099D01*
X1704003D01*
X1703503Y1564599D01*
Y1566103D01*
G01Y1560985D02*
Y1562489D01*
X1704003Y1562989D01*
X1705697D01*
X1706826Y1561860D01*
Y1554066D01*
X1705469Y1552709D01*
X1702965Y1551353D01*
X1702423Y1551514D01*
X1700707Y1550585D01*
X1700546Y1550042D01*
Y1550043D01*
X1698832Y1549115D01*
Y1549114D01*
X1698290Y1549275D01*
X1696574Y1548345D01*
X1696413Y1547803D01*
X1696412Y1547804D01*
X1646102Y1520555D01*
X1642823Y1515857D01*
X1641051Y1509829D01*
X1642186Y1454303D01*
X1655383Y1412508D01*
Y1393349D01*
X1661503Y1387229D01*
Y1385442D01*
X1660358Y1384297D01*
G01X1651518Y1348187D02*
X1650373Y1347042D01*
Y1345191D01*
X1674813Y1271170D01*
X1675850Y1264726D01*
Y1259600D01*
G01X1648118Y1348187D02*
X1649263Y1347042D01*
Y1345012D01*
X1673731Y1270906D01*
X1674740Y1264637D01*
Y1259600D01*
G01X1651518Y1396583D02*
X1650373Y1395438D01*
Y1393429D01*
X1656493Y1387309D01*
Y1345374D01*
X1678804Y1271167D01*
X1679590Y1265827D01*
Y1259600D01*
G01X1648118Y1396583D02*
X1649263Y1395438D01*
Y1392969D01*
X1655383Y1386849D01*
Y1345210D01*
X1677717Y1270925D01*
X1678480Y1265745D01*
Y1259600D01*
G01X1675998Y1360099D02*
X1674853Y1361244D01*
Y1363491D01*
X1668733Y1369611D01*
Y1412479D01*
X1647375Y1454505D01*
X1646330Y1509510D01*
X1647530Y1514000D01*
X1649476Y1516818D01*
X1710729Y1549528D01*
X1716598Y1555398D01*
Y1566651D01*
X1714819Y1568430D01*
X1712665D01*
X1712165Y1568930D01*
Y1570434D01*
G01Y1565315D02*
Y1566820D01*
X1712665Y1567320D01*
X1714359D01*
X1715488Y1566191D01*
Y1555858D01*
X1714110Y1554480D01*
X1713544D01*
X1712164Y1553100D01*
Y1552534D01*
X1710060Y1550430D01*
X1708293Y1549487D01*
X1707752Y1549651D01*
X1706031Y1548731D01*
X1705866Y1548190D01*
X1648715Y1517671D01*
X1646506Y1514473D01*
X1645217Y1509645D01*
X1646270Y1454229D01*
X1667623Y1412213D01*
Y1369151D01*
X1673743Y1363031D01*
Y1361244D01*
X1672598Y1360099D01*
G01X1651535Y1463741D02*
Y1462237D01*
X1652035Y1461737D01*
X1654189D01*
X1655968Y1459958D01*
Y1451680D01*
X1674853Y1412950D01*
Y1409640D01*
X1675998Y1408495D01*
G01X1651535Y1458622D02*
Y1460127D01*
X1652035Y1460627D01*
X1653729D01*
X1654858Y1459498D01*
Y1451423D01*
X1655712Y1449671D01*
X1655528Y1449136D01*
X1656384Y1447382D01*
X1656918Y1447198D01*
X1657772Y1445446D01*
X1657588Y1444911D01*
X1658444Y1443157D01*
X1658978Y1442973D01*
X1659832Y1441221D01*
X1659648Y1440686D01*
X1660504Y1438932D01*
X1661038Y1438748D01*
X1661892Y1436996D01*
X1661708Y1436461D01*
X1662564Y1434707D01*
X1663098Y1434523D01*
X1663952Y1432771D01*
X1663768Y1432236D01*
X1664624Y1430482D01*
X1665159Y1430298D01*
X1665158Y1430297D01*
X1666012Y1428546D01*
X1666013D01*
X1665829Y1428011D01*
X1666685Y1426257D01*
X1667219Y1426073D01*
X1668073Y1424321D01*
X1667889Y1423786D01*
X1668745Y1422032D01*
X1669279Y1421848D01*
X1669278D01*
X1673743Y1412693D01*
Y1409640D01*
X1672598Y1408495D01*
G01X1721558Y1396583D02*
X1722703Y1395438D01*
Y1392969D01*
X1728823Y1386849D01*
Y1345130D01*
X1754098Y1274756D01*
X1754100Y1274750D01*
X1756230Y1264970D01*
X1754448Y1251125D01*
X1748482Y1242605D01*
X1737633Y1230573D01*
X1717122Y1210062D01*
X1704387Y1204787D01*
X1700624D01*
G01X1724958Y1396583D02*
X1723813Y1395438D01*
Y1393429D01*
X1729933Y1387309D01*
Y1345324D01*
X1755143Y1275133D01*
X1755146Y1275124D01*
X1755170Y1275057D01*
X1755185Y1274986D01*
X1757356Y1265019D01*
X1755514Y1250712D01*
X1749352Y1241912D01*
X1738438Y1229808D01*
X1717751Y1209121D01*
X1704608Y1203677D01*
X1700624D01*
G01X1733798Y1372385D02*
X1734943Y1371240D01*
Y1368771D01*
X1741063Y1362651D01*
X1760375Y1265087D01*
X1758200Y1249773D01*
X1752906Y1241837D01*
X1740190Y1227700D01*
X1719297Y1206807D01*
X1705390Y1201046D01*
X1700812D01*
G01X1737198Y1372385D02*
X1736053Y1371240D01*
Y1369231D01*
X1742087Y1363198D01*
X1761501Y1265118D01*
X1761474Y1264931D01*
X1759264Y1249366D01*
X1753785Y1241154D01*
X1740996Y1226936D01*
X1719926Y1205866D01*
X1705611Y1199936D01*
X1700812D01*
G01X1712718Y1372385D02*
X1711573Y1371240D01*
Y1369231D01*
X1717693Y1363111D01*
Y1345711D01*
X1747755Y1273150D01*
X1747777Y1273048D01*
X1749556Y1264603D01*
X1748107Y1253630D01*
X1743481Y1247052D01*
X1729576Y1235686D01*
X1706685Y1212795D01*
X1702731Y1211157D01*
X1700712D01*
G01X1721558Y1348187D02*
X1722703Y1347042D01*
Y1344953D01*
X1750460Y1273700D01*
X1752350Y1264750D01*
X1750750Y1252570D01*
X1745250Y1244850D01*
X1731370Y1233490D01*
X1708507Y1210627D01*
X1703438Y1208527D01*
X1700424D01*
G01X1700478Y1348187D02*
X1699333Y1347042D01*
Y1344700D01*
X1704462Y1263343D01*
X1704463Y1263338D01*
X1704464Y1263332D01*
X1704466Y1263322D01*
X1704467Y1263316D01*
X1706750Y1251051D01*
X1707200Y1246862D01*
Y1229586D01*
X1703392Y1220393D01*
X1701636Y1218637D01*
X1700612D01*
G01X1700478Y1396583D02*
X1699333Y1395438D01*
Y1393429D01*
X1705453Y1387309D01*
Y1345442D01*
X1743866Y1271997D01*
X1743897Y1271845D01*
X1745455Y1264312D01*
X1744236Y1254933D01*
X1740295Y1249380D01*
X1727601Y1239251D01*
X1704219Y1215869D01*
X1701872Y1214897D01*
X1700712D01*
G01X1709318Y1372385D02*
X1710463Y1371240D01*
Y1368771D01*
X1716583Y1362651D01*
Y1345490D01*
X1746690Y1272820D01*
X1748430Y1264560D01*
X1747042Y1254046D01*
X1742660Y1247816D01*
X1728830Y1236510D01*
X1706056Y1213736D01*
X1702510Y1212267D01*
X1700712D01*
G01X1724958Y1348187D02*
X1723813Y1347042D01*
Y1345162D01*
X1751528Y1274019D01*
X1751546Y1273930D01*
X1753476Y1264794D01*
X1751815Y1252151D01*
X1746068Y1244085D01*
X1732116Y1232666D01*
X1709136Y1209686D01*
X1703659Y1207417D01*
X1700424D01*
G01X1697078Y1396583D02*
X1698223Y1395438D01*
Y1392969D01*
X1704343Y1386849D01*
Y1345169D01*
X1742810Y1271620D01*
X1744330Y1264270D01*
X1743170Y1255350D01*
X1739480Y1250150D01*
X1726860Y1240080D01*
X1703590Y1216810D01*
X1701651Y1216007D01*
X1700712D01*
G01X1697078Y1348187D02*
X1698223Y1347042D01*
Y1344665D01*
X1703358Y1263206D01*
X1703370Y1263140D01*
X1703371Y1263135D01*
X1703372Y1263129D01*
X1703373Y1263124D01*
X1703374Y1263118D01*
Y1263115D01*
X1703375Y1263113D01*
X1705650Y1250890D01*
X1706090Y1246802D01*
Y1229807D01*
X1702451Y1221022D01*
X1701176Y1219747D01*
X1700612D01*
G01X1660358Y1372385D02*
X1661503Y1371240D01*
Y1368771D01*
X1667623Y1362651D01*
Y1345280D01*
X1682220Y1271487D01*
Y1259600D01*
G01X1663758Y1372385D02*
X1662613Y1371240D01*
Y1369231D01*
X1668733Y1363111D01*
Y1345389D01*
X1683330Y1271596D01*
Y1259600D01*
G01X1672598Y1348187D02*
X1673743Y1347042D01*
Y1344920D01*
X1685960Y1272992D01*
Y1259600D01*
G01X1675998Y1348187D02*
X1674853Y1347042D01*
Y1345014D01*
X1687070Y1273086D01*
Y1259600D01*
G01X1675998Y1396583D02*
X1674853Y1395438D01*
Y1393429D01*
X1680973Y1387309D01*
Y1344216D01*
X1694551Y1264321D01*
Y1256012D01*
G01X1672598Y1396583D02*
X1673743Y1395438D01*
Y1392969D01*
X1679863Y1386849D01*
Y1344122D01*
X1693441Y1264227D01*
Y1256012D01*
G01X1660196Y1462953D02*
Y1464457D01*
X1660696Y1464957D01*
X1662390D01*
X1663519Y1463828D01*
Y1451900D01*
X1664375Y1449837D01*
X1664158Y1449315D01*
X1664907Y1447512D01*
X1665429Y1447296D01*
X1666176Y1445495D01*
X1665960Y1444973D01*
X1666708Y1443171D01*
X1667231Y1442954D01*
X1667978Y1441153D01*
X1667762Y1440631D01*
X1668510Y1438828D01*
X1669033Y1438612D01*
X1669032D01*
X1669779Y1436811D01*
X1669780D01*
X1669564Y1436289D01*
X1670312Y1434486D01*
X1670835Y1434270D01*
X1670833D01*
X1671580Y1432469D01*
X1671582D01*
X1671366Y1431947D01*
X1672114Y1430144D01*
X1672636Y1429928D01*
X1672634D01*
X1673382Y1428127D01*
X1673383D01*
X1673167Y1427605D01*
X1673915Y1425802D01*
X1674438Y1425586D01*
X1674436D01*
X1675184Y1423785D01*
X1675185D01*
X1674968Y1423263D01*
X1675717Y1421460D01*
X1676239Y1421244D01*
X1676238D01*
X1679863Y1412508D01*
Y1393349D01*
X1685983Y1387229D01*
Y1385442D01*
X1684838Y1384297D01*
G01X1688238D02*
X1687093Y1385442D01*
Y1387689D01*
X1680973Y1393809D01*
Y1412730D01*
X1664629Y1452122D01*
Y1464288D01*
X1662850Y1466067D01*
X1660696D01*
X1660196Y1466567D01*
Y1468071D01*
G01X1668858Y1458622D02*
Y1460127D01*
X1669358Y1460627D01*
X1671052D01*
X1672181Y1459498D01*
Y1451970D01*
X1673061Y1450231D01*
X1672863Y1449626D01*
X1673745Y1447885D01*
X1674350Y1447687D01*
X1674349D01*
X1675229Y1445948D01*
X1675230D01*
X1675032Y1445343D01*
X1675914Y1443602D01*
X1676519Y1443404D01*
X1676518Y1443403D01*
X1677398Y1441665D01*
X1677399D01*
X1677201Y1441060D01*
X1678083Y1439319D01*
X1678687Y1439121D01*
X1678686Y1439120D01*
X1679566Y1437382D01*
X1679567D01*
X1679369Y1436777D01*
X1680251Y1435036D01*
X1680855Y1434838D01*
X1680854Y1434837D01*
X1681734Y1433099D01*
X1681735D01*
X1681537Y1432494D01*
X1682419Y1430753D01*
X1683024Y1430555D01*
X1683023Y1430554D01*
X1683903Y1428815D01*
X1683904Y1428816D01*
X1683706Y1428211D01*
X1684588Y1426470D01*
X1685192Y1426272D01*
X1685191D01*
X1686071Y1424533D01*
X1686072D01*
X1685874Y1423928D01*
X1686756Y1422187D01*
X1687360Y1421989D01*
X1688239Y1420250D01*
X1688073Y1419742D01*
X1689020Y1417872D01*
X1689528Y1417706D01*
X1692103Y1412620D01*
Y1369151D01*
X1698223Y1363031D01*
Y1361244D01*
X1697078Y1360099D01*
G01X1700478D02*
X1699333Y1361244D01*
Y1363491D01*
X1693213Y1369611D01*
Y1412885D01*
X1673291Y1452235D01*
Y1459958D01*
X1671512Y1461737D01*
X1669358D01*
X1668858Y1462237D01*
Y1463741D01*
G01X1684838Y1372385D02*
X1685983Y1371240D01*
Y1368771D01*
X1692103Y1362651D01*
Y1345259D01*
X1699591Y1262760D01*
X1701400Y1253011D01*
Y1238266D01*
X1699232Y1233032D01*
X1697799Y1231599D01*
G01X1688238Y1372385D02*
X1687093Y1371240D01*
Y1369231D01*
X1693213Y1363111D01*
Y1345311D01*
X1693214Y1345310D01*
X1700692Y1262912D01*
X1702510Y1253114D01*
Y1238045D01*
X1700258Y1232608D01*
Y1232488D01*
X1698584Y1230814D01*
G01X1677519Y1462953D02*
Y1464457D01*
X1678019Y1464957D01*
X1679713D01*
X1680842Y1463828D01*
Y1451523D01*
X1681636Y1449743D01*
X1681408Y1449148D01*
X1682203Y1447366D01*
X1682798Y1447139D01*
X1682797D01*
X1683591Y1445359D01*
X1683592D01*
X1683364Y1444764D01*
X1684159Y1442982D01*
X1684754Y1442755D01*
X1684753Y1442754D01*
X1685547Y1440974D01*
X1685548Y1440975D01*
X1685320Y1440380D01*
X1686114Y1438598D01*
X1686710Y1438371D01*
X1686708Y1438369D01*
X1687502Y1436591D01*
X1687504D01*
X1687276Y1435996D01*
X1688070Y1434214D01*
X1688666Y1433987D01*
X1688664Y1433985D01*
X1692356Y1425709D01*
X1692357D01*
X1692129Y1425115D01*
X1692923Y1423333D01*
X1693518Y1423105D01*
X1693517D01*
X1694311Y1421325D01*
X1694312D01*
X1694084Y1420731D01*
X1694878Y1418949D01*
X1695473Y1418721D01*
X1696267Y1416941D01*
X1696040Y1416347D01*
X1696834Y1414565D01*
X1697429Y1414337D01*
X1698223Y1412557D01*
Y1409640D01*
X1697078Y1408495D01*
G01X1677519Y1468071D02*
Y1466567D01*
X1678019Y1466067D01*
X1680173D01*
X1681952Y1464288D01*
Y1451760D01*
X1699333Y1412794D01*
Y1409640D01*
X1700478Y1408495D01*
G01X1686181Y1458622D02*
Y1460127D01*
X1686681Y1460627D01*
X1688375D01*
X1689504Y1459498D01*
Y1452059D01*
X1690185Y1450233D01*
X1689921Y1449654D01*
X1690603Y1447826D01*
X1691183Y1447562D01*
X1691182D01*
X1691863Y1445739D01*
X1691864Y1445736D01*
X1691600Y1445157D01*
X1692282Y1443329D01*
X1692862Y1443065D01*
X1692861D01*
X1693542Y1441239D01*
X1693543D01*
X1693279Y1440660D01*
X1693961Y1438832D01*
X1694541Y1438568D01*
X1694539D01*
X1696053Y1434513D01*
X1696054D01*
X1695819Y1433998D01*
X1696500Y1432170D01*
X1697016Y1431935D01*
X1697697Y1430109D01*
X1697462Y1429594D01*
X1698144Y1427766D01*
X1698660Y1427531D01*
X1699341Y1425705D01*
X1699106Y1425190D01*
X1699788Y1423362D01*
X1700304Y1423127D01*
X1700985Y1421301D01*
X1700721Y1420723D01*
X1701403Y1418895D01*
X1701983Y1418630D01*
X1702664Y1416804D01*
X1702400Y1416226D01*
X1703082Y1414398D01*
X1703662Y1414133D01*
X1704343Y1412307D01*
Y1393349D01*
X1710463Y1387229D01*
Y1385442D01*
X1709318Y1384297D01*
G01X1686181Y1463741D02*
Y1462237D01*
X1686681Y1461737D01*
X1688835D01*
X1690614Y1459958D01*
Y1452260D01*
X1692904Y1446126D01*
X1692905Y1446123D01*
X1693901Y1443455D01*
X1693902Y1443452D01*
X1705453Y1412508D01*
Y1393809D01*
X1711573Y1387689D01*
Y1385442D01*
X1712718Y1384297D01*
G01X1724958Y1360099D02*
X1723813Y1361244D01*
Y1363491D01*
X1717693Y1369611D01*
Y1412868D01*
X1699275Y1452078D01*
Y1464288D01*
X1697496Y1466067D01*
X1695342D01*
X1694842Y1466567D01*
Y1468071D01*
G01Y1462953D02*
Y1464457D01*
X1695342Y1464957D01*
X1697036D01*
X1698165Y1463828D01*
Y1451830D01*
X1698994Y1450066D01*
X1698778Y1449467D01*
X1699608Y1447701D01*
X1700206Y1447485D01*
X1701035Y1445721D01*
X1700819Y1445122D01*
X1701649Y1443356D01*
X1702247Y1443140D01*
X1703076Y1441376D01*
X1702860Y1440777D01*
X1703690Y1439011D01*
X1704288Y1438795D01*
X1708419Y1430000D01*
X1708203Y1429401D01*
X1709033Y1427635D01*
X1709631Y1427419D01*
X1710460Y1425655D01*
X1710244Y1425056D01*
X1711074Y1423290D01*
X1711672Y1423074D01*
X1712501Y1421310D01*
X1712285Y1420711D01*
X1713115Y1418945D01*
X1713713Y1418729D01*
X1714542Y1416965D01*
X1714326Y1416366D01*
X1715156Y1414600D01*
X1715754Y1414384D01*
X1716583Y1412620D01*
Y1369151D01*
X1722703Y1363031D01*
Y1361244D01*
X1721558Y1360099D01*
G01X1703503Y1458622D02*
Y1460127D01*
X1704003Y1460627D01*
X1705697D01*
X1706826Y1459498D01*
Y1451754D01*
X1707554Y1449946D01*
X1707305Y1449360D01*
X1708033Y1447550D01*
X1708620Y1447301D01*
X1708619D01*
X1709347Y1445493D01*
X1709348D01*
X1709099Y1444907D01*
X1709827Y1443097D01*
X1710414Y1442848D01*
X1710413D01*
X1711141Y1441040D01*
X1711142D01*
X1710893Y1440454D01*
X1711621Y1438644D01*
X1712208Y1438395D01*
X1712206D01*
X1712934Y1436586D01*
X1712936Y1436587D01*
X1712687Y1436001D01*
X1713415Y1434191D01*
X1714002Y1433942D01*
X1714000Y1433941D01*
X1714728Y1432134D01*
X1714730D01*
X1714481Y1431548D01*
X1715209Y1429738D01*
X1715796Y1429489D01*
X1715794Y1429486D01*
X1716522Y1427680D01*
X1716524Y1427681D01*
X1716274Y1427095D01*
X1717003Y1425285D01*
X1717589Y1425036D01*
X1717587D01*
X1718315Y1423227D01*
X1718317Y1423228D01*
X1718067Y1422642D01*
X1718796Y1420832D01*
X1719382Y1420583D01*
X1719381D01*
X1720109Y1418775D01*
X1720110D01*
X1719944Y1418384D01*
X1720673Y1416574D01*
X1721063Y1416408D01*
X1721062D01*
X1722703Y1412336D01*
Y1409640D01*
X1721558Y1408495D01*
G01X1703503Y1463741D02*
Y1462237D01*
X1704003Y1461737D01*
X1706157D01*
X1707936Y1459958D01*
Y1451970D01*
X1723733Y1412750D01*
X1723773Y1412543D01*
X1723806D01*
X1723813Y1412550D01*
Y1409640D01*
X1724958Y1408495D01*
G01X1737198Y1384297D02*
X1736053Y1385442D01*
Y1387689D01*
X1729933Y1393809D01*
Y1412803D01*
X1716598Y1452373D01*
Y1464288D01*
X1714819Y1466067D01*
X1712665D01*
X1712165Y1466567D01*
Y1468071D01*
G01X1733798Y1384297D02*
X1734943Y1385442D01*
Y1387229D01*
X1728823Y1393349D01*
Y1412620D01*
X1727999Y1415065D01*
X1727428Y1415348D01*
X1726805Y1417197D01*
X1727088Y1417767D01*
X1726466Y1419614D01*
X1725895Y1419897D01*
X1725272Y1421746D01*
X1725555Y1422316D01*
X1724933Y1424163D01*
X1724362Y1424446D01*
X1723739Y1426295D01*
X1724022Y1426865D01*
X1723400Y1428712D01*
X1722829Y1428995D01*
X1722206Y1430844D01*
X1722489Y1431414D01*
X1720087Y1438543D01*
X1719516Y1438826D01*
X1718893Y1440674D01*
X1719176Y1441245D01*
X1718554Y1443092D01*
X1717983Y1443375D01*
X1717361Y1445223D01*
X1717643Y1445794D01*
X1717021Y1447641D01*
X1716450Y1447924D01*
X1715828Y1449772D01*
X1716110Y1450343D01*
X1715488Y1452190D01*
Y1463828D01*
X1714359Y1464957D01*
X1712665D01*
X1712165Y1464457D01*
Y1462953D01*
G54D27*
X1795453Y812874D03*
Y834922D03*
G54D18*
X173829Y455492D03*
Y583957D03*
X202844Y455492D03*
Y583957D03*
X266841Y421555D03*
Y550020D03*
X295856Y421555D03*
Y550020D03*
X630915Y455492D03*
Y583957D03*
X659930Y455492D03*
Y583957D03*
X723927Y421555D03*
Y550020D03*
X752942Y421555D03*
Y550020D03*
X1088002Y455492D03*
Y583957D03*
X1117017Y455492D03*
Y583957D03*
X1181014Y421555D03*
Y550020D03*
X1210029Y421555D03*
Y550020D03*
X1545089Y455492D03*
Y583957D03*
X1574104Y455492D03*
Y583957D03*
X1638101Y421555D03*
Y550020D03*
X1667116Y421555D03*
Y550020D03*
G54D28*
X1803917Y823898D03*
G54D19*
X190325Y368760D03*
X279360Y636752D03*
X647411Y368760D03*
X736446Y636752D03*
X1104498Y368760D03*
X1193533Y636752D03*
X1561585Y368760D03*
X1650620Y636752D03*
G54D29*
G01X420782Y1103114D02*
X418703Y1101035D01*
X416265D01*
X415070Y1099840D01*
Y1097888D01*
X422728Y1090230D01*
Y1057470D01*
X430262Y1049936D01*
X439231D01*
X449287Y1039880D01*
X452091D01*
G01X452910Y1105552D02*
Y1102872D01*
X449998Y1099960D01*
Y1097815D01*
X448023Y1095840D01*
X445367D01*
X440666Y1100541D01*
X431808D01*
X427107Y1095840D01*
X423966D01*
X422755Y1097051D01*
Y1101141D01*
X420782Y1103114D01*
G01D02*
Y1105552D01*
G01X464385Y1038534D02*
Y1096555D01*
X468865Y1101035D01*
X484290D01*
X486369Y1103114D01*
G01Y1105552D02*
Y1103114D01*
G01D02*
X488342Y1101141D01*
Y1097051D01*
X489553Y1095840D01*
X492694D01*
X497395Y1100541D01*
X506253D01*
X510954Y1095840D01*
X513610D01*
X515585Y1097815D01*
Y1099960D01*
X518497Y1102872D01*
Y1105552D01*
G01X978987Y1489832D02*
X979820Y1488999D01*
Y1487105D01*
X978602Y1485887D01*
X926684D01*
X920339Y1479542D01*
Y1458993D01*
X924027Y1455305D01*
Y1422410D01*
X935537Y1410900D01*
Y1406605D01*
X931159Y1402227D01*
G01X982241Y1489637D02*
X981463Y1488859D01*
Y1486626D01*
X979224Y1484387D01*
X927306D01*
X921839Y1478920D01*
Y1459615D01*
X925527Y1455927D01*
Y1423032D01*
X937037Y1411522D01*
Y1400505D01*
X931159Y1394627D01*
G01X939559Y1398427D02*
X940709Y1399577D01*
X953796D01*
X957104Y1396269D01*
Y1387881D01*
X955301Y1386078D01*
X953888Y1386134D01*
X952716Y1387402D01*
G01X952561Y1383465D02*
X953826Y1384636D01*
X953829Y1384635D01*
X955241Y1384579D01*
X955898Y1384553D01*
X958604Y1387259D01*
Y1396891D01*
X954418Y1401077D01*
X940709D01*
X939559Y1402227D01*
G01X1367084Y1105552D02*
Y1102872D01*
X1364172Y1099960D01*
Y1097815D01*
X1362197Y1095840D01*
X1359541D01*
X1354840Y1100541D01*
X1345982D01*
X1341281Y1095840D01*
X1338140D01*
X1336929Y1097051D01*
Y1101141D01*
X1334956Y1103114D01*
G01D02*
X1332877Y1101035D01*
X1330439D01*
X1329244Y1099840D01*
Y1097888D01*
X1336902Y1090230D01*
Y1057470D01*
X1344436Y1049936D01*
X1353405D01*
X1363461Y1039880D01*
X1366265D01*
G01X1334956Y1103114D02*
Y1105552D01*
G01X1400543Y1103114D02*
X1398464Y1101035D01*
X1383039D01*
X1378559Y1096555D01*
Y1038534D01*
G01X1400543Y1105552D02*
Y1103114D01*
G01D02*
X1402516Y1101141D01*
Y1097051D01*
X1403727Y1095840D01*
X1406868D01*
X1411569Y1100541D01*
X1420427D01*
X1425128Y1095840D01*
X1427784D01*
X1429759Y1097815D01*
Y1099960D01*
X1432671Y1102872D01*
Y1105552D01*
M02*
